G04 ================== begin FILE IDENTIFICATION RECORD ==================*
G04 Layout Name:  9049_F0T_FAN_BOARD_MP5048_D_v02_20221209_0830.brd*
G04 Film Name:    fab.art*
G04 File Format:  Gerber RS274X*
G04 File Origin:  Cadence Allegro 17.2-S081*
G04 Origin Date:  Mon Dec 12 15:05:05 2022*
G04 *
G04 Layer:  PIN/SPECIAL_DRILL*
G04 Layer:  DRAWING FORMAT/TITLE_BLOCK_A*
G04 Layer:  MANUFACTURING/NCLEGEND-1-6*
G04 Layer:  BOARD GEOMETRY/DESIGN_OUTLINE*
G04 Layer:  BOARD GEOMETRY/CUTOUT*
G04 Layer:  MANUFACTURING/NCDRILL_LEGEND*
G04 Layer:  MANUFACTURING/NCDRILL_FIGURE*
G04 Layer:  MANUFACTURING/PHOTOPLOT_OUTLINE*
G04 Layer:  MANUFACTURING/DIMENSION*
G04 Layer:  MANUFACTURING/DETAILS*
G04 Layer:  DRAWING FORMAT/TITLE_BLOCK*
G04 Layer:  DRAWING FORMAT/TITLE_DATA_FAB*
G04 *
G04 Offset:    (0.00 0.00)*
G04 Mirror:    No*
G04 Mode:      Positive*
G04 Rotation:  0*
G04 FullContactRelief:  No*
G04 UndefLineWidth:     6.00*
G04 ================== end FILE IDENTIFICATION RECORD ====================*
%FSLAX25Y25*MOIN*%
%IR0*IPPOS*OFA0.00000B0.00000*MIA0B0*SFA1.00000B1.00000*%
%AMMACRO17*
4,1,46,.05906,.17844,
.059724,.155545,
.06128,.13665,
.09787,-.20608,
.098198,-.223234,
.095542,-.240184,
.089983,-.256415,
.081691,-.271435,
.070916,-.284786,
.057986,-.296063,
.043294,-.304924,
.027287,-.311099,
.010451,-.314401,
-.006703,-.314729,
-.023653,-.312073,
-.039884,-.306514,
-.054904,-.298221,
-.068255,-.287446,
-.079532,-.274517,
-.088393,-.259825,
-.094568,-.243818,
-.09787,-.226982,
-.098198,-.209828,
-.09787,-.20608,
-.06128,.13665,
-.059515,.159487,
-.05906,.17844,
-.05906,.25591,
-.058163,.266166,
-.055498,.27611,
-.051147,.28544,
-.045243,.293873,
-.037963,.301153,
-.02953,.307057,
-.0202,.311408,
-.010256,.314073,
0.0,.31497,
.010256,.314073,
.0202,.311408,
.02953,.307057,
.037963,.301153,
.045243,.293873,
.051147,.28544,
.055498,.27611,
.058163,.266166,
.05906,.25591,
.05906,.17844,
0.0*
%
%ADD17MACRO17*%
%AMMACRO14*
1,1,.006,.035,0.0*
20,1,.006,.035,0.0,.034468,-.006078,0.0*
1,1,.006,.034468,-.006078*
20,1,.006,.034468,-.006078,.032889,-.011971,0.0*
1,1,.006,.032889,-.011971*
20,1,.006,.032889,-.011971,.030311,-.0175,0.0*
1,1,.006,.030311,-.0175*
20,1,.006,.030311,-.0175,.026812,-.022498,0.0*
1,1,.006,.026812,-.022498*
20,1,.006,.026812,-.022498,.022498,-.026812,0.0*
1,1,.006,.022498,-.026812*
20,1,.006,.022498,-.026812,.0175,-.030311,0.0*
1,1,.006,.0175,-.030311*
20,1,.006,.0175,-.030311,.011971,-.032889,0.0*
1,1,.006,.011971,-.032889*
20,1,.006,.011971,-.032889,.006078,-.034468,0.0*
1,1,.006,.006078,-.034468*
20,1,.006,.006078,-.034468,0.0,-.035,0.0*
1,1,.006,0.0,-.035*
20,1,.006,0.0,-.035,-.006078,-.034468,0.0*
1,1,.006,-.006078,-.034468*
20,1,.006,-.006078,-.034468,-.011971,-.032889,0.0*
1,1,.006,-.011971,-.032889*
20,1,.006,-.011971,-.032889,-.0175,-.030311,0.0*
1,1,.006,-.0175,-.030311*
20,1,.006,-.0175,-.030311,-.022498,-.026812,0.0*
1,1,.006,-.022498,-.026812*
20,1,.006,-.022498,-.026812,-.026812,-.022498,0.0*
1,1,.006,-.026812,-.022498*
20,1,.006,-.026812,-.022498,-.030311,-.0175,0.0*
1,1,.006,-.030311,-.0175*
20,1,.006,-.030311,-.0175,-.032889,-.011971,0.0*
1,1,.006,-.032889,-.011971*
20,1,.006,-.032889,-.011971,-.034468,-.006078,0.0*
1,1,.006,-.034468,-.006078*
20,1,.006,-.034468,-.006078,-.035,0.0,0.0*
1,1,.006,-.035,0.0*
20,1,.006,-.035,0.0,-.034468,.006078,0.0*
1,1,.006,-.034468,.006078*
20,1,.006,-.034468,.006078,-.032889,.011971,0.0*
1,1,.006,-.032889,.011971*
20,1,.006,-.032889,.011971,-.030311,.0175,0.0*
1,1,.006,-.030311,.0175*
20,1,.006,-.030311,.0175,-.026812,.022498,0.0*
1,1,.006,-.026812,.022498*
20,1,.006,-.026812,.022498,-.022498,.026812,0.0*
1,1,.006,-.022498,.026812*
20,1,.006,-.022498,.026812,-.0175,.030311,0.0*
1,1,.006,-.0175,.030311*
20,1,.006,-.0175,.030311,-.011971,.032889,0.0*
1,1,.006,-.011971,.032889*
20,1,.006,-.011971,.032889,-.006078,.034468,0.0*
1,1,.006,-.006078,.034468*
20,1,.006,-.006078,.034468,0.0,.035,0.0*
1,1,.006,0.0,.035*
20,1,.006,0.0,.035,.006078,.034468,0.0*
1,1,.006,.006078,.034468*
20,1,.006,.006078,.034468,.011971,.032889,0.0*
1,1,.006,.011971,.032889*
20,1,.006,.011971,.032889,.0175,.030311,0.0*
1,1,.006,.0175,.030311*
20,1,.006,.0175,.030311,.022498,.026812,0.0*
1,1,.006,.022498,.026812*
20,1,.006,.022498,.026812,.026812,.022498,0.0*
1,1,.006,.026812,.022498*
20,1,.006,.026812,.022498,.030311,.0175,0.0*
1,1,.006,.030311,.0175*
20,1,.006,.030311,.0175,.032889,.011971,0.0*
1,1,.006,.032889,.011971*
20,1,.006,.032889,.011971,.034468,.006078,0.0*
1,1,.006,.034468,.006078*
20,1,.006,.034468,.006078,.035,0.0,0.0*
1,1,.006,.035,0.0*
1,1,.006,-.02082,.01041*
20,1,.006,-.02082,.01041,-.02082,-.01041,0.0*
1,1,.006,-.02082,-.01041*
1,1,.006,-.0288,.01041*
20,1,.006,-.0288,.01041,-.01284,.01041,0.0*
1,1,.006,-.01284,.01041*
1,1,.006,-.00693,-.01041*
20,1,.006,-.00693,-.01041,-.00693,.01041,0.0*
1,1,.006,-.00693,.01041*
20,1,.006,-.00693,.01041,.0014,.01041,0.0*
1,1,.006,.0014,.01041*
20,1,.006,.0014,.01041,.00417,.00937,0.0*
1,1,.006,.00417,.00937*
20,1,.006,.00417,.00937,.00626,.00694,0.0*
1,1,.006,.00626,.00694*
20,1,.006,.00626,.00694,.00695,.00416,0.0*
1,1,.006,.00695,.00416*
20,1,.006,.00695,.00416,.00626,.00139,0.0*
1,1,.006,.00626,.00139*
20,1,.006,.00626,.00139,.00452,-.00069,0.0*
1,1,.006,.00452,-.00069*
20,1,.006,.00452,-.00069,.0014,-.00174,0.0*
1,1,.006,.0014,-.00174*
20,1,.006,.0014,-.00174,-.00693,-.00174,0.0*
1,1,.006,-.00693,-.00174*
1,1,.006,.01216,.01041*
20,1,.006,.01216,.01041,.02084,-.01041,0.0*
1,1,.006,.02084,-.01041*
20,1,.006,.02084,-.01041,.02952,.01041,0.0*
1,1,.006,.02952,.01041*
%
%ADD14MACRO14*%
%AMMACRO20*
1,1,.006,.126,0.0*
20,1,.006,.126,0.0,.124086,-.02188,0.0*
1,1,.006,.124086,-.02188*
20,1,.006,.124086,-.02188,.118401,-.043095,0.0*
1,1,.006,.118401,-.043095*
20,1,.006,.118401,-.043095,.109119,-.063,0.0*
1,1,.006,.109119,-.063*
20,1,.006,.109119,-.063,.096522,-.080991,0.0*
1,1,.006,.096522,-.080991*
20,1,.006,.096522,-.080991,.080991,-.096522,0.0*
1,1,.006,.080991,-.096522*
20,1,.006,.080991,-.096522,.063,-.109119,0.0*
1,1,.006,.063,-.109119*
20,1,.006,.063,-.109119,.043095,-.118401,0.0*
1,1,.006,.043095,-.118401*
20,1,.006,.043095,-.118401,.02188,-.124086,0.0*
1,1,.006,.02188,-.124086*
20,1,.006,.02188,-.124086,0.0,-.126,0.0*
1,1,.006,0.0,-.126*
20,1,.006,0.0,-.126,-.02188,-.124086,0.0*
1,1,.006,-.02188,-.124086*
20,1,.006,-.02188,-.124086,-.043095,-.118401,0.0*
1,1,.006,-.043095,-.118401*
20,1,.006,-.043095,-.118401,-.063,-.109119,0.0*
1,1,.006,-.063,-.109119*
20,1,.006,-.063,-.109119,-.080991,-.096522,0.0*
1,1,.006,-.080991,-.096522*
20,1,.006,-.080991,-.096522,-.096522,-.080991,0.0*
1,1,.006,-.096522,-.080991*
20,1,.006,-.096522,-.080991,-.109119,-.063,0.0*
1,1,.006,-.109119,-.063*
20,1,.006,-.109119,-.063,-.118401,-.043095,0.0*
1,1,.006,-.118401,-.043095*
20,1,.006,-.118401,-.043095,-.124086,-.02188,0.0*
1,1,.006,-.124086,-.02188*
20,1,.006,-.124086,-.02188,-.126,0.0,0.0*
1,1,.006,-.126,0.0*
20,1,.006,-.126,0.0,-.124086,.02188,0.0*
1,1,.006,-.124086,.02188*
20,1,.006,-.124086,.02188,-.118401,.043095,0.0*
1,1,.006,-.118401,.043095*
20,1,.006,-.118401,.043095,-.109119,.063,0.0*
1,1,.006,-.109119,.063*
20,1,.006,-.109119,.063,-.096522,.080991,0.0*
1,1,.006,-.096522,.080991*
20,1,.006,-.096522,.080991,-.080991,.096522,0.0*
1,1,.006,-.080991,.096522*
20,1,.006,-.080991,.096522,-.063,.109119,0.0*
1,1,.006,-.063,.109119*
20,1,.006,-.063,.109119,-.043095,.118401,0.0*
1,1,.006,-.043095,.118401*
20,1,.006,-.043095,.118401,-.02188,.124086,0.0*
1,1,.006,-.02188,.124086*
20,1,.006,-.02188,.124086,0.0,.126,0.0*
1,1,.006,0.0,.126*
20,1,.006,0.0,.126,.02188,.124086,0.0*
1,1,.006,.02188,.124086*
20,1,.006,.02188,.124086,.043095,.118401,0.0*
1,1,.006,.043095,.118401*
20,1,.006,.043095,.118401,.063,.109119,0.0*
1,1,.006,.063,.109119*
20,1,.006,.063,.109119,.080991,.096522,0.0*
1,1,.006,.080991,.096522*
20,1,.006,.080991,.096522,.096522,.080991,0.0*
1,1,.006,.096522,.080991*
20,1,.006,.096522,.080991,.109119,.063,0.0*
1,1,.006,.109119,.063*
20,1,.006,.109119,.063,.118401,.043095,0.0*
1,1,.006,.118401,.043095*
20,1,.006,.118401,.043095,.124086,.02188,0.0*
1,1,.006,.124086,.02188*
20,1,.006,.124086,.02188,.126,0.0,0.0*
1,1,.006,.126,0.0*
1,1,.006,-.09871,.025*
20,1,.006,-.09871,.025,-.09121,.03249,0.0*
1,1,.006,-.09121,.03249*
20,1,.006,-.09121,.03249,-.08246,.03624,0.0*
1,1,.006,-.08246,.03624*
20,1,.006,-.08246,.03624,-.07247,.03749,0.0*
1,1,.006,-.07247,.03749*
20,1,.006,-.07247,.03749,-.05997,.03499,0.0*
1,1,.006,-.05997,.03499*
20,1,.006,-.05997,.03499,-.05122,.02874,0.0*
1,1,.006,-.05122,.02874*
20,1,.006,-.05122,.02874,-.04873,.02125,0.0*
1,1,.006,-.04873,.02125*
20,1,.006,-.04873,.02125,-.04997,.01375,0.0*
1,1,.006,-.04997,.01375*
20,1,.006,-.04997,.01375,-.05497,.0075,0.0*
1,1,.006,-.05497,.0075*
20,1,.006,-.05497,.0075,-.07996,-.00499,0.0*
1,1,.006,-.07996,-.00499*
20,1,.006,-.07996,-.00499,-.09121,-.01374,0.0*
1,1,.006,-.09121,-.01374*
20,1,.006,-.09121,-.01374,-.09871,-.02624,0.0*
1,1,.006,-.09871,-.02624*
20,1,.006,-.09871,-.02624,-.1012,-.03748,0.0*
1,1,.006,-.1012,-.03748*
20,1,.006,-.1012,-.03748,-.04873,-.03748,0.0*
1,1,.006,-.04873,-.03748*
1,1,.006,-.02747,-.02624*
20,1,.006,-.02747,-.02624,-.01998,-.03248,0.0*
1,1,.006,-.01998,-.03248*
20,1,.006,-.01998,-.03248,-.01123,-.03623,0.0*
1,1,.006,-.01123,-.03623*
20,1,.006,-.01123,-.03623,.00001,-.03748,0.0*
1,1,.006,.00001,-.03748*
20,1,.006,.00001,-.03748,.01126,-.03498,0.0*
1,1,.006,.01126,-.03498*
20,1,.006,.01126,-.03498,.02001,-.02998,0.0*
1,1,.006,.02001,-.02998*
20,1,.006,.02001,-.02998,.02625,-.02124,0.0*
1,1,.006,.02625,-.02124*
20,1,.006,.02625,-.02124,.0275,-.01124,0.0*
1,1,.006,.0275,-.01124*
20,1,.006,.0275,-.01124,.02501,-.00125,0.0*
1,1,.006,.02501,-.00125*
20,1,.006,.02501,-.00125,.01876,.005,0.0*
1,1,.006,.01876,.005*
20,1,.006,.01876,.005,.01001,.01,0.0*
1,1,.006,.01001,.01*
20,1,.006,.01001,.01,.00127,.01125,0.0*
1,1,.006,.00127,.01125*
20,1,.006,.00127,.01125,-.00748,.01,0.0*
1,1,.006,-.00748,.01*
20,1,.006,-.00748,.01,-.01873,.005,0.0*
1,1,.006,-.01873,.005*
20,1,.006,-.01873,.005,-.01498,.03749,0.0*
1,1,.006,-.01498,.03749*
20,1,.006,-.01498,.03749,.01876,.03749,0.0*
1,1,.006,.01876,.03749*
1,1,.006,.05125,.025*
20,1,.006,.05125,.025,.05875,.03249,0.0*
1,1,.006,.05875,.03249*
20,1,.006,.05875,.03249,.0675,.03624,0.0*
1,1,.006,.0675,.03624*
20,1,.006,.0675,.03624,.07749,.03749,0.0*
1,1,.006,.07749,.03749*
20,1,.006,.07749,.03749,.08999,.03499,0.0*
1,1,.006,.08999,.03499*
20,1,.006,.08999,.03499,.09874,.02874,0.0*
1,1,.006,.09874,.02874*
20,1,.006,.09874,.02874,.10123,.02125,0.0*
1,1,.006,.10123,.02125*
20,1,.006,.10123,.02125,.09999,.01375,0.0*
1,1,.006,.09999,.01375*
20,1,.006,.09999,.01375,.09499,.0075,0.0*
1,1,.006,.09499,.0075*
20,1,.006,.09499,.0075,.07,-.00499,0.0*
1,1,.006,.07,-.00499*
20,1,.006,.07,-.00499,.05875,-.01374,0.0*
1,1,.006,.05875,-.01374*
20,1,.006,.05875,-.01374,.05125,-.02624,0.0*
1,1,.006,.05125,-.02624*
20,1,.006,.05125,-.02624,.04876,-.03748,0.0*
1,1,.006,.04876,-.03748*
20,1,.006,.04876,-.03748,.10123,-.03748,0.0*
1,1,.006,.10123,-.03748*
%
%ADD20MACRO20*%
%AMMACRO16*
1,1,.006,.035,.035*
20,1,.006,.035,.035,.035,-.035,0.0*
1,1,.006,.035,-.035*
20,1,.006,.035,-.035,-.035,-.035,0.0*
1,1,.006,-.035,-.035*
20,1,.006,-.035,-.035,-.035,.035,0.0*
1,1,.006,-.035,.035*
20,1,.006,-.035,.035,.035,.035,0.0*
1,1,.006,.035,.035*
1,1,.006,-.0245,.01225*
20,1,.006,-.0245,.01225,-.02777,.01143,0.0*
1,1,.006,-.02777,.01143*
20,1,.006,-.02777,.01143,-.03022,.00939,0.0*
1,1,.006,-.03022,.00939*
20,1,.006,-.03022,.00939,-.03185,.00694,0.0*
1,1,.006,-.03185,.00694*
20,1,.006,-.03185,.00694,-.03308,.00367,0.0*
1,1,.006,-.03308,.00367*
20,1,.006,-.03308,.00367,-.03348,0.0,0.0*
1,1,.006,-.03348,0.0*
20,1,.006,-.03348,0.0,-.03308,-.00368,0.0*
1,1,.006,-.03308,-.00368*
20,1,.006,-.03308,-.00368,-.03185,-.00694,0.0*
1,1,.006,-.03185,-.00694*
20,1,.006,-.03185,-.00694,-.03022,-.00939,0.0*
1,1,.006,-.03022,-.00939*
20,1,.006,-.03022,-.00939,-.02777,-.01143,0.0*
1,1,.006,-.02777,-.01143*
20,1,.006,-.02777,-.01143,-.0245,-.01225,0.0*
1,1,.006,-.0245,-.01225*
20,1,.006,-.0245,-.01225,-.02123,-.01143,0.0*
1,1,.006,-.02123,-.01143*
20,1,.006,-.02123,-.01143,-.01878,-.00939,0.0*
1,1,.006,-.01878,-.00939*
20,1,.006,-.01878,-.00939,-.01715,-.00694,0.0*
1,1,.006,-.01715,-.00694*
20,1,.006,-.01715,-.00694,-.01592,-.00368,0.0*
1,1,.006,-.01592,-.00368*
20,1,.006,-.01592,-.00368,-.01552,0.0,0.0*
1,1,.006,-.01552,0.0*
20,1,.006,-.01552,0.0,-.01592,.00367,0.0*
1,1,.006,-.01592,.00367*
20,1,.006,-.01592,.00367,-.01715,.00694,0.0*
1,1,.006,-.01715,.00694*
20,1,.006,-.01715,.00694,-.01878,.00939,0.0*
1,1,.006,-.01878,.00939*
20,1,.006,-.01878,.00939,-.02123,.01143,0.0*
1,1,.006,-.02123,.01143*
20,1,.006,-.02123,.01143,-.0245,.01225,0.0*
1,1,.006,-.0245,.01225*
1,1,.006,-.00897,-.00735*
20,1,.006,-.00897,-.00735,-.00652,-.01021,0.0*
1,1,.006,-.00652,-.01021*
20,1,.006,-.00652,-.01021,-.00326,-.01184,0.0*
1,1,.006,-.00326,-.01184*
20,1,.006,-.00326,-.01184,.00042,-.01225,0.0*
1,1,.006,.00042,-.01225*
20,1,.006,.00042,-.01225,.00369,-.01184,0.0*
1,1,.006,.00369,-.01184*
20,1,.006,.00369,-.01184,.00695,-.0098,0.0*
1,1,.006,.00695,-.0098*
20,1,.006,.00695,-.0098,.00899,-.00735,0.0*
1,1,.006,.00899,-.00735*
20,1,.006,.00899,-.00735,.0094,-.0049,0.0*
1,1,.006,.0094,-.0049*
20,1,.006,.0094,-.0049,.00859,-.00204,0.0*
1,1,.006,.00859,-.00204*
20,1,.006,.00859,-.00204,.00573,0.0,0.0*
1,1,.006,.00573,0.0*
20,1,.006,.00573,0.0,.00287,.00082,0.0*
1,1,.006,.00287,.00082*
20,1,.006,.00287,.00082,-.00081,.00082,0.0*
1,1,.006,-.00081,.00082*
1,1,.006,.00287,.00082*
20,1,.006,.00287,.00082,.00532,.00204,0.0*
1,1,.006,.00532,.00204*
20,1,.006,.00532,.00204,.00736,.00408,0.0*
1,1,.006,.00736,.00408*
20,1,.006,.00736,.00408,.00818,.00653,0.0*
1,1,.006,.00818,.00653*
20,1,.006,.00818,.00653,.00736,.00898,0.0*
1,1,.006,.00736,.00898*
20,1,.006,.00736,.00898,.00532,.01102,0.0*
1,1,.006,.00532,.01102*
20,1,.006,.00532,.01102,.00164,.01225,0.0*
1,1,.006,.00164,.01225*
20,1,.006,.00164,.01225,-.00203,.01184,0.0*
1,1,.006,-.00203,.01184*
20,1,.006,-.00203,.01184,-.00571,.01021,0.0*
1,1,.006,-.00571,.01021*
1,1,.006,.02452,-.01225*
20,1,.006,.02452,-.01225,.02738,-.01184,0.0*
1,1,.006,.02738,-.01184*
20,1,.006,.02738,-.01184,.03064,-.01062,0.0*
1,1,.006,.03064,-.01062*
20,1,.006,.03064,-.01062,.03269,-.00858,0.0*
1,1,.006,.03269,-.00858*
20,1,.006,.03269,-.00858,.0335,-.00572,0.0*
1,1,.006,.0335,-.00572*
20,1,.006,.0335,-.00572,.03269,-.00286,0.0*
1,1,.006,.03269,-.00286*
20,1,.006,.03269,-.00286,.03024,-.00041,0.0*
1,1,.006,.03024,-.00041*
20,1,.006,.03024,-.00041,.02656,.00082,0.0*
1,1,.006,.02656,.00082*
20,1,.006,.02656,.00082,.02248,.00082,0.0*
1,1,.006,.02248,.00082*
20,1,.006,.02248,.00082,.02003,.00163,0.0*
1,1,.006,.02003,.00163*
20,1,.006,.02003,.00163,.01799,.00367,0.0*
1,1,.006,.01799,.00367*
20,1,.006,.01799,.00367,.01717,.00653,0.0*
1,1,.006,.01717,.00653*
20,1,.006,.01717,.00653,.0184,.00939,0.0*
1,1,.006,.0184,.00939*
20,1,.006,.0184,.00939,.02125,.01143,0.0*
1,1,.006,.02125,.01143*
20,1,.006,.02125,.01143,.02452,.01225,0.0*
1,1,.006,.02452,.01225*
20,1,.006,.02452,.01225,.02779,.01143,0.0*
1,1,.006,.02779,.01143*
20,1,.006,.02779,.01143,.03064,.00939,0.0*
1,1,.006,.03064,.00939*
20,1,.006,.03064,.00939,.03187,.00653,0.0*
1,1,.006,.03187,.00653*
20,1,.006,.03187,.00653,.03105,.00367,0.0*
1,1,.006,.03105,.00367*
20,1,.006,.03105,.00367,.02901,.00163,0.0*
1,1,.006,.02901,.00163*
20,1,.006,.02901,.00163,.02656,.00082,0.0*
1,1,.006,.02656,.00082*
20,1,.006,.02656,.00082,.02248,.00082,0.0*
1,1,.006,.02248,.00082*
20,1,.006,.02248,.00082,.0188,-.00041,0.0*
1,1,.006,.0188,-.00041*
20,1,.006,.0188,-.00041,.01635,-.00286,0.0*
1,1,.006,.01635,-.00286*
20,1,.006,.01635,-.00286,.01554,-.00572,0.0*
1,1,.006,.01554,-.00572*
20,1,.006,.01554,-.00572,.01635,-.00858,0.0*
1,1,.006,.01635,-.00858*
20,1,.006,.01635,-.00858,.0184,-.01062,0.0*
1,1,.006,.0184,-.01062*
20,1,.006,.0184,-.01062,.02166,-.01184,0.0*
1,1,.006,.02166,-.01184*
20,1,.006,.02166,-.01184,.02452,-.01225,0.0*
1,1,.006,.02452,-.01225*
%
%ADD16MACRO16*%
%AMMACRO18*
1,1,.006,.0595,0.0*
20,1,.006,.0595,0.0,0.0,-.0595,0.0*
1,1,.006,0.0,-.0595*
20,1,.006,0.0,-.0595,-.0595,0.0,0.0*
1,1,.006,-.0595,0.0*
20,1,.006,-.0595,0.0,0.0,.0595,0.0*
1,1,.006,0.0,.0595*
20,1,.006,0.0,.0595,.0595,0.0,0.0*
1,1,.006,.0595,0.0*
1,1,.006,-.04165,-.02082*
20,1,.006,-.04165,-.02082,-.04165,.02083,0.0*
1,1,.006,-.04165,.02083*
20,1,.006,-.04165,.02083,-.04998,.0125,0.0*
1,1,.006,-.04998,.0125*
1,1,.006,-.04998,-.02082*
20,1,.006,-.04998,-.02082,-.03332,-.02082,0.0*
1,1,.006,-.03332,-.02082*
1,1,.006,.00001,-.02082*
20,1,.006,.00001,-.02082,.00001,.02083,0.0*
1,1,.006,.00001,.02083*
20,1,.006,.00001,.02083,-.00832,.0125,0.0*
1,1,.006,-.00832,.0125*
1,1,.006,-.00832,-.02082*
20,1,.006,-.00832,-.02082,.00834,-.02082,0.0*
1,1,.006,.00834,-.02082*
1,1,.006,.02987,-.01596*
20,1,.006,.02987,-.01596,.03473,-.01943,0.0*
1,1,.006,.03473,-.01943*
20,1,.006,.03473,-.01943,.04029,-.02082,0.0*
1,1,.006,.04029,-.02082*
20,1,.006,.04029,-.02082,.04584,-.01943,0.0*
1,1,.006,.04584,-.01943*
20,1,.006,.04584,-.01943,.0507,-.01527,0.0*
1,1,.006,.0507,-.01527*
20,1,.006,.0507,-.01527,.05417,-.00902,0.0*
1,1,.006,.05417,-.00902*
20,1,.006,.05417,-.00902,.05556,-.00277,0.0*
1,1,.006,.05556,-.00277*
20,1,.006,.05556,-.00277,.05556,.00486,0.0*
1,1,.006,.05556,.00486*
20,1,.006,.05556,.00486,.05417,.01111,0.0*
1,1,.006,.05417,.01111*
20,1,.006,.05417,.01111,.0507,.01666,0.0*
1,1,.006,.0507,.01666*
20,1,.006,.0507,.01666,.04653,.01944,0.0*
1,1,.006,.04653,.01944*
20,1,.006,.04653,.01944,.04167,.02083,0.0*
1,1,.006,.04167,.02083*
20,1,.006,.04167,.02083,.03612,.01944,0.0*
1,1,.006,.03612,.01944*
20,1,.006,.03612,.01944,.03196,.01666,0.0*
1,1,.006,.03196,.01666*
20,1,.006,.03196,.01666,.02918,.0125,0.0*
1,1,.006,.02918,.0125*
20,1,.006,.02918,.0125,.02779,.00695,0.0*
1,1,.006,.02779,.00695*
20,1,.006,.02779,.00695,.02918,.00209,0.0*
1,1,.006,.02918,.00209*
20,1,.006,.02918,.00209,.03265,-.00277,0.0*
1,1,.006,.03265,-.00277*
20,1,.006,.03265,-.00277,.03682,-.00555,0.0*
1,1,.006,.03682,-.00555*
20,1,.006,.03682,-.00555,.04167,-.00624,0.0*
1,1,.006,.04167,-.00624*
20,1,.006,.04167,-.00624,.04723,-.00486,0.0*
1,1,.006,.04723,-.00486*
20,1,.006,.04723,-.00486,.05139,-.00138,0.0*
1,1,.006,.05139,-.00138*
20,1,.006,.05139,-.00138,.05556,.00486,0.0*
1,1,.006,.05556,.00486*
%
%ADD18MACRO18*%
%AMMACRO12*
1,1,.006,.00384,0.0*
20,1,.006,.00384,0.0,-.00384,0.0,0.0*
1,1,.006,-.00384,0.0*
1,1,.006,0.0,.00384*
20,1,.006,0.0,.00384,0.0,-.00384,0.0*
1,1,.006,0.0,-.00384*
%
%ADD12MACRO12*%
%AMMACRO13*
1,1,.006,.035,0.0*
20,1,.006,.035,0.0,.034468,-.006078,0.0*
1,1,.006,.034468,-.006078*
20,1,.006,.034468,-.006078,.032889,-.011971,0.0*
1,1,.006,.032889,-.011971*
20,1,.006,.032889,-.011971,.030311,-.0175,0.0*
1,1,.006,.030311,-.0175*
20,1,.006,.030311,-.0175,.026812,-.022498,0.0*
1,1,.006,.026812,-.022498*
20,1,.006,.026812,-.022498,.022498,-.026812,0.0*
1,1,.006,.022498,-.026812*
20,1,.006,.022498,-.026812,.0175,-.030311,0.0*
1,1,.006,.0175,-.030311*
20,1,.006,.0175,-.030311,.011971,-.032889,0.0*
1,1,.006,.011971,-.032889*
20,1,.006,.011971,-.032889,.006078,-.034468,0.0*
1,1,.006,.006078,-.034468*
20,1,.006,.006078,-.034468,0.0,-.035,0.0*
1,1,.006,0.0,-.035*
20,1,.006,0.0,-.035,-.006078,-.034468,0.0*
1,1,.006,-.006078,-.034468*
20,1,.006,-.006078,-.034468,-.011971,-.032889,0.0*
1,1,.006,-.011971,-.032889*
20,1,.006,-.011971,-.032889,-.0175,-.030311,0.0*
1,1,.006,-.0175,-.030311*
20,1,.006,-.0175,-.030311,-.022498,-.026812,0.0*
1,1,.006,-.022498,-.026812*
20,1,.006,-.022498,-.026812,-.026812,-.022498,0.0*
1,1,.006,-.026812,-.022498*
20,1,.006,-.026812,-.022498,-.030311,-.0175,0.0*
1,1,.006,-.030311,-.0175*
20,1,.006,-.030311,-.0175,-.032889,-.011971,0.0*
1,1,.006,-.032889,-.011971*
20,1,.006,-.032889,-.011971,-.034468,-.006078,0.0*
1,1,.006,-.034468,-.006078*
20,1,.006,-.034468,-.006078,-.035,0.0,0.0*
1,1,.006,-.035,0.0*
20,1,.006,-.035,0.0,-.034468,.006078,0.0*
1,1,.006,-.034468,.006078*
20,1,.006,-.034468,.006078,-.032889,.011971,0.0*
1,1,.006,-.032889,.011971*
20,1,.006,-.032889,.011971,-.030311,.0175,0.0*
1,1,.006,-.030311,.0175*
20,1,.006,-.030311,.0175,-.026812,.022498,0.0*
1,1,.006,-.026812,.022498*
20,1,.006,-.026812,.022498,-.022498,.026812,0.0*
1,1,.006,-.022498,.026812*
20,1,.006,-.022498,.026812,-.0175,.030311,0.0*
1,1,.006,-.0175,.030311*
20,1,.006,-.0175,.030311,-.011971,.032889,0.0*
1,1,.006,-.011971,.032889*
20,1,.006,-.011971,.032889,-.006078,.034468,0.0*
1,1,.006,-.006078,.034468*
20,1,.006,-.006078,.034468,0.0,.035,0.0*
1,1,.006,0.0,.035*
20,1,.006,0.0,.035,.006078,.034468,0.0*
1,1,.006,.006078,.034468*
20,1,.006,.006078,.034468,.011971,.032889,0.0*
1,1,.006,.011971,.032889*
20,1,.006,.011971,.032889,.0175,.030311,0.0*
1,1,.006,.0175,.030311*
20,1,.006,.0175,.030311,.022498,.026812,0.0*
1,1,.006,.022498,.026812*
20,1,.006,.022498,.026812,.026812,.022498,0.0*
1,1,.006,.026812,.022498*
20,1,.006,.026812,.022498,.030311,.0175,0.0*
1,1,.006,.030311,.0175*
20,1,.006,.030311,.0175,.032889,.011971,0.0*
1,1,.006,.032889,.011971*
20,1,.006,.032889,.011971,.034468,.006078,0.0*
1,1,.006,.034468,.006078*
20,1,.006,.034468,.006078,.035,0.0,0.0*
1,1,.006,.035,0.0*
1,1,.006,-.0295,.01041*
20,1,.006,-.0295,.01041,-.02082,-.01041,0.0*
1,1,.006,-.02082,-.01041*
20,1,.006,-.02082,-.01041,-.01214,.01041,0.0*
1,1,.006,-.01214,.01041*
1,1,.006,.00001,-.01041*
20,1,.006,.00001,-.01041,.00001,.01041,0.0*
1,1,.006,.00001,.01041*
20,1,.006,.00001,.01041,-.00415,.00625,0.0*
1,1,.006,-.00415,.00625*
1,1,.006,-.00415,-.01041*
20,1,.006,-.00415,-.01041,.00417,-.01041,0.0*
1,1,.006,.00417,-.01041*
1,1,.006,.02084,.01041*
20,1,.006,.02084,.01041,.01806,.00972,0.0*
1,1,.006,.01806,.00972*
20,1,.006,.01806,.00972,.01598,.00798,0.0*
1,1,.006,.01598,.00798*
20,1,.006,.01598,.00798,.01459,.0059,0.0*
1,1,.006,.01459,.0059*
20,1,.006,.01459,.0059,.01355,.00312,0.0*
1,1,.006,.01355,.00312*
20,1,.006,.01355,.00312,.01321,0.0,0.0*
1,1,.006,.01321,0.0*
20,1,.006,.01321,0.0,.01355,-.00312,0.0*
1,1,.006,.01355,-.00312*
20,1,.006,.01355,-.00312,.01459,-.0059,0.0*
1,1,.006,.01459,-.0059*
20,1,.006,.01459,-.0059,.01598,-.00798,0.0*
1,1,.006,.01598,-.00798*
20,1,.006,.01598,-.00798,.01806,-.00972,0.0*
1,1,.006,.01806,-.00972*
20,1,.006,.01806,-.00972,.02084,-.01041,0.0*
1,1,.006,.02084,-.01041*
20,1,.006,.02084,-.01041,.02362,-.00972,0.0*
1,1,.006,.02362,-.00972*
20,1,.006,.02362,-.00972,.0257,-.00798,0.0*
1,1,.006,.0257,-.00798*
20,1,.006,.0257,-.00798,.02709,-.0059,0.0*
1,1,.006,.02709,-.0059*
20,1,.006,.02709,-.0059,.02813,-.00312,0.0*
1,1,.006,.02813,-.00312*
20,1,.006,.02813,-.00312,.02847,0.0,0.0*
1,1,.006,.02847,0.0*
20,1,.006,.02847,0.0,.02813,.00312,0.0*
1,1,.006,.02813,.00312*
20,1,.006,.02813,.00312,.02709,.0059,0.0*
1,1,.006,.02709,.0059*
20,1,.006,.02709,.0059,.0257,.00798,0.0*
1,1,.006,.0257,.00798*
20,1,.006,.0257,.00798,.02362,.00972,0.0*
1,1,.006,.02362,.00972*
20,1,.006,.02362,.00972,.02084,.01041,0.0*
1,1,.006,.02084,.01041*
%
%ADD13MACRO13*%
%ADD10C,.125*%
%AMMACRO15*
1,1,.006,0.0,.035*
20,1,.006,0.0,.035,.030311,-.0175,0.0*
1,1,.006,.030311,-.0175*
20,1,.006,.030311,-.0175,-.030311,-.0175,0.0*
1,1,.006,-.030311,-.0175*
20,1,.006,-.030311,-.0175,0.0,.035,0.0*
1,1,.006,0.0,.035*
1,1,.006,-.01433,-.00918*
20,1,.006,-.01433,-.00918,-.01433,.00184,0.0*
1,1,.006,-.01433,.00184*
1,1,.006,-.01433,.00018*
20,1,.006,-.01433,.00018,-.01341,.0011,0.0*
1,1,.006,-.01341,.0011*
20,1,.006,-.01341,.0011,-.01249,.00165,0.0*
1,1,.006,-.01249,.00165*
20,1,.006,-.01249,.00165,-.01102,.00184,0.0*
1,1,.006,-.01102,.00184*
20,1,.006,-.01102,.00184,-.00973,.00165,0.0*
1,1,.006,-.00973,.00165*
20,1,.006,-.00973,.00165,-.00845,.00073,0.0*
1,1,.006,-.00845,.00073*
20,1,.006,-.00845,.00073,-.0079,-.00055,0.0*
1,1,.006,-.0079,-.00055*
20,1,.006,-.0079,-.00055,-.00771,-.00184,0.0*
1,1,.006,-.00771,-.00184*
20,1,.006,-.00771,-.00184,-.0079,-.00312,0.0*
1,1,.006,-.0079,-.00312*
20,1,.006,-.0079,-.00312,-.00845,-.00441,0.0*
1,1,.006,-.00845,-.00441*
20,1,.006,-.00845,-.00441,-.00955,-.00514,0.0*
1,1,.006,-.00955,-.00514*
20,1,.006,-.00955,-.00514,-.01102,-.00551,0.0*
1,1,.006,-.01102,-.00551*
20,1,.006,-.01102,-.00551,-.01231,-.00533,0.0*
1,1,.006,-.01231,-.00533*
20,1,.006,-.01231,-.00533,-.01359,-.00478,0.0*
1,1,.006,-.01359,-.00478*
20,1,.006,-.01359,-.00478,-.01433,-.00404,0.0*
1,1,.006,-.01433,-.00404*
1,1,.006,.00001,.00551*
20,1,.006,.00001,.00551,.00001,-.00551,0.0*
1,1,.006,.00001,-.00551*
1,1,.006,-.00256,.00184*
20,1,.006,-.00256,.00184,.00258,.00184,0.0*
1,1,.006,.00258,.00184*
1,1,.006,.01104,-.00551*
20,1,.006,.01104,-.00551,.00994,-.00533,0.0*
1,1,.006,.00994,-.00533*
20,1,.006,.00994,-.00533,.00884,-.00459,0.0*
1,1,.006,.00884,-.00459*
20,1,.006,.00884,-.00459,.0081,-.00331,0.0*
1,1,.006,.0081,-.00331*
20,1,.006,.0081,-.00331,.00773,-.00184,0.0*
1,1,.006,.00773,-.00184*
20,1,.006,.00773,-.00184,.0081,-.00037,0.0*
1,1,.006,.0081,-.00037*
20,1,.006,.0081,-.00037,.00884,.00092,0.0*
1,1,.006,.00884,.00092*
20,1,.006,.00884,.00092,.00994,.00165,0.0*
1,1,.006,.00994,.00165*
20,1,.006,.00994,.00165,.01104,.00184,0.0*
1,1,.006,.01104,.00184*
20,1,.006,.01104,.00184,.01214,.00165,0.0*
1,1,.006,.01214,.00165*
20,1,.006,.01214,.00165,.01324,.00092,0.0*
1,1,.006,.01324,.00092*
20,1,.006,.01324,.00092,.01398,-.00037,0.0*
1,1,.006,.01398,-.00037*
20,1,.006,.01398,-.00037,.01416,-.00184,0.0*
1,1,.006,.01416,-.00184*
20,1,.006,.01416,-.00184,.01398,-.00331,0.0*
1,1,.006,.01398,-.00331*
20,1,.006,.01398,-.00331,.01324,-.00459,0.0*
1,1,.006,.01324,-.00459*
20,1,.006,.01324,-.00459,.01214,-.00533,0.0*
1,1,.006,.01214,-.00533*
20,1,.006,.01214,-.00533,.01104,-.00551,0.0*
1,1,.006,.01104,-.00551*
%
%ADD15MACRO15*%
%AMMACRO19*
1,1,.006,.0625,0.0*
20,1,.006,.0625,0.0,.03125,.054127,0.0*
1,1,.006,.03125,.054127*
20,1,.006,.03125,.054127,-.03125,.054127,0.0*
1,1,.006,-.03125,.054127*
20,1,.006,-.03125,.054127,-.0625,0.0,0.0*
1,1,.006,-.0625,0.0*
20,1,.006,-.0625,0.0,-.03125,-.054127,0.0*
1,1,.006,-.03125,-.054127*
20,1,.006,-.03125,-.054127,.03125,-.054127,0.0*
1,1,.006,.03125,-.054127*
20,1,.006,.03125,-.054127,.0625,0.0,0.0*
1,1,.006,.0625,0.0*
1,1,.006,-.02143,-.02552*
20,1,.006,-.02143,-.02552,-.02143,.0051,0.0*
1,1,.006,-.02143,.0051*
1,1,.006,-.02143,.00051*
20,1,.006,-.02143,.00051,-.02399,.00306,0.0*
1,1,.006,-.02399,.00306*
20,1,.006,-.02399,.00306,-.02705,.00459,0.0*
1,1,.006,-.02705,.00459*
20,1,.006,-.02705,.00459,-.03062,.0051,0.0*
1,1,.006,-.03062,.0051*
20,1,.006,-.03062,.0051,-.03368,.00459,0.0*
1,1,.006,-.03368,.00459*
20,1,.006,-.03368,.00459,-.03725,.00204,0.0*
1,1,.006,-.03725,.00204*
20,1,.006,-.03725,.00204,-.0393,-.00153,0.0*
1,1,.006,-.0393,-.00153*
20,1,.006,-.0393,-.00153,-.03981,-.0051,0.0*
1,1,.006,-.03981,-.0051*
20,1,.006,-.03981,-.0051,-.0393,-.00868,0.0*
1,1,.006,-.0393,-.00868*
20,1,.006,-.0393,-.00868,-.03725,-.01225,0.0*
1,1,.006,-.03725,-.01225*
20,1,.006,-.03725,-.01225,-.03368,-.0148,0.0*
1,1,.006,-.03368,-.0148*
20,1,.006,-.03368,-.0148,-.03062,-.01531,0.0*
1,1,.006,-.03062,-.01531*
20,1,.006,-.03062,-.01531,-.02705,-.0148,0.0*
1,1,.006,-.02705,-.0148*
20,1,.006,-.02705,-.0148,-.02399,-.01327,0.0*
1,1,.006,-.02399,-.01327*
20,1,.006,-.02399,-.01327,-.02143,-.01072,0.0*
1,1,.006,-.02143,-.01072*
1,1,.006,-.01275,.0051*
20,1,.006,-.01275,.0051,-.00662,-.01531,0.0*
1,1,.006,-.00662,-.01531*
20,1,.006,-.00662,-.01531,.00001,.0051,0.0*
1,1,.006,.00001,.0051*
20,1,.006,.00001,.0051,.00664,-.01531,0.0*
1,1,.006,.00664,-.01531*
20,1,.006,.00664,-.01531,.01277,.0051,0.0*
1,1,.006,.01277,.0051*
1,1,.006,.03064,.01531*
20,1,.006,.03064,.01531,.03064,-.01531,0.0*
1,1,.006,.03064,-.01531*
1,1,.006,.0235,.0051*
20,1,.006,.0235,.0051,.03778,.0051,0.0*
1,1,.006,.03778,.0051*
%
%ADD19MACRO19*%
%AMMACRO11*
1,1,.006,0.0,.035*
20,1,.006,0.0,.035,.030311,-.0175,0.0*
1,1,.006,.030311,-.0175*
20,1,.006,.030311,-.0175,-.030311,-.0175,0.0*
1,1,.006,-.030311,-.0175*
20,1,.006,-.030311,-.0175,0.0,.035,0.0*
1,1,.006,0.0,.035*
1,1,.006,-.01102,.00551*
20,1,.006,-.01102,.00551,-.01249,.00514,0.0*
1,1,.006,-.01249,.00514*
20,1,.006,-.01249,.00514,-.01359,.00422,0.0*
1,1,.006,-.01359,.00422*
20,1,.006,-.01359,.00422,-.01433,.00312,0.0*
1,1,.006,-.01433,.00312*
20,1,.006,-.01433,.00312,-.01488,.00165,0.0*
1,1,.006,-.01488,.00165*
20,1,.006,-.01488,.00165,-.01506,0.0,0.0*
1,1,.006,-.01506,0.0*
20,1,.006,-.01506,0.0,-.01488,-.00165,0.0*
1,1,.006,-.01488,-.00165*
20,1,.006,-.01488,-.00165,-.01433,-.00312,0.0*
1,1,.006,-.01433,-.00312*
20,1,.006,-.01433,-.00312,-.01359,-.00422,0.0*
1,1,.006,-.01359,-.00422*
20,1,.006,-.01359,-.00422,-.01249,-.00514,0.0*
1,1,.006,-.01249,-.00514*
20,1,.006,-.01249,-.00514,-.01102,-.00551,0.0*
1,1,.006,-.01102,-.00551*
20,1,.006,-.01102,-.00551,-.00955,-.00514,0.0*
1,1,.006,-.00955,-.00514*
20,1,.006,-.00955,-.00514,-.00845,-.00422,0.0*
1,1,.006,-.00845,-.00422*
20,1,.006,-.00845,-.00422,-.00771,-.00312,0.0*
1,1,.006,-.00771,-.00312*
20,1,.006,-.00771,-.00312,-.00716,-.00165,0.0*
1,1,.006,-.00716,-.00165*
20,1,.006,-.00716,-.00165,-.00698,0.0,0.0*
1,1,.006,-.00698,0.0*
20,1,.006,-.00698,0.0,-.00716,.00165,0.0*
1,1,.006,-.00716,.00165*
20,1,.006,-.00716,.00165,-.00771,.00312,0.0*
1,1,.006,-.00771,.00312*
20,1,.006,-.00771,.00312,-.00845,.00422,0.0*
1,1,.006,-.00845,.00422*
20,1,.006,-.00845,.00422,-.00955,.00514,0.0*
1,1,.006,-.00955,.00514*
20,1,.006,-.00955,.00514,-.01102,.00551,0.0*
1,1,.006,-.01102,.00551*
1,1,.006,-.00348,-.00092*
20,1,.006,-.00348,-.00092,-.00219,.00037,0.0*
1,1,.006,-.00219,.00037*
20,1,.006,-.00219,.00037,-.00109,.0011,0.0*
1,1,.006,-.00109,.0011*
20,1,.006,-.00109,.0011,.00038,.00147,0.0*
1,1,.006,.00038,.00147*
20,1,.006,.00038,.00147,.00166,.0011,0.0*
1,1,.006,.00166,.0011*
20,1,.006,.00166,.0011,.00258,.00037,0.0*
1,1,.006,.00258,.00037*
20,1,.006,.00258,.00037,.00332,-.00073,0.0*
1,1,.006,.00332,-.00073*
20,1,.006,.00332,-.00073,.0035,-.00202,0.0*
1,1,.006,.0035,-.00202*
20,1,.006,.0035,-.00202,.00332,-.00312,0.0*
1,1,.006,.00332,-.00312*
20,1,.006,.00332,-.00312,.00258,-.00422,0.0*
1,1,.006,.00258,-.00422*
20,1,.006,.00258,-.00422,.00148,-.00514,0.0*
1,1,.006,.00148,-.00514*
20,1,.006,.00148,-.00514,.00019,-.00551,0.0*
1,1,.006,.00019,-.00551*
20,1,.006,.00019,-.00551,-.00128,-.00514,0.0*
1,1,.006,-.00128,-.00514*
20,1,.006,-.00128,-.00514,-.00256,-.00404,0.0*
1,1,.006,-.00256,-.00404*
20,1,.006,-.00256,-.00404,-.0033,-.00239,0.0*
1,1,.006,-.0033,-.00239*
20,1,.006,-.0033,-.00239,-.00348,-.00055,0.0*
1,1,.006,-.00348,-.00055*
20,1,.006,-.00348,-.00055,-.00311,.00184,0.0*
1,1,.006,-.00311,.00184*
20,1,.006,-.00311,.00184,-.00256,.00312,0.0*
1,1,.006,-.00256,.00312*
20,1,.006,-.00256,.00312,-.00164,.00441,0.0*
1,1,.006,-.00164,.00441*
20,1,.006,-.00164,.00441,-.00036,.00533,0.0*
1,1,.006,-.00036,.00533*
20,1,.006,-.00036,.00533,.00093,.00551,0.0*
1,1,.006,.00093,.00551*
20,1,.006,.00093,.00551,.00221,.00514,0.0*
1,1,.006,.00221,.00514*
20,1,.006,.00221,.00514,.00313,.00422,0.0*
1,1,.006,.00313,.00422*
1,1,.006,.01067,-.00551*
20,1,.006,.01067,-.00551,.01104,-.00312,0.0*
1,1,.006,.01104,-.00312*
20,1,.006,.01104,-.00312,.01159,-.0011,0.0*
1,1,.006,.01159,-.0011*
20,1,.006,.01159,-.0011,.01233,.00073,0.0*
1,1,.006,.01233,.00073*
20,1,.006,.01233,.00073,.01324,.00275,0.0*
1,1,.006,.01324,.00275*
20,1,.006,.01324,.00275,.01471,.00551,0.0*
1,1,.006,.01471,.00551*
20,1,.006,.01471,.00551,.00737,.00551,0.0*
1,1,.006,.00737,.00551*
%
%ADD11MACRO11*%
%ADD21C,.006*%
G75*
%LPD*%
G75*
G36*
G01X1364599Y1486302D02*
X1365400D01*
Y1486300D01*
X1367500D01*
Y1426000D01*
X1372500Y1406000D01*
X1382500D01*
X1387500Y1426000D01*
Y1485924D01*
X1389400D01*
X1390369D01*
Y1575924D01*
X1390360Y1590646D01*
X1387163Y1584860D01*
X1382500Y1576000D01*
X1367500Y1586000D01*
X1367389Y1586085D01*
X1365633Y1587271D01*
X1365605Y1587289D01*
X1364599Y1587896D01*
Y1486302D01*
G37*
G54D10*
X-58189Y19685D03*
Y619685D03*
Y1307087D03*
X865353Y19685D03*
Y1307087D03*
G54D11*
X-58431Y824000D03*
X-63431Y837184D03*
Y1152816D03*
X-58431Y1166000D03*
X-53431Y837184D03*
Y1152816D03*
X-27318Y824000D03*
X-32318Y837184D03*
X-22318D03*
X-32318Y1152816D03*
X-22318D03*
X-27318Y1166000D03*
X1265450Y985200D03*
G54D20*
X101772Y1287047D03*
X1265450Y909600D03*
G54D21*
G01X-320500Y-470483D02*
Y2626000D01*
X2967000D01*
Y-470483D01*
X-320500D01*
G01X-120729Y1768132D02*
X-133229D01*
X-130729Y1766272D01*
G01X-120729D02*
Y1769992D01*
G01X-133229Y1780532D02*
X-132812Y1779292D01*
X-131771Y1778362D01*
X-130521Y1777742D01*
X-128854Y1777277D01*
X-126979Y1777122D01*
X-125104Y1777277D01*
X-123437Y1777742D01*
X-122187Y1778362D01*
X-121146Y1779292D01*
X-120729Y1780532D01*
X-121146Y1781772D01*
X-122187Y1782702D01*
X-123437Y1783322D01*
X-125104Y1783787D01*
X-126979Y1783942D01*
X-128854Y1783787D01*
X-130521Y1783322D01*
X-131771Y1782702D01*
X-132812Y1781772D01*
X-133229Y1780532D01*
G01X-120729Y1788902D02*
X-133229D01*
X-122812Y1792932D01*
X-133229Y1796962D01*
X-120729D01*
G01Y1801302D02*
X-133229D01*
X-122812Y1805332D01*
X-133229Y1809362D01*
X-120729D01*
G01X-122713Y-18750D02*
X-127363D01*
Y-6250D01*
X-122713D01*
G01X-113387Y1268297D02*
X-118037D01*
Y1280797D01*
X-113387D01*
G01X-111870Y1772952D02*
Y1741456D01*
G01D02*
Y1792637D01*
G01Y1843818D02*
Y1792637D01*
G01X-45640Y1772952D02*
X-119744D01*
G01X-111870Y1812322D02*
Y1843818D01*
G01X-46494Y1812322D02*
X-119744D01*
G01X-122500Y2023500D02*
Y2031500D01*
X-123700Y2029900D01*
G01Y2023500D02*
X-121300D01*
G01X-114500Y2031500D02*
X-115300Y2031233D01*
X-115900Y2030567D01*
X-116300Y2029767D01*
X-116600Y2028700D01*
X-116700Y2027500D01*
X-116600Y2026300D01*
X-116300Y2025233D01*
X-115900Y2024433D01*
X-115300Y2023767D01*
X-114500Y2023500D01*
X-113700Y2023767D01*
X-113100Y2024433D01*
X-112700Y2025233D01*
X-112400Y2026300D01*
X-112300Y2027500D01*
X-112400Y2028700D01*
X-112700Y2029767D01*
X-113100Y2030567D01*
X-113700Y2031233D01*
X-114500Y2031500D01*
G01X-106500Y2023233D02*
X-106700Y2023367D01*
Y2023633D01*
X-106500Y2023767D01*
X-106300Y2023633D01*
Y2023367D01*
X-106500Y2023233D01*
G01X-100400Y2023500D02*
Y2031500D01*
X-96600D01*
G01X-98000Y2027633D02*
X-100400D01*
G01X-90500Y2023500D02*
X-91300Y2023633D01*
X-92000Y2024167D01*
X-92600Y2024967D01*
X-93000Y2025900D01*
X-93200Y2026967D01*
Y2028033D01*
X-93000Y2029100D01*
X-92600Y2030033D01*
X-92000Y2030833D01*
X-91300Y2031367D01*
X-90500Y2031500D01*
X-89700Y2031367D01*
X-89000Y2030833D01*
X-88400Y2030033D01*
X-88000Y2029100D01*
X-87800Y2028033D01*
Y2026967D01*
X-88000Y2025900D01*
X-88400Y2024967D01*
X-89000Y2024167D01*
X-89700Y2023633D01*
X-90500Y2023500D01*
G01X-84500D02*
Y2031500D01*
X-82000D01*
X-81200Y2031100D01*
X-80700Y2030567D01*
X-80500Y2029500D01*
X-80700Y2028433D01*
X-81300Y2027767D01*
X-82000Y2027367D01*
X-84500D01*
G01X-82000D02*
X-80500Y2023500D01*
G01X-66500Y2031500D02*
Y2023500D01*
G01X-68800Y2031500D02*
X-64200D01*
G01X-60600Y2023500D02*
Y2031500D01*
G01X-56400D02*
Y2023500D01*
G01Y2027500D02*
X-60600D01*
G01X-48500Y2023500D02*
X-52500D01*
Y2031500D01*
X-48500D01*
G01X-50100Y2027633D02*
X-52500D01*
G01X-36500Y2023500D02*
Y2031500D01*
X-34100D01*
X-33300Y2031100D01*
X-32700Y2030167D01*
X-32500Y2029100D01*
X-32700Y2028033D01*
X-33200Y2027233D01*
X-34100Y2026833D01*
X-36500D01*
G01X-26500Y2031500D02*
Y2023500D01*
G01X-28800Y2031500D02*
X-24200D01*
G01X-20600Y2023500D02*
Y2031500D01*
G01X-16400D02*
Y2023500D01*
G01Y2027500D02*
X-20600D01*
G01X-2500Y2031500D02*
Y2023500D01*
G01X-4800Y2031500D02*
X-200D01*
G01X5500Y2023500D02*
X4700Y2023633D01*
X4000Y2024167D01*
X3400Y2024967D01*
X3000Y2025900D01*
X2800Y2026967D01*
Y2028033D01*
X3000Y2029100D01*
X3400Y2030033D01*
X4000Y2030833D01*
X4700Y2031367D01*
X5500Y2031500D01*
X6300Y2031367D01*
X7000Y2030833D01*
X7600Y2030033D01*
X8000Y2029100D01*
X8200Y2028033D01*
Y2026967D01*
X8000Y2025900D01*
X7600Y2024967D01*
X7000Y2024167D01*
X6300Y2023633D01*
X5500Y2023500D01*
G01X13500D02*
X12700Y2023633D01*
X12000Y2024167D01*
X11400Y2024967D01*
X11000Y2025900D01*
X10800Y2026967D01*
Y2028033D01*
X11000Y2029100D01*
X11400Y2030033D01*
X12000Y2030833D01*
X12700Y2031367D01*
X13500Y2031500D01*
X14300Y2031367D01*
X15000Y2030833D01*
X15600Y2030033D01*
X16000Y2029100D01*
X16200Y2028033D01*
Y2026967D01*
X16000Y2025900D01*
X15600Y2024967D01*
X15000Y2024167D01*
X14300Y2023633D01*
X13500Y2023500D01*
G01X19500Y2031500D02*
Y2023500D01*
X23500D01*
G01X28300Y2031500D02*
X30700D01*
G01X29500D02*
Y2023500D01*
G01X28300D02*
X30700D01*
G01X35200D02*
Y2031500D01*
X39800Y2023500D01*
Y2031500D01*
G01X46100Y2027500D02*
X48100D01*
Y2025100D01*
X47500Y2024300D01*
X46800Y2023767D01*
X45800Y2023500D01*
X44800Y2023767D01*
X44100Y2024300D01*
X43500Y2025100D01*
X43100Y2026033D01*
X42900Y2027100D01*
Y2028033D01*
X43100Y2028833D01*
X43500Y2029767D01*
X44100Y2030567D01*
X44700Y2031100D01*
X45500Y2031500D01*
X46200D01*
X47000Y2031233D01*
X47600Y2030700D01*
G01X59400Y2023500D02*
Y2031500D01*
G01X63600D02*
Y2023500D01*
G01Y2027500D02*
X59400D01*
G01X69500Y2023500D02*
X68700Y2023633D01*
X68000Y2024167D01*
X67400Y2024967D01*
X67000Y2025900D01*
X66800Y2026967D01*
Y2028033D01*
X67000Y2029100D01*
X67400Y2030033D01*
X68000Y2030833D01*
X68700Y2031367D01*
X69500Y2031500D01*
X70300Y2031367D01*
X71000Y2030833D01*
X71600Y2030033D01*
X72000Y2029100D01*
X72200Y2028033D01*
Y2026967D01*
X72000Y2025900D01*
X71600Y2024967D01*
X71000Y2024167D01*
X70300Y2023633D01*
X69500Y2023500D01*
G01X75500Y2031500D02*
Y2023500D01*
X79500D01*
G01X87500D02*
X83500D01*
Y2031500D01*
X87500D01*
G01X85900Y2027633D02*
X83500D01*
G01X91400Y2024566D02*
X92200Y2023900D01*
X93100Y2023500D01*
X93900D01*
X94700Y2023900D01*
X95300Y2024566D01*
X95600Y2025500D01*
X95400Y2026433D01*
X94900Y2027233D01*
X94000Y2027767D01*
X92800Y2028033D01*
X92100Y2028567D01*
X91800Y2029500D01*
X92000Y2030433D01*
X92500Y2031100D01*
X93200Y2031500D01*
X93900D01*
X94600Y2031233D01*
X95200Y2030567D01*
G01X106500Y2031500D02*
X107900Y2023500D01*
X109500Y2031500D01*
X111100Y2023500D01*
X112500Y2031500D01*
G01X115400Y2023500D02*
Y2031500D01*
G01X119600D02*
Y2023500D01*
G01Y2027500D02*
X115400D01*
G01X124300Y2031500D02*
X126700D01*
G01X125500D02*
Y2023500D01*
G01X124300D02*
X126700D01*
G01X135700Y2030833D02*
X135100Y2031233D01*
X134400Y2031500D01*
X133600D01*
X132700Y2031100D01*
X132000Y2030433D01*
X131500Y2029633D01*
X131100Y2028300D01*
X131000Y2027100D01*
X131200Y2025900D01*
X131500Y2025100D01*
X132100Y2024300D01*
X132800Y2023767D01*
X133500Y2023500D01*
X134200D01*
X134900Y2023767D01*
X135500Y2024167D01*
X136000Y2024700D01*
G01X139400Y2023500D02*
Y2031500D01*
G01X143600D02*
Y2023500D01*
G01Y2027500D02*
X139400D01*
G01X155400Y2024566D02*
X156200Y2023900D01*
X157100Y2023500D01*
X157900D01*
X158700Y2023900D01*
X159300Y2024566D01*
X159600Y2025500D01*
X159400Y2026433D01*
X158900Y2027233D01*
X158000Y2027767D01*
X156800Y2028033D01*
X156100Y2028567D01*
X155800Y2029500D01*
X156000Y2030433D01*
X156500Y2031100D01*
X157200Y2031500D01*
X157900D01*
X158600Y2031233D01*
X159200Y2030567D01*
G01X164300Y2031500D02*
X166700D01*
G01X165500D02*
Y2023500D01*
G01X164300D02*
X166700D01*
G01X171600Y2031500D02*
X175400D01*
X171600Y2023500D01*
X175400D01*
G01X183500D02*
X179500D01*
Y2031500D01*
X183500D01*
G01X181900Y2027633D02*
X179500D01*
G01X196300Y2031500D02*
X198700D01*
G01X197500D02*
Y2023500D01*
G01X196300D02*
X198700D01*
G01X203400Y2024566D02*
X204200Y2023900D01*
X205100Y2023500D01*
X205900D01*
X206700Y2023900D01*
X207300Y2024566D01*
X207600Y2025500D01*
X207400Y2026433D01*
X206900Y2027233D01*
X206000Y2027767D01*
X204800Y2028033D01*
X204100Y2028567D01*
X203800Y2029500D01*
X204000Y2030433D01*
X204500Y2031100D01*
X205200Y2031500D01*
X205900D01*
X206600Y2031233D01*
X207200Y2030567D01*
G01X223500Y2023500D02*
X219500D01*
Y2031500D01*
X223500D01*
G01X221900Y2027633D02*
X219500D01*
G01X229500Y2023500D02*
X228700Y2023633D01*
X228000Y2024167D01*
X227400Y2024967D01*
X227000Y2025900D01*
X226800Y2026967D01*
Y2028033D01*
X227000Y2029100D01*
X227400Y2030033D01*
X228000Y2030833D01*
X228700Y2031367D01*
X229500Y2031500D01*
X230300Y2031367D01*
X231000Y2030833D01*
X231600Y2030033D01*
X232000Y2029100D01*
X232200Y2028033D01*
Y2026967D01*
X232000Y2025900D01*
X231600Y2024967D01*
X231000Y2024167D01*
X230300Y2023633D01*
X229500Y2023500D01*
G01X230300Y2025633D02*
X231500Y2023500D01*
G01X235300Y2031500D02*
Y2025767D01*
X235700Y2024566D01*
X236500Y2023767D01*
X237500Y2023500D01*
X238500Y2023767D01*
X239300Y2024566D01*
X239700Y2025767D01*
Y2031500D01*
G01X243000Y2023500D02*
X245500Y2031500D01*
X248000Y2023500D01*
G01X247100Y2026300D02*
X243900D01*
G01X251500Y2031500D02*
Y2023500D01*
X255500D01*
G01X269500Y2031500D02*
Y2023500D01*
G01X267200Y2031500D02*
X271800D01*
G01X277500Y2023500D02*
X276700Y2023633D01*
X276000Y2024167D01*
X275400Y2024967D01*
X275000Y2025900D01*
X274800Y2026967D01*
Y2028033D01*
X275000Y2029100D01*
X275400Y2030033D01*
X276000Y2030833D01*
X276700Y2031367D01*
X277500Y2031500D01*
X278300Y2031367D01*
X279000Y2030833D01*
X279600Y2030033D01*
X280000Y2029100D01*
X280200Y2028033D01*
Y2026967D01*
X280000Y2025900D01*
X279600Y2024967D01*
X279000Y2024167D01*
X278300Y2023633D01*
X277500Y2023500D01*
G01X293500D02*
X292700Y2023633D01*
X292000Y2024167D01*
X291400Y2024967D01*
X291000Y2025900D01*
X290800Y2026967D01*
Y2028033D01*
X291000Y2029100D01*
X291400Y2030033D01*
X292000Y2030833D01*
X292700Y2031367D01*
X293500Y2031500D01*
X294300Y2031367D01*
X295000Y2030833D01*
X295600Y2030033D01*
X296000Y2029100D01*
X296200Y2028033D01*
Y2026967D01*
X296000Y2025900D01*
X295600Y2024967D01*
X295000Y2024167D01*
X294300Y2023633D01*
X293500Y2023500D01*
G01X299500D02*
Y2031500D01*
X302000D01*
X302800Y2031100D01*
X303300Y2030567D01*
X303500Y2029500D01*
X303300Y2028433D01*
X302700Y2027767D01*
X302000Y2027367D01*
X299500D01*
G01X302000D02*
X303500Y2023500D01*
G01X314900D02*
Y2031500D01*
X317500Y2024833D01*
X320100Y2031500D01*
Y2023500D01*
G01X325500D02*
X324700Y2023633D01*
X324000Y2024167D01*
X323400Y2024967D01*
X323000Y2025900D01*
X322800Y2026967D01*
Y2028033D01*
X323000Y2029100D01*
X323400Y2030033D01*
X324000Y2030833D01*
X324700Y2031367D01*
X325500Y2031500D01*
X326300Y2031367D01*
X327000Y2030833D01*
X327600Y2030033D01*
X328000Y2029100D01*
X328200Y2028033D01*
Y2026967D01*
X328000Y2025900D01*
X327600Y2024967D01*
X327000Y2024167D01*
X326300Y2023633D01*
X325500Y2023500D01*
G01X331500D02*
Y2031500D01*
X334000D01*
X334800Y2031100D01*
X335300Y2030567D01*
X335500Y2029500D01*
X335300Y2028433D01*
X334700Y2027767D01*
X334000Y2027367D01*
X331500D01*
G01X334000D02*
X335500Y2023500D01*
G01X343500D02*
X339500D01*
Y2031500D01*
X343500D01*
G01X341900Y2027633D02*
X339500D01*
G01X357500Y2031500D02*
Y2023500D01*
G01X355200Y2031500D02*
X359800D01*
G01X363400Y2023500D02*
Y2031500D01*
G01X367600D02*
Y2023500D01*
G01Y2027500D02*
X363400D01*
G01X371000Y2023500D02*
X373500Y2031500D01*
X376000Y2023500D01*
G01X375100Y2026300D02*
X371900D01*
G01X379200Y2023500D02*
Y2031500D01*
X383800Y2023500D01*
Y2031500D01*
G01X397300Y2023500D02*
X397500Y2025233D01*
X397800Y2026700D01*
X398200Y2028033D01*
X398700Y2029500D01*
X399500Y2031500D01*
X395500D01*
G01X405500D02*
X404700Y2031233D01*
X404100Y2030567D01*
X403700Y2029767D01*
X403400Y2028700D01*
X403300Y2027500D01*
X403400Y2026300D01*
X403700Y2025233D01*
X404100Y2024433D01*
X404700Y2023767D01*
X405500Y2023500D01*
X406300Y2023767D01*
X406900Y2024433D01*
X407300Y2025233D01*
X407600Y2026300D01*
X407700Y2027500D01*
X407600Y2028700D01*
X407300Y2029767D01*
X406900Y2030567D01*
X406300Y2031233D01*
X405500Y2031500D01*
G01X418900Y2023500D02*
Y2031500D01*
X421500Y2024833D01*
X424100Y2031500D01*
Y2023500D01*
G01X428300Y2031500D02*
X430700D01*
G01X429500D02*
Y2023500D01*
G01X428300D02*
X430700D01*
G01X435500Y2031500D02*
Y2023500D01*
X439500D01*
G01X445500Y2023233D02*
X445300Y2023367D01*
Y2023633D01*
X445500Y2023767D01*
X445700Y2023633D01*
Y2023367D01*
X445500Y2023233D01*
G01X467200Y2023500D02*
Y2031500D01*
X471800Y2023500D01*
Y2031500D01*
G01X477500Y2023500D02*
X476700Y2023633D01*
X476000Y2024167D01*
X475400Y2024967D01*
X475000Y2025900D01*
X474800Y2026967D01*
Y2028033D01*
X475000Y2029100D01*
X475400Y2030033D01*
X476000Y2030833D01*
X476700Y2031367D01*
X477500Y2031500D01*
X478300Y2031367D01*
X479000Y2030833D01*
X479600Y2030033D01*
X480000Y2029100D01*
X480200Y2028033D01*
Y2026967D01*
X480000Y2025900D01*
X479600Y2024967D01*
X479000Y2024167D01*
X478300Y2023633D01*
X477500Y2023500D01*
G01X483200D02*
Y2031500D01*
X487800Y2023500D01*
Y2031500D01*
G01X492200Y2026167D02*
X494800D01*
G01X499600Y2023500D02*
Y2031500D01*
X503400D01*
G01X502000Y2027633D02*
X499600D01*
G01X507300Y2031500D02*
Y2025767D01*
X507700Y2024566D01*
X508500Y2023767D01*
X509500Y2023500D01*
X510500Y2023767D01*
X511300Y2024566D01*
X511700Y2025767D01*
Y2031500D01*
G01X515200Y2023500D02*
Y2031500D01*
X519800Y2023500D01*
Y2031500D01*
G01X527700Y2030833D02*
X527100Y2031233D01*
X526400Y2031500D01*
X525600D01*
X524700Y2031100D01*
X524000Y2030433D01*
X523500Y2029633D01*
X523100Y2028300D01*
X523000Y2027100D01*
X523200Y2025900D01*
X523500Y2025100D01*
X524100Y2024300D01*
X524800Y2023767D01*
X525500Y2023500D01*
X526200D01*
X526900Y2023767D01*
X527500Y2024167D01*
X528000Y2024700D01*
G01X533500Y2031500D02*
Y2023500D01*
G01X531200Y2031500D02*
X535800D01*
G01X540300D02*
X542700D01*
G01X541500D02*
Y2023500D01*
G01X540300D02*
X542700D01*
G01X549500D02*
X548700Y2023633D01*
X548000Y2024167D01*
X547400Y2024967D01*
X547000Y2025900D01*
X546800Y2026967D01*
Y2028033D01*
X547000Y2029100D01*
X547400Y2030033D01*
X548000Y2030833D01*
X548700Y2031367D01*
X549500Y2031500D01*
X550300Y2031367D01*
X551000Y2030833D01*
X551600Y2030033D01*
X552000Y2029100D01*
X552200Y2028033D01*
Y2026967D01*
X552000Y2025900D01*
X551600Y2024967D01*
X551000Y2024167D01*
X550300Y2023633D01*
X549500Y2023500D01*
G01X555200D02*
Y2031500D01*
X559800Y2023500D01*
Y2031500D01*
G01X563000Y2023500D02*
X565500Y2031500D01*
X568000Y2023500D01*
G01X567100Y2026300D02*
X563900D01*
G01X571500Y2031500D02*
Y2023500D01*
X575500D01*
G01X587500D02*
Y2031500D01*
X589900D01*
X590700Y2031100D01*
X591300Y2030167D01*
X591500Y2029100D01*
X591300Y2028033D01*
X590800Y2027233D01*
X589900Y2026833D01*
X587500D01*
G01X595000Y2023500D02*
X597500Y2031500D01*
X600000Y2023500D01*
G01X599100Y2026300D02*
X595900D01*
G01X603300Y2023500D02*
Y2031500D01*
X605300D01*
X606100Y2031100D01*
X606700Y2030567D01*
X607200Y2029767D01*
X607600Y2028833D01*
X607700Y2027500D01*
X607600Y2026167D01*
X607200Y2025233D01*
X606700Y2024433D01*
X606100Y2023900D01*
X605300Y2023500D01*
X603300D01*
G01X620300Y2031500D02*
X622700D01*
G01X621500D02*
Y2023500D01*
G01X620300D02*
X622700D01*
G01X627400Y2024566D02*
X628200Y2023900D01*
X629100Y2023500D01*
X629900D01*
X630700Y2023900D01*
X631300Y2024566D01*
X631600Y2025500D01*
X631400Y2026433D01*
X630900Y2027233D01*
X630000Y2027767D01*
X628800Y2028033D01*
X628100Y2028567D01*
X627800Y2029500D01*
X628000Y2030433D01*
X628500Y2031100D01*
X629200Y2031500D01*
X629900D01*
X630600Y2031233D01*
X631200Y2030567D01*
G01X643500Y2023500D02*
Y2031500D01*
X646000D01*
X646800Y2031100D01*
X647300Y2030567D01*
X647500Y2029500D01*
X647300Y2028433D01*
X646700Y2027767D01*
X646000Y2027367D01*
X643500D01*
G01X646000D02*
X647500Y2023500D01*
G01X655500D02*
X651500D01*
Y2031500D01*
X655500D01*
G01X653900Y2027633D02*
X651500D01*
G01X661500Y2023500D02*
X660700Y2023633D01*
X660000Y2024167D01*
X659400Y2024967D01*
X659000Y2025900D01*
X658800Y2026967D01*
Y2028033D01*
X659000Y2029100D01*
X659400Y2030033D01*
X660000Y2030833D01*
X660700Y2031367D01*
X661500Y2031500D01*
X662300Y2031367D01*
X663000Y2030833D01*
X663600Y2030033D01*
X664000Y2029100D01*
X664200Y2028033D01*
Y2026967D01*
X664000Y2025900D01*
X663600Y2024967D01*
X663000Y2024167D01*
X662300Y2023633D01*
X661500Y2023500D01*
G01X662300Y2025633D02*
X663500Y2023500D01*
G01X667300Y2031500D02*
Y2025767D01*
X667700Y2024566D01*
X668500Y2023767D01*
X669500Y2023500D01*
X670500Y2023767D01*
X671300Y2024566D01*
X671700Y2025767D01*
Y2031500D01*
G01X676300D02*
X678700D01*
G01X677500D02*
Y2023500D01*
G01X676300D02*
X678700D01*
G01X683500D02*
Y2031500D01*
X686000D01*
X686800Y2031100D01*
X687300Y2030567D01*
X687500Y2029500D01*
X687300Y2028433D01*
X686700Y2027767D01*
X686000Y2027367D01*
X683500D01*
G01X686000D02*
X687500Y2023500D01*
G01X695500D02*
X691500D01*
Y2031500D01*
X695500D01*
G01X693900Y2027633D02*
X691500D01*
G01X699300Y2023500D02*
Y2031500D01*
X701300D01*
X702100Y2031100D01*
X702700Y2030567D01*
X703200Y2029767D01*
X703600Y2028833D01*
X703700Y2027500D01*
X703600Y2026167D01*
X703200Y2025233D01*
X702700Y2024433D01*
X702100Y2023900D01*
X701300Y2023500D01*
X699300D01*
G01X717500Y2031500D02*
Y2023500D01*
G01X715200Y2031500D02*
X719800D01*
G01X725500Y2023500D02*
X724700Y2023633D01*
X724000Y2024167D01*
X723400Y2024967D01*
X723000Y2025900D01*
X722800Y2026967D01*
Y2028033D01*
X723000Y2029100D01*
X723400Y2030033D01*
X724000Y2030833D01*
X724700Y2031367D01*
X725500Y2031500D01*
X726300Y2031367D01*
X727000Y2030833D01*
X727600Y2030033D01*
X728000Y2029100D01*
X728200Y2028033D01*
Y2026967D01*
X728000Y2025900D01*
X727600Y2024967D01*
X727000Y2024167D01*
X726300Y2023633D01*
X725500Y2023500D01*
G01X742300Y2027767D02*
X742700Y2028167D01*
X743000Y2028833D01*
X743200Y2029767D01*
X743000Y2030567D01*
X742600Y2031100D01*
X741900Y2031500D01*
X739200D01*
Y2023500D01*
X742500D01*
X743200Y2024033D01*
X743600Y2024833D01*
X743800Y2025767D01*
X743600Y2026700D01*
X743000Y2027500D01*
X742300Y2027767D01*
X739200D01*
G01X751500Y2023500D02*
X747500D01*
Y2031500D01*
X751500D01*
G01X749900Y2027633D02*
X747500D01*
G01X763000Y2023500D02*
X765500Y2031500D01*
X768000Y2023500D01*
G01X767100Y2026300D02*
X763900D01*
G01X771300Y2023500D02*
Y2031500D01*
X773300D01*
X774100Y2031100D01*
X774700Y2030567D01*
X775200Y2029767D01*
X775600Y2028833D01*
X775700Y2027500D01*
X775600Y2026167D01*
X775200Y2025233D01*
X774700Y2024433D01*
X774100Y2023900D01*
X773300Y2023500D01*
X771300D01*
G01X779300D02*
Y2031500D01*
X781300D01*
X782100Y2031100D01*
X782700Y2030567D01*
X783200Y2029767D01*
X783600Y2028833D01*
X783700Y2027500D01*
X783600Y2026167D01*
X783200Y2025233D01*
X782700Y2024433D01*
X782100Y2023900D01*
X781300Y2023500D01*
X779300D01*
G01X791500D02*
X787500D01*
Y2031500D01*
X791500D01*
G01X789900Y2027633D02*
X787500D01*
G01X795300Y2023500D02*
Y2031500D01*
X797300D01*
X798100Y2031100D01*
X798700Y2030567D01*
X799200Y2029767D01*
X799600Y2028833D01*
X799700Y2027500D01*
X799600Y2026167D01*
X799200Y2025233D01*
X798700Y2024433D01*
X798100Y2023900D01*
X797300Y2023500D01*
X795300D01*
G01X813500Y2031500D02*
Y2023500D01*
G01X811200Y2031500D02*
X815800D01*
G01X821500Y2023500D02*
X820700Y2023633D01*
X820000Y2024167D01*
X819400Y2024967D01*
X819000Y2025900D01*
X818800Y2026967D01*
Y2028033D01*
X819000Y2029100D01*
X819400Y2030033D01*
X820000Y2030833D01*
X820700Y2031367D01*
X821500Y2031500D01*
X822300Y2031367D01*
X823000Y2030833D01*
X823600Y2030033D01*
X824000Y2029100D01*
X824200Y2028033D01*
Y2026967D01*
X824000Y2025900D01*
X823600Y2024967D01*
X823000Y2024167D01*
X822300Y2023633D01*
X821500Y2023500D01*
G01X835500D02*
Y2031500D01*
X837900D01*
X838700Y2031100D01*
X839300Y2030167D01*
X839500Y2029100D01*
X839300Y2028033D01*
X838800Y2027233D01*
X837900Y2026833D01*
X835500D01*
G01X843500Y2023500D02*
Y2031500D01*
X846000D01*
X846800Y2031100D01*
X847300Y2030567D01*
X847500Y2029500D01*
X847300Y2028433D01*
X846700Y2027767D01*
X846000Y2027367D01*
X843500D01*
G01X846000D02*
X847500Y2023500D01*
G01X855500D02*
X851500D01*
Y2031500D01*
X855500D01*
G01X853900Y2027633D02*
X851500D01*
G01X859000Y2031500D02*
X861500Y2023500D01*
X864000Y2031500D01*
G01X871500Y2023500D02*
X867500D01*
Y2031500D01*
X871500D01*
G01X869900Y2027633D02*
X867500D01*
G01X875200Y2023500D02*
Y2031500D01*
X879800Y2023500D01*
Y2031500D01*
G01X885500D02*
Y2023500D01*
G01X883200Y2031500D02*
X887800D01*
G01X901500D02*
Y2023500D01*
G01X899200Y2031500D02*
X903800D01*
G01X907400Y2023500D02*
Y2031500D01*
G01X911600D02*
Y2023500D01*
G01Y2027500D02*
X907400D01*
G01X919500Y2023500D02*
X915500D01*
Y2031500D01*
X919500D01*
G01X917900Y2027633D02*
X915500D01*
G01X931500Y2023500D02*
Y2031500D01*
X933900D01*
X934700Y2031100D01*
X935300Y2030167D01*
X935500Y2029100D01*
X935300Y2028033D01*
X934800Y2027233D01*
X933900Y2026833D01*
X931500D01*
G01X941500Y2023500D02*
X940700Y2023633D01*
X940000Y2024167D01*
X939400Y2024967D01*
X939000Y2025900D01*
X938800Y2026967D01*
Y2028033D01*
X939000Y2029100D01*
X939400Y2030033D01*
X940000Y2030833D01*
X940700Y2031367D01*
X941500Y2031500D01*
X942300Y2031367D01*
X943000Y2030833D01*
X943600Y2030033D01*
X944000Y2029100D01*
X944200Y2028033D01*
Y2026967D01*
X944000Y2025900D01*
X943600Y2024967D01*
X943000Y2024167D01*
X942300Y2023633D01*
X941500Y2023500D01*
G01X949500Y2031500D02*
Y2023500D01*
G01X947200Y2031500D02*
X951800D01*
G01X959500Y2023500D02*
X955500D01*
Y2031500D01*
X959500D01*
G01X957900Y2027633D02*
X955500D01*
G01X963200Y2023500D02*
Y2031500D01*
X967800Y2023500D01*
Y2031500D01*
G01X973500D02*
Y2023500D01*
G01X971200Y2031500D02*
X975800D01*
G01X980300D02*
X982700D01*
G01X981500D02*
Y2023500D01*
G01X980300D02*
X982700D01*
G01X987000D02*
X989500Y2031500D01*
X992000Y2023500D01*
G01X991100Y2026300D02*
X987900D01*
G01X995500Y2031500D02*
Y2023500D01*
X999500D01*
G01X1011500D02*
Y2031500D01*
X1013900D01*
X1014700Y2031100D01*
X1015300Y2030167D01*
X1015500Y2029100D01*
X1015300Y2028033D01*
X1014800Y2027233D01*
X1013900Y2026833D01*
X1011500D01*
G01X1019300Y2031500D02*
Y2025767D01*
X1019700Y2024566D01*
X1020500Y2023767D01*
X1021500Y2023500D01*
X1022500Y2023767D01*
X1023300Y2024566D01*
X1023700Y2025767D01*
Y2031500D01*
G01X1027500D02*
Y2023500D01*
X1031500D01*
G01X1035500Y2031500D02*
Y2023500D01*
X1039500D01*
G01X1051000D02*
X1053500Y2031500D01*
X1056000Y2023500D01*
G01X1055100Y2026300D02*
X1051900D01*
G01X1058500Y2031500D02*
X1059900Y2023500D01*
X1061500Y2031500D01*
X1063100Y2023500D01*
X1064500Y2031500D01*
G01X1067000Y2023500D02*
X1069500Y2031500D01*
X1072000Y2023500D01*
G01X1071100Y2026300D02*
X1067900D01*
G01X1077500Y2023500D02*
Y2027100D01*
X1075500Y2031500D01*
G01X1079500D02*
X1077500Y2027100D01*
G01X1085500Y2023233D02*
X1085300Y2023367D01*
Y2023633D01*
X1085500Y2023767D01*
X1085700Y2023633D01*
Y2023367D01*
X1085500Y2023233D01*
G01X-124200Y2039433D02*
X-123500Y2038767D01*
X-122700Y2038500D01*
X-121900Y2038767D01*
X-121200Y2039566D01*
X-120700Y2040767D01*
X-120500Y2041967D01*
Y2043433D01*
X-120700Y2044633D01*
X-121200Y2045700D01*
X-121800Y2046233D01*
X-122500Y2046500D01*
X-123300Y2046233D01*
X-123900Y2045700D01*
X-124300Y2044900D01*
X-124500Y2043833D01*
X-124300Y2042900D01*
X-123800Y2041967D01*
X-123200Y2041433D01*
X-122500Y2041300D01*
X-121700Y2041566D01*
X-121100Y2042233D01*
X-120500Y2043433D01*
G01X-114500Y2038233D02*
X-114700Y2038367D01*
Y2038633D01*
X-114500Y2038767D01*
X-114300Y2038633D01*
Y2038367D01*
X-114500Y2038233D01*
G01X-109000Y2038500D02*
X-106500Y2046500D01*
X-104000Y2038500D01*
G01X-104900Y2041300D02*
X-108100D01*
G01X-100800Y2038500D02*
Y2046500D01*
X-96200Y2038500D01*
Y2046500D01*
G01X-90500Y2038500D02*
Y2042100D01*
X-92500Y2046500D01*
G01X-88500D02*
X-90500Y2042100D01*
G01X-76600Y2039566D02*
X-75800Y2038900D01*
X-74900Y2038500D01*
X-74100D01*
X-73300Y2038900D01*
X-72700Y2039566D01*
X-72400Y2040500D01*
X-72600Y2041433D01*
X-73100Y2042233D01*
X-74000Y2042767D01*
X-75200Y2043033D01*
X-75900Y2043567D01*
X-76200Y2044500D01*
X-76000Y2045433D01*
X-75500Y2046100D01*
X-74800Y2046500D01*
X-74100D01*
X-73400Y2046233D01*
X-72800Y2045567D01*
G01X-68500Y2038500D02*
Y2046500D01*
X-66100D01*
X-65300Y2046100D01*
X-64700Y2045167D01*
X-64500Y2044100D01*
X-64700Y2043033D01*
X-65200Y2042233D01*
X-66100Y2041833D01*
X-68500D01*
G01X-56500Y2038500D02*
X-60500D01*
Y2046500D01*
X-56500D01*
G01X-58100Y2042633D02*
X-60500D01*
G01X-48300Y2045833D02*
X-48900Y2046233D01*
X-49600Y2046500D01*
X-50400D01*
X-51300Y2046100D01*
X-52000Y2045433D01*
X-52500Y2044633D01*
X-52900Y2043300D01*
X-53000Y2042100D01*
X-52800Y2040900D01*
X-52500Y2040100D01*
X-51900Y2039300D01*
X-51200Y2038767D01*
X-50500Y2038500D01*
X-49800D01*
X-49100Y2038767D01*
X-48500Y2039167D01*
X-48000Y2039700D01*
G01X-43700Y2046500D02*
X-41300D01*
G01X-42500D02*
Y2038500D01*
G01X-43700D02*
X-41300D01*
G01X-37000D02*
X-34500Y2046500D01*
X-32000Y2038500D01*
G01X-32900Y2041300D02*
X-36100D01*
G01X-28500Y2046500D02*
Y2038500D01*
X-24500D01*
G01X-12700D02*
Y2046500D01*
X-10700D01*
X-9900Y2046100D01*
X-9300Y2045567D01*
X-8800Y2044767D01*
X-8400Y2043833D01*
X-8300Y2042500D01*
X-8400Y2041167D01*
X-8800Y2040233D01*
X-9300Y2039433D01*
X-9900Y2038900D01*
X-10700Y2038500D01*
X-12700D01*
G01X-4500D02*
Y2046500D01*
X-2000D01*
X-1200Y2046100D01*
X-700Y2045567D01*
X-500Y2044500D01*
X-700Y2043433D01*
X-1300Y2042767D01*
X-2000Y2042367D01*
X-4500D01*
G01X-2000D02*
X-500Y2038500D01*
G01X4300Y2046500D02*
X6700D01*
G01X5500D02*
Y2038500D01*
G01X4300D02*
X6700D01*
G01X11500Y2046500D02*
Y2038500D01*
X15500D01*
G01X19500Y2046500D02*
Y2038500D01*
X23500D01*
G01X35000D02*
X37500Y2046500D01*
X40000Y2038500D01*
G01X39100Y2041300D02*
X35900D01*
G01X43200Y2038500D02*
Y2046500D01*
X47800Y2038500D01*
Y2046500D01*
G01X51300Y2038500D02*
Y2046500D01*
X53300D01*
X54100Y2046100D01*
X54700Y2045567D01*
X55200Y2044767D01*
X55600Y2043833D01*
X55700Y2042500D01*
X55600Y2041167D01*
X55200Y2040233D01*
X54700Y2039433D01*
X54100Y2038900D01*
X53300Y2038500D01*
X51300D01*
G01X67400Y2039566D02*
X68200Y2038900D01*
X69100Y2038500D01*
X69900D01*
X70700Y2038900D01*
X71300Y2039566D01*
X71600Y2040500D01*
X71400Y2041433D01*
X70900Y2042233D01*
X70000Y2042767D01*
X68800Y2043033D01*
X68100Y2043567D01*
X67800Y2044500D01*
X68000Y2045433D01*
X68500Y2046100D01*
X69200Y2046500D01*
X69900D01*
X70600Y2046233D01*
X71200Y2045567D01*
G01X77500Y2046500D02*
Y2038500D01*
G01X75200Y2046500D02*
X79800D01*
G01X83000Y2038500D02*
X85500Y2046500D01*
X88000Y2038500D01*
G01X87100Y2041300D02*
X83900D01*
G01X95700Y2045833D02*
X95100Y2046233D01*
X94400Y2046500D01*
X93600D01*
X92700Y2046100D01*
X92000Y2045433D01*
X91500Y2044633D01*
X91100Y2043300D01*
X91000Y2042100D01*
X91200Y2040900D01*
X91500Y2040100D01*
X92100Y2039300D01*
X92800Y2038767D01*
X93500Y2038500D01*
X94200D01*
X94900Y2038767D01*
X95500Y2039167D01*
X96000Y2039700D01*
G01X99300Y2038500D02*
Y2046500D01*
G01X103100D02*
X99300Y2041566D01*
G01X103700Y2038500D02*
X101000Y2043833D01*
G01X111500Y2038500D02*
X107500D01*
Y2046500D01*
X111500D01*
G01X109900Y2042633D02*
X107500D01*
G01X115300Y2038500D02*
Y2046500D01*
X117300D01*
X118100Y2046100D01*
X118700Y2045567D01*
X119200Y2044767D01*
X119600Y2043833D01*
X119700Y2042500D01*
X119600Y2041167D01*
X119200Y2040233D01*
X118700Y2039433D01*
X118100Y2038900D01*
X117300Y2038500D01*
X115300D01*
G01X131400D02*
Y2046500D01*
G01X135600D02*
Y2038500D01*
G01Y2042500D02*
X131400D01*
G01X141500Y2038500D02*
X140700Y2038633D01*
X140000Y2039167D01*
X139400Y2039967D01*
X139000Y2040900D01*
X138800Y2041967D01*
Y2043033D01*
X139000Y2044100D01*
X139400Y2045033D01*
X140000Y2045833D01*
X140700Y2046367D01*
X141500Y2046500D01*
X142300Y2046367D01*
X143000Y2045833D01*
X143600Y2045033D01*
X144000Y2044100D01*
X144200Y2043033D01*
Y2041967D01*
X144000Y2040900D01*
X143600Y2039967D01*
X143000Y2039167D01*
X142300Y2038633D01*
X141500Y2038500D01*
G01X147500Y2046500D02*
Y2038500D01*
X151500D01*
G01X159500D02*
X155500D01*
Y2046500D01*
X159500D01*
G01X157900Y2042633D02*
X155500D01*
G01X171500Y2038500D02*
Y2046500D01*
X173900D01*
X174700Y2046100D01*
X175300Y2045167D01*
X175500Y2044100D01*
X175300Y2043033D01*
X174800Y2042233D01*
X173900Y2041833D01*
X171500D01*
G01X179500Y2046500D02*
Y2038500D01*
X183500D01*
G01X191500D02*
X187500D01*
Y2046500D01*
X191500D01*
G01X189900Y2042633D02*
X187500D01*
G01X195000Y2038500D02*
X197500Y2046500D01*
X200000Y2038500D01*
G01X199100Y2041300D02*
X195900D01*
G01X203400Y2039566D02*
X204200Y2038900D01*
X205100Y2038500D01*
X205900D01*
X206700Y2038900D01*
X207300Y2039566D01*
X207600Y2040500D01*
X207400Y2041433D01*
X206900Y2042233D01*
X206000Y2042767D01*
X204800Y2043033D01*
X204100Y2043567D01*
X203800Y2044500D01*
X204000Y2045433D01*
X204500Y2046100D01*
X205200Y2046500D01*
X205900D01*
X206600Y2046233D01*
X207200Y2045567D01*
G01X215500Y2038500D02*
X211500D01*
Y2046500D01*
X215500D01*
G01X213900Y2042633D02*
X211500D01*
G01X227600Y2038500D02*
Y2046500D01*
X231400D01*
G01X230000Y2042633D02*
X227600D01*
G01X237500Y2038500D02*
X236700Y2038633D01*
X236000Y2039167D01*
X235400Y2039967D01*
X235000Y2040900D01*
X234800Y2041967D01*
Y2043033D01*
X235000Y2044100D01*
X235400Y2045033D01*
X236000Y2045833D01*
X236700Y2046367D01*
X237500Y2046500D01*
X238300Y2046367D01*
X239000Y2045833D01*
X239600Y2045033D01*
X240000Y2044100D01*
X240200Y2043033D01*
Y2041967D01*
X240000Y2040900D01*
X239600Y2039967D01*
X239000Y2039167D01*
X238300Y2038633D01*
X237500Y2038500D01*
G01X243500Y2046500D02*
Y2038500D01*
X247500D01*
G01X251500Y2046500D02*
Y2038500D01*
X255500D01*
G01X261500D02*
X260700Y2038633D01*
X260000Y2039167D01*
X259400Y2039967D01*
X259000Y2040900D01*
X258800Y2041967D01*
Y2043033D01*
X259000Y2044100D01*
X259400Y2045033D01*
X260000Y2045833D01*
X260700Y2046367D01*
X261500Y2046500D01*
X262300Y2046367D01*
X263000Y2045833D01*
X263600Y2045033D01*
X264000Y2044100D01*
X264200Y2043033D01*
Y2041967D01*
X264000Y2040900D01*
X263600Y2039967D01*
X263000Y2039167D01*
X262300Y2038633D01*
X261500Y2038500D01*
G01X266500Y2046500D02*
X267900Y2038500D01*
X269500Y2046500D01*
X271100Y2038500D01*
X272500Y2046500D01*
G01X285500Y2038500D02*
X284700Y2038633D01*
X284000Y2039167D01*
X283400Y2039967D01*
X283000Y2040900D01*
X282800Y2041967D01*
Y2043033D01*
X283000Y2044100D01*
X283400Y2045033D01*
X284000Y2045833D01*
X284700Y2046367D01*
X285500Y2046500D01*
X286300Y2046367D01*
X287000Y2045833D01*
X287600Y2045033D01*
X288000Y2044100D01*
X288200Y2043033D01*
Y2041967D01*
X288000Y2040900D01*
X287600Y2039967D01*
X287000Y2039167D01*
X286300Y2038633D01*
X285500Y2038500D01*
G01X291300Y2046500D02*
Y2040767D01*
X291700Y2039566D01*
X292500Y2038767D01*
X293500Y2038500D01*
X294500Y2038767D01*
X295300Y2039566D01*
X295700Y2040767D01*
Y2046500D01*
G01X301500D02*
Y2038500D01*
G01X299200Y2046500D02*
X303800D01*
G01X307500D02*
Y2038500D01*
X311500D01*
G01X316300Y2046500D02*
X318700D01*
G01X317500D02*
Y2038500D01*
G01X316300D02*
X318700D01*
G01X323200D02*
Y2046500D01*
X327800Y2038500D01*
Y2046500D01*
G01X335500Y2038500D02*
X331500D01*
Y2046500D01*
X335500D01*
G01X333900Y2042633D02*
X331500D01*
G01X341500Y2038233D02*
X341300Y2038367D01*
Y2038633D01*
X341500Y2038767D01*
X341700Y2038633D01*
Y2038367D01*
X341500Y2038233D01*
G01X355500Y2038500D02*
Y2046500D01*
X357900D01*
X358700Y2046100D01*
X359300Y2045167D01*
X359500Y2044100D01*
X359300Y2043033D01*
X358800Y2042233D01*
X357900Y2041833D01*
X355500D01*
G01X365500Y2046500D02*
Y2038500D01*
G01X363200Y2046500D02*
X367800D01*
G01X371400Y2038500D02*
Y2046500D01*
G01X375600D02*
Y2038500D01*
G01Y2042500D02*
X371400D01*
G01X389500Y2046500D02*
Y2038500D01*
G01X387200Y2046500D02*
X391800D01*
G01X397500Y2038500D02*
X396700Y2038633D01*
X396000Y2039167D01*
X395400Y2039967D01*
X395000Y2040900D01*
X394800Y2041967D01*
Y2043033D01*
X395000Y2044100D01*
X395400Y2045033D01*
X396000Y2045833D01*
X396700Y2046367D01*
X397500Y2046500D01*
X398300Y2046367D01*
X399000Y2045833D01*
X399600Y2045033D01*
X400000Y2044100D01*
X400200Y2043033D01*
Y2041967D01*
X400000Y2040900D01*
X399600Y2039967D01*
X399000Y2039167D01*
X398300Y2038633D01*
X397500Y2038500D01*
G01X403500Y2046500D02*
Y2038500D01*
X407500D01*
G01X415500D02*
X411500D01*
Y2046500D01*
X415500D01*
G01X413900Y2042633D02*
X411500D01*
G01X419500Y2038500D02*
Y2046500D01*
X422000D01*
X422800Y2046100D01*
X423300Y2045567D01*
X423500Y2044500D01*
X423300Y2043433D01*
X422700Y2042767D01*
X422000Y2042367D01*
X419500D01*
G01X422000D02*
X423500Y2038500D01*
G01X427000D02*
X429500Y2046500D01*
X432000Y2038500D01*
G01X431100Y2041300D02*
X427900D01*
G01X435200Y2038500D02*
Y2046500D01*
X439800Y2038500D01*
Y2046500D01*
G01X447700Y2045833D02*
X447100Y2046233D01*
X446400Y2046500D01*
X445600D01*
X444700Y2046100D01*
X444000Y2045433D01*
X443500Y2044633D01*
X443100Y2043300D01*
X443000Y2042100D01*
X443200Y2040900D01*
X443500Y2040100D01*
X444100Y2039300D01*
X444800Y2038767D01*
X445500Y2038500D01*
X446200D01*
X446900Y2038767D01*
X447500Y2039167D01*
X448000Y2039700D01*
G01X455500Y2038500D02*
X451500D01*
Y2046500D01*
X455500D01*
G01X453900Y2042633D02*
X451500D01*
G01X469500Y2038233D02*
X469300Y2038367D01*
Y2038633D01*
X469500Y2038767D01*
X469700Y2038633D01*
Y2038367D01*
X469500Y2038233D01*
G01Y2041833D02*
X469300Y2041967D01*
Y2042233D01*
X469500Y2042367D01*
X469700Y2042233D01*
Y2041967D01*
X469500Y2041833D01*
G01X484400Y2041167D02*
X486800D01*
G01X485500Y2042900D02*
Y2039433D01*
G01X491700Y2038233D02*
X495300Y2046500D01*
G01X500200Y2041167D02*
X502800D01*
G01X507300Y2039700D02*
X507900Y2039033D01*
X508600Y2038633D01*
X509500Y2038500D01*
X510400Y2038767D01*
X511100Y2039300D01*
X511600Y2040233D01*
X511700Y2041300D01*
X511500Y2042367D01*
X511000Y2043033D01*
X510300Y2043567D01*
X509600Y2043700D01*
X508900Y2043567D01*
X508000Y2043033D01*
X508300Y2046500D01*
X511000D01*
G01X517000Y2035833D02*
X516000Y2037167D01*
X515500Y2038500D01*
Y2043833D01*
X516000Y2045167D01*
X517000Y2046500D01*
G01X522900Y2038500D02*
Y2046500D01*
X525500Y2039833D01*
X528100Y2046500D01*
Y2038500D01*
G01X532300Y2046500D02*
X534700D01*
G01X533500D02*
Y2038500D01*
G01X532300D02*
X534700D01*
G01X539500Y2046500D02*
Y2038500D01*
X543500D01*
G01X550000Y2035833D02*
X551000Y2037167D01*
X551500Y2038500D01*
Y2043833D01*
X551000Y2045167D01*
X550000Y2046500D01*
G01X557300Y2037033D02*
X557700Y2038767D01*
G01X571200Y2038500D02*
Y2046500D01*
X575800Y2038500D01*
Y2046500D01*
G01X579500Y2038500D02*
Y2046500D01*
X581900D01*
X582700Y2046100D01*
X583300Y2045167D01*
X583500Y2044100D01*
X583300Y2043033D01*
X582800Y2042233D01*
X581900Y2041833D01*
X579500D01*
G01X589500Y2046500D02*
Y2038500D01*
G01X587200Y2046500D02*
X591800D01*
G01X595400Y2038500D02*
Y2046500D01*
G01X599600D02*
Y2038500D01*
G01Y2042500D02*
X595400D01*
G01X613500Y2046500D02*
Y2038500D01*
G01X611200Y2046500D02*
X615800D01*
G01X621500Y2038500D02*
X620700Y2038633D01*
X620000Y2039167D01*
X619400Y2039967D01*
X619000Y2040900D01*
X618800Y2041967D01*
Y2043033D01*
X619000Y2044100D01*
X619400Y2045033D01*
X620000Y2045833D01*
X620700Y2046367D01*
X621500Y2046500D01*
X622300Y2046367D01*
X623000Y2045833D01*
X623600Y2045033D01*
X624000Y2044100D01*
X624200Y2043033D01*
Y2041967D01*
X624000Y2040900D01*
X623600Y2039967D01*
X623000Y2039167D01*
X622300Y2038633D01*
X621500Y2038500D01*
G01X627500Y2046500D02*
Y2038500D01*
X631500D01*
G01X639500D02*
X635500D01*
Y2046500D01*
X639500D01*
G01X637900Y2042633D02*
X635500D01*
G01X643500Y2038500D02*
Y2046500D01*
X646000D01*
X646800Y2046100D01*
X647300Y2045567D01*
X647500Y2044500D01*
X647300Y2043433D01*
X646700Y2042767D01*
X646000Y2042367D01*
X643500D01*
G01X646000D02*
X647500Y2038500D01*
G01X651000D02*
X653500Y2046500D01*
X656000Y2038500D01*
G01X655100Y2041300D02*
X651900D01*
G01X659200Y2038500D02*
Y2046500D01*
X663800Y2038500D01*
Y2046500D01*
G01X671700Y2045833D02*
X671100Y2046233D01*
X670400Y2046500D01*
X669600D01*
X668700Y2046100D01*
X668000Y2045433D01*
X667500Y2044633D01*
X667100Y2043300D01*
X667000Y2042100D01*
X667200Y2040900D01*
X667500Y2040100D01*
X668100Y2039300D01*
X668800Y2038767D01*
X669500Y2038500D01*
X670200D01*
X670900Y2038767D01*
X671500Y2039167D01*
X672000Y2039700D01*
G01X679500Y2038500D02*
X675500D01*
Y2046500D01*
X679500D01*
G01X677900Y2042633D02*
X675500D01*
G01X685500Y2038233D02*
X685300Y2038367D01*
Y2038633D01*
X685500Y2038767D01*
X685700Y2038633D01*
Y2038367D01*
X685500Y2038233D01*
G01Y2041833D02*
X685300Y2041967D01*
Y2042233D01*
X685500Y2042367D01*
X685700Y2042233D01*
Y2041967D01*
X685500Y2041833D01*
G01X700400Y2041167D02*
X702800D01*
G01X701500Y2042900D02*
Y2039433D01*
G01X707700Y2038233D02*
X711300Y2046500D01*
G01X716200Y2041167D02*
X718800D01*
G01X726700Y2038500D02*
Y2046500D01*
X723000Y2040767D01*
X728000D01*
G01X733000Y2035833D02*
X732000Y2037167D01*
X731500Y2038500D01*
Y2043833D01*
X732000Y2045167D01*
X733000Y2046500D01*
G01X738900Y2038500D02*
Y2046500D01*
X741500Y2039833D01*
X744100Y2046500D01*
Y2038500D01*
G01X748300Y2046500D02*
X750700D01*
G01X749500D02*
Y2038500D01*
G01X748300D02*
X750700D01*
G01X755500Y2046500D02*
Y2038500D01*
X759500D01*
G01X766000Y2035833D02*
X767000Y2037167D01*
X767500Y2038500D01*
Y2043833D01*
X767000Y2045167D01*
X766000Y2046500D01*
G01X773500Y2038233D02*
X773300Y2038367D01*
Y2038633D01*
X773500Y2038767D01*
X773700Y2038633D01*
Y2038367D01*
X773500Y2038233D01*
G01X-122500Y2053500D02*
X-121800Y2053633D01*
X-121000Y2054033D01*
X-120500Y2054700D01*
X-120300Y2055633D01*
X-120500Y2056566D01*
X-121100Y2057367D01*
X-122000Y2057767D01*
X-123000D01*
X-123600Y2058033D01*
X-124100Y2058700D01*
X-124300Y2059633D01*
X-124000Y2060567D01*
X-123300Y2061233D01*
X-122500Y2061500D01*
X-121700Y2061233D01*
X-121000Y2060567D01*
X-120700Y2059633D01*
X-120900Y2058700D01*
X-121400Y2058033D01*
X-122000Y2057767D01*
X-123000D01*
X-123900Y2057367D01*
X-124500Y2056566D01*
X-124700Y2055633D01*
X-124500Y2054700D01*
X-124000Y2054033D01*
X-123200Y2053633D01*
X-122500Y2053500D01*
G01X-114500Y2053233D02*
X-114700Y2053367D01*
Y2053633D01*
X-114500Y2053767D01*
X-114300Y2053633D01*
Y2053367D01*
X-114500Y2053233D01*
G01X-108800Y2053500D02*
Y2061500D01*
X-104200Y2053500D01*
Y2061500D01*
G01X-98500Y2053500D02*
X-99300Y2053633D01*
X-100000Y2054167D01*
X-100600Y2054967D01*
X-101000Y2055900D01*
X-101200Y2056967D01*
Y2058033D01*
X-101000Y2059100D01*
X-100600Y2060033D01*
X-100000Y2060833D01*
X-99300Y2061367D01*
X-98500Y2061500D01*
X-97700Y2061367D01*
X-97000Y2060833D01*
X-96400Y2060033D01*
X-96000Y2059100D01*
X-95800Y2058033D01*
Y2056967D01*
X-96000Y2055900D01*
X-96400Y2054967D01*
X-97000Y2054167D01*
X-97700Y2053633D01*
X-98500Y2053500D01*
G01X-90500Y2061500D02*
Y2053500D01*
G01X-92800Y2061500D02*
X-88200D01*
G01X-77000Y2053500D02*
X-74500Y2061500D01*
X-72000Y2053500D01*
G01X-72900Y2056300D02*
X-76100D01*
G01X-68500Y2061500D02*
Y2053500D01*
X-64500D01*
G01X-60500Y2061500D02*
Y2053500D01*
X-56500D01*
G01X-50500D02*
X-51300Y2053633D01*
X-52000Y2054167D01*
X-52600Y2054967D01*
X-53000Y2055900D01*
X-53200Y2056967D01*
Y2058033D01*
X-53000Y2059100D01*
X-52600Y2060033D01*
X-52000Y2060833D01*
X-51300Y2061367D01*
X-50500Y2061500D01*
X-49700Y2061367D01*
X-49000Y2060833D01*
X-48400Y2060033D01*
X-48000Y2059100D01*
X-47800Y2058033D01*
Y2056967D01*
X-48000Y2055900D01*
X-48400Y2054967D01*
X-49000Y2054167D01*
X-49700Y2053633D01*
X-50500Y2053500D01*
G01X-45500Y2061500D02*
X-44100Y2053500D01*
X-42500Y2061500D01*
X-40900Y2053500D01*
X-39500Y2061500D01*
G01X-25700Y2057767D02*
X-25300Y2058167D01*
X-25000Y2058833D01*
X-24800Y2059767D01*
X-25000Y2060567D01*
X-25400Y2061100D01*
X-26100Y2061500D01*
X-28800D01*
Y2053500D01*
X-25500D01*
X-24800Y2054033D01*
X-24400Y2054833D01*
X-24200Y2055767D01*
X-24400Y2056700D01*
X-25000Y2057500D01*
X-25700Y2057767D01*
X-28800D01*
G01X-20500Y2053500D02*
Y2061500D01*
X-18000D01*
X-17200Y2061100D01*
X-16700Y2060567D01*
X-16500Y2059500D01*
X-16700Y2058433D01*
X-17300Y2057767D01*
X-18000Y2057367D01*
X-20500D01*
G01X-18000D02*
X-16500Y2053500D01*
G01X-8500D02*
X-12500D01*
Y2061500D01*
X-8500D01*
G01X-10100Y2057633D02*
X-12500D01*
G01X-5000Y2053500D02*
X-2500Y2061500D01*
X0Y2053500D01*
G01X-900Y2056300D02*
X-4100D01*
G01X3300Y2053500D02*
Y2061500D01*
G01X7100D02*
X3300Y2056566D01*
G01X7700Y2053500D02*
X5000Y2058833D01*
G01X13500Y2053500D02*
X12700Y2053633D01*
X12000Y2054167D01*
X11400Y2054967D01*
X11000Y2055900D01*
X10800Y2056967D01*
Y2058033D01*
X11000Y2059100D01*
X11400Y2060033D01*
X12000Y2060833D01*
X12700Y2061367D01*
X13500Y2061500D01*
X14300Y2061367D01*
X15000Y2060833D01*
X15600Y2060033D01*
X16000Y2059100D01*
X16200Y2058033D01*
Y2056967D01*
X16000Y2055900D01*
X15600Y2054967D01*
X15000Y2054167D01*
X14300Y2053633D01*
X13500Y2053500D01*
G01X19300Y2061500D02*
Y2055767D01*
X19700Y2054566D01*
X20500Y2053767D01*
X21500Y2053500D01*
X22500Y2053767D01*
X23300Y2054566D01*
X23700Y2055767D01*
Y2061500D01*
G01X29500D02*
Y2053500D01*
G01X27200Y2061500D02*
X31800D01*
G01X43600Y2053500D02*
Y2061500D01*
X47400D01*
G01X46000Y2057633D02*
X43600D01*
G01X53500Y2053500D02*
X52700Y2053633D01*
X52000Y2054167D01*
X51400Y2054967D01*
X51000Y2055900D01*
X50800Y2056967D01*
Y2058033D01*
X51000Y2059100D01*
X51400Y2060033D01*
X52000Y2060833D01*
X52700Y2061367D01*
X53500Y2061500D01*
X54300Y2061367D01*
X55000Y2060833D01*
X55600Y2060033D01*
X56000Y2059100D01*
X56200Y2058033D01*
Y2056967D01*
X56000Y2055900D01*
X55600Y2054967D01*
X55000Y2054167D01*
X54300Y2053633D01*
X53500Y2053500D01*
G01X59500D02*
Y2061500D01*
X62000D01*
X62800Y2061100D01*
X63300Y2060567D01*
X63500Y2059500D01*
X63300Y2058433D01*
X62700Y2057767D01*
X62000Y2057367D01*
X59500D01*
G01X62000D02*
X63500Y2053500D01*
G01X75500Y2061500D02*
Y2053500D01*
X79500D01*
G01X83000D02*
X85500Y2061500D01*
X88000Y2053500D01*
G01X87100Y2056300D02*
X83900D01*
G01X91400Y2054566D02*
X92200Y2053900D01*
X93100Y2053500D01*
X93900D01*
X94700Y2053900D01*
X95300Y2054566D01*
X95600Y2055500D01*
X95400Y2056433D01*
X94900Y2057233D01*
X94000Y2057767D01*
X92800Y2058033D01*
X92100Y2058567D01*
X91800Y2059500D01*
X92000Y2060433D01*
X92500Y2061100D01*
X93200Y2061500D01*
X93900D01*
X94600Y2061233D01*
X95200Y2060567D01*
G01X103500Y2053500D02*
X99500D01*
Y2061500D01*
X103500D01*
G01X101900Y2057633D02*
X99500D01*
G01X107500Y2053500D02*
Y2061500D01*
X110000D01*
X110800Y2061100D01*
X111300Y2060567D01*
X111500Y2059500D01*
X111300Y2058433D01*
X110700Y2057767D01*
X110000Y2057367D01*
X107500D01*
G01X110000D02*
X111500Y2053500D01*
G01X123000Y2061500D02*
X125500Y2053500D01*
X128000Y2061500D01*
G01X132300D02*
X134700D01*
G01X133500D02*
Y2053500D01*
G01X132300D02*
X134700D01*
G01X139000D02*
X141500Y2061500D01*
X144000Y2053500D01*
G01X143100Y2056300D02*
X139900D01*
G01X155400Y2053500D02*
Y2061500D01*
G01X159600D02*
Y2053500D01*
G01Y2057500D02*
X155400D01*
G01X165500Y2053500D02*
X164700Y2053633D01*
X164000Y2054167D01*
X163400Y2054967D01*
X163000Y2055900D01*
X162800Y2056967D01*
Y2058033D01*
X163000Y2059100D01*
X163400Y2060033D01*
X164000Y2060833D01*
X164700Y2061367D01*
X165500Y2061500D01*
X166300Y2061367D01*
X167000Y2060833D01*
X167600Y2060033D01*
X168000Y2059100D01*
X168200Y2058033D01*
Y2056967D01*
X168000Y2055900D01*
X167600Y2054967D01*
X167000Y2054167D01*
X166300Y2053633D01*
X165500Y2053500D01*
G01X171500Y2061500D02*
Y2053500D01*
X175500D01*
G01X183500D02*
X179500D01*
Y2061500D01*
X183500D01*
G01X181900Y2057633D02*
X179500D01*
G01X189500Y2053233D02*
X189300Y2053367D01*
Y2053633D01*
X189500Y2053767D01*
X189700Y2053633D01*
Y2053367D01*
X189500Y2053233D01*
G01X-122700Y2068500D02*
X-122500Y2070233D01*
X-122200Y2071700D01*
X-121800Y2073033D01*
X-121300Y2074500D01*
X-120500Y2076500D01*
X-124500D01*
G01X-114500Y2068233D02*
X-114700Y2068367D01*
Y2068633D01*
X-114500Y2068767D01*
X-114300Y2068633D01*
Y2068367D01*
X-114500Y2068233D01*
G01X-108400Y2068500D02*
Y2076500D01*
X-104600D01*
G01X-106000Y2072633D02*
X-108400D01*
G01X-98500Y2068500D02*
X-99300Y2068633D01*
X-100000Y2069167D01*
X-100600Y2069967D01*
X-101000Y2070900D01*
X-101200Y2071967D01*
Y2073033D01*
X-101000Y2074100D01*
X-100600Y2075033D01*
X-100000Y2075833D01*
X-99300Y2076367D01*
X-98500Y2076500D01*
X-97700Y2076367D01*
X-97000Y2075833D01*
X-96400Y2075033D01*
X-96000Y2074100D01*
X-95800Y2073033D01*
Y2071967D01*
X-96000Y2070900D01*
X-96400Y2069967D01*
X-97000Y2069167D01*
X-97700Y2068633D01*
X-98500Y2068500D01*
G01X-92500D02*
Y2076500D01*
X-90000D01*
X-89200Y2076100D01*
X-88700Y2075567D01*
X-88500Y2074500D01*
X-88700Y2073433D01*
X-89300Y2072767D01*
X-90000Y2072367D01*
X-92500D01*
G01X-90000D02*
X-88500Y2068500D01*
G01X-74500D02*
Y2076500D01*
X-75700Y2074900D01*
G01Y2068500D02*
X-73300D01*
G01X-66500Y2076500D02*
X-67300Y2076233D01*
X-67900Y2075567D01*
X-68300Y2074767D01*
X-68600Y2073700D01*
X-68700Y2072500D01*
X-68600Y2071300D01*
X-68300Y2070233D01*
X-67900Y2069433D01*
X-67300Y2068767D01*
X-66500Y2068500D01*
X-65700Y2068767D01*
X-65100Y2069433D01*
X-64700Y2070233D01*
X-64400Y2071300D01*
X-64300Y2072500D01*
X-64400Y2073700D01*
X-64700Y2074767D01*
X-65100Y2075567D01*
X-65700Y2076233D01*
X-66500Y2076500D01*
G01X-61100Y2068500D02*
Y2076500D01*
X-58500Y2069833D01*
X-55900Y2076500D01*
Y2068500D01*
G01X-51700Y2076500D02*
X-49300D01*
G01X-50500D02*
Y2068500D01*
G01X-51700D02*
X-49300D01*
G01X-44500Y2076500D02*
Y2068500D01*
X-40500D01*
G01X-36600Y2069566D02*
X-35800Y2068900D01*
X-34900Y2068500D01*
X-34100D01*
X-33300Y2068900D01*
X-32700Y2069566D01*
X-32400Y2070500D01*
X-32600Y2071433D01*
X-33100Y2072233D01*
X-34000Y2072767D01*
X-35200Y2073033D01*
X-35900Y2073567D01*
X-36200Y2074500D01*
X-36000Y2075433D01*
X-35500Y2076100D01*
X-34800Y2076500D01*
X-34100D01*
X-33400Y2076233D01*
X-32800Y2075567D01*
G01X-21000Y2076500D02*
X-18500Y2068500D01*
X-16000Y2076500D01*
G01X-11700D02*
X-9300D01*
G01X-10500D02*
Y2068500D01*
G01X-11700D02*
X-9300D01*
G01X-5000D02*
X-2500Y2076500D01*
X0Y2068500D01*
G01X-900Y2071300D02*
X-4100D01*
G01X3400Y2069566D02*
X4200Y2068900D01*
X5100Y2068500D01*
X5900D01*
X6700Y2068900D01*
X7300Y2069566D01*
X7600Y2070500D01*
X7400Y2071433D01*
X6900Y2072233D01*
X6000Y2072767D01*
X4800Y2073033D01*
X4100Y2073567D01*
X3800Y2074500D01*
X4000Y2075433D01*
X4500Y2076100D01*
X5200Y2076500D01*
X5900D01*
X6600Y2076233D01*
X7200Y2075567D01*
G01X19300Y2076500D02*
Y2070767D01*
X19700Y2069566D01*
X20500Y2068767D01*
X21500Y2068500D01*
X22500Y2068767D01*
X23300Y2069566D01*
X23700Y2070767D01*
Y2076500D01*
G01X27400Y2069566D02*
X28200Y2068900D01*
X29100Y2068500D01*
X29900D01*
X30700Y2068900D01*
X31300Y2069566D01*
X31600Y2070500D01*
X31400Y2071433D01*
X30900Y2072233D01*
X30000Y2072767D01*
X28800Y2073033D01*
X28100Y2073567D01*
X27800Y2074500D01*
X28000Y2075433D01*
X28500Y2076100D01*
X29200Y2076500D01*
X29900D01*
X30600Y2076233D01*
X31200Y2075567D01*
G01X39500Y2068500D02*
X35500D01*
Y2076500D01*
X39500D01*
G01X37900Y2072633D02*
X35500D01*
G01X51800Y2069433D02*
X52500Y2068767D01*
X53300Y2068500D01*
X54100Y2068767D01*
X54800Y2069566D01*
X55300Y2070767D01*
X55500Y2071967D01*
Y2073433D01*
X55300Y2074633D01*
X54800Y2075700D01*
X54200Y2076233D01*
X53500Y2076500D01*
X52700Y2076233D01*
X52100Y2075700D01*
X51700Y2074900D01*
X51500Y2073833D01*
X51700Y2072900D01*
X52200Y2071967D01*
X52800Y2071433D01*
X53500Y2071300D01*
X54300Y2071566D01*
X54900Y2072233D01*
X55500Y2073433D01*
G01X61500Y2068233D02*
X61300Y2068367D01*
Y2068633D01*
X61500Y2068767D01*
X61700Y2068633D01*
Y2068367D01*
X61500Y2068233D01*
G01X69500Y2068500D02*
X70200Y2068633D01*
X71000Y2069033D01*
X71500Y2069700D01*
X71700Y2070633D01*
X71500Y2071566D01*
X70900Y2072367D01*
X70000Y2072767D01*
X69000D01*
X68400Y2073033D01*
X67900Y2073700D01*
X67700Y2074633D01*
X68000Y2075567D01*
X68700Y2076233D01*
X69500Y2076500D01*
X70300Y2076233D01*
X71000Y2075567D01*
X71300Y2074633D01*
X71100Y2073700D01*
X70600Y2073033D01*
X70000Y2072767D01*
X69000D01*
X68100Y2072367D01*
X67500Y2071566D01*
X67300Y2070633D01*
X67500Y2069700D01*
X68000Y2069033D01*
X68800Y2068633D01*
X69500Y2068500D01*
G01X74900D02*
Y2076500D01*
X77500Y2069833D01*
X80100Y2076500D01*
Y2068500D01*
G01X84300Y2076500D02*
X86700D01*
G01X85500D02*
Y2068500D01*
G01X84300D02*
X86700D01*
G01X91500Y2076500D02*
Y2068500D01*
X95500D01*
G01X99400Y2069566D02*
X100200Y2068900D01*
X101100Y2068500D01*
X101900D01*
X102700Y2068900D01*
X103300Y2069566D01*
X103600Y2070500D01*
X103400Y2071433D01*
X102900Y2072233D01*
X102000Y2072767D01*
X100800Y2073033D01*
X100100Y2073567D01*
X99800Y2074500D01*
X100000Y2075433D01*
X100500Y2076100D01*
X101200Y2076500D01*
X101900D01*
X102600Y2076233D01*
X103200Y2075567D01*
G01X115300Y2068500D02*
Y2076500D01*
X117300D01*
X118100Y2076100D01*
X118700Y2075567D01*
X119200Y2074767D01*
X119600Y2073833D01*
X119700Y2072500D01*
X119600Y2071167D01*
X119200Y2070233D01*
X118700Y2069433D01*
X118100Y2068900D01*
X117300Y2068500D01*
X115300D01*
G01X123500D02*
Y2076500D01*
X126000D01*
X126800Y2076100D01*
X127300Y2075567D01*
X127500Y2074500D01*
X127300Y2073433D01*
X126700Y2072767D01*
X126000Y2072367D01*
X123500D01*
G01X126000D02*
X127500Y2068500D01*
G01X132300Y2076500D02*
X134700D01*
G01X133500D02*
Y2068500D01*
G01X132300D02*
X134700D01*
G01X139500Y2076500D02*
Y2068500D01*
X143500D01*
G01X147500Y2076500D02*
Y2068500D01*
X151500D01*
G01X166300Y2072767D02*
X166700Y2073167D01*
X167000Y2073833D01*
X167200Y2074767D01*
X167000Y2075567D01*
X166600Y2076100D01*
X165900Y2076500D01*
X163200D01*
Y2068500D01*
X166500D01*
X167200Y2069033D01*
X167600Y2069833D01*
X167800Y2070767D01*
X167600Y2071700D01*
X167000Y2072500D01*
X166300Y2072767D01*
X163200D01*
G01X172300Y2076500D02*
X174700D01*
G01X173500D02*
Y2068500D01*
G01X172300D02*
X174700D01*
G01X181500Y2076500D02*
Y2068500D01*
G01X179200Y2076500D02*
X183800D01*
G01X189500Y2068233D02*
X189300Y2068367D01*
Y2068633D01*
X189500Y2068767D01*
X189700Y2068633D01*
Y2068367D01*
X189500Y2068233D01*
G01X203600Y2068500D02*
Y2076500D01*
X207400D01*
G01X206000Y2072633D02*
X203600D01*
G01X213500Y2068500D02*
X212700Y2068633D01*
X212000Y2069167D01*
X211400Y2069967D01*
X211000Y2070900D01*
X210800Y2071967D01*
Y2073033D01*
X211000Y2074100D01*
X211400Y2075033D01*
X212000Y2075833D01*
X212700Y2076367D01*
X213500Y2076500D01*
X214300Y2076367D01*
X215000Y2075833D01*
X215600Y2075033D01*
X216000Y2074100D01*
X216200Y2073033D01*
Y2071967D01*
X216000Y2070900D01*
X215600Y2069967D01*
X215000Y2069167D01*
X214300Y2068633D01*
X213500Y2068500D01*
G01X219500D02*
Y2076500D01*
X222000D01*
X222800Y2076100D01*
X223300Y2075567D01*
X223500Y2074500D01*
X223300Y2073433D01*
X222700Y2072767D01*
X222000Y2072367D01*
X219500D01*
G01X222000D02*
X223500Y2068500D01*
G01X237500D02*
X238200Y2068633D01*
X239000Y2069033D01*
X239500Y2069700D01*
X239700Y2070633D01*
X239500Y2071566D01*
X238900Y2072367D01*
X238000Y2072767D01*
X237000D01*
X236400Y2073033D01*
X235900Y2073700D01*
X235700Y2074633D01*
X236000Y2075567D01*
X236700Y2076233D01*
X237500Y2076500D01*
X238300Y2076233D01*
X239000Y2075567D01*
X239300Y2074633D01*
X239100Y2073700D01*
X238600Y2073033D01*
X238000Y2072767D01*
X237000D01*
X236100Y2072367D01*
X235500Y2071566D01*
X235300Y2070633D01*
X235500Y2069700D01*
X236000Y2069033D01*
X236800Y2068633D01*
X237500Y2068500D01*
G01X242900D02*
Y2076500D01*
X245500Y2069833D01*
X248100Y2076500D01*
Y2068500D01*
G01X252300Y2076500D02*
X254700D01*
G01X253500D02*
Y2068500D01*
G01X252300D02*
X254700D01*
G01X259500Y2076500D02*
Y2068500D01*
X263500D01*
G01X267400Y2069566D02*
X268200Y2068900D01*
X269100Y2068500D01*
X269900D01*
X270700Y2068900D01*
X271300Y2069566D01*
X271600Y2070500D01*
X271400Y2071433D01*
X270900Y2072233D01*
X270000Y2072767D01*
X268800Y2073033D01*
X268100Y2073567D01*
X267800Y2074500D01*
X268000Y2075433D01*
X268500Y2076100D01*
X269200Y2076500D01*
X269900D01*
X270600Y2076233D01*
X271200Y2075567D01*
G01X283000Y2076500D02*
X285500Y2068500D01*
X288000Y2076500D01*
G01X292300D02*
X294700D01*
G01X293500D02*
Y2068500D01*
G01X292300D02*
X294700D01*
G01X299000D02*
X301500Y2076500D01*
X304000Y2068500D01*
G01X303100Y2071300D02*
X299900D01*
G01X307400Y2069566D02*
X308200Y2068900D01*
X309100Y2068500D01*
X309900D01*
X310700Y2068900D01*
X311300Y2069566D01*
X311600Y2070500D01*
X311400Y2071433D01*
X310900Y2072233D01*
X310000Y2072767D01*
X308800Y2073033D01*
X308100Y2073567D01*
X307800Y2074500D01*
X308000Y2075433D01*
X308500Y2076100D01*
X309200Y2076500D01*
X309900D01*
X310600Y2076233D01*
X311200Y2075567D01*
G01X323300Y2076500D02*
Y2070767D01*
X323700Y2069566D01*
X324500Y2068767D01*
X325500Y2068500D01*
X326500Y2068767D01*
X327300Y2069566D01*
X327700Y2070767D01*
Y2076500D01*
G01X331400Y2069566D02*
X332200Y2068900D01*
X333100Y2068500D01*
X333900D01*
X334700Y2068900D01*
X335300Y2069566D01*
X335600Y2070500D01*
X335400Y2071433D01*
X334900Y2072233D01*
X334000Y2072767D01*
X332800Y2073033D01*
X332100Y2073567D01*
X331800Y2074500D01*
X332000Y2075433D01*
X332500Y2076100D01*
X333200Y2076500D01*
X333900D01*
X334600Y2076233D01*
X335200Y2075567D01*
G01X343500Y2068500D02*
X339500D01*
Y2076500D01*
X343500D01*
G01X341900Y2072633D02*
X339500D01*
G01X357300Y2068500D02*
X357500Y2070233D01*
X357800Y2071700D01*
X358200Y2073033D01*
X358700Y2074500D01*
X359500Y2076500D01*
X355500D01*
G01X365500Y2068233D02*
X365300Y2068367D01*
Y2068633D01*
X365500Y2068767D01*
X365700Y2068633D01*
Y2068367D01*
X365500Y2068233D01*
G01X371800Y2069433D02*
X372500Y2068767D01*
X373300Y2068500D01*
X374100Y2068767D01*
X374800Y2069566D01*
X375300Y2070767D01*
X375500Y2071967D01*
Y2073433D01*
X375300Y2074633D01*
X374800Y2075700D01*
X374200Y2076233D01*
X373500Y2076500D01*
X372700Y2076233D01*
X372100Y2075700D01*
X371700Y2074900D01*
X371500Y2073833D01*
X371700Y2072900D01*
X372200Y2071967D01*
X372800Y2071433D01*
X373500Y2071300D01*
X374300Y2071566D01*
X374900Y2072233D01*
X375500Y2073433D01*
G01X378900Y2068500D02*
Y2076500D01*
X381500Y2069833D01*
X384100Y2076500D01*
Y2068500D01*
G01X388300Y2076500D02*
X390700D01*
G01X389500D02*
Y2068500D01*
G01X388300D02*
X390700D01*
G01X395500Y2076500D02*
Y2068500D01*
X399500D01*
G01X403400Y2069566D02*
X404200Y2068900D01*
X405100Y2068500D01*
X405900D01*
X406700Y2068900D01*
X407300Y2069566D01*
X407600Y2070500D01*
X407400Y2071433D01*
X406900Y2072233D01*
X406000Y2072767D01*
X404800Y2073033D01*
X404100Y2073567D01*
X403800Y2074500D01*
X404000Y2075433D01*
X404500Y2076100D01*
X405200Y2076500D01*
X405900D01*
X406600Y2076233D01*
X407200Y2075567D01*
G01X419300Y2068500D02*
Y2076500D01*
X421300D01*
X422100Y2076100D01*
X422700Y2075567D01*
X423200Y2074767D01*
X423600Y2073833D01*
X423700Y2072500D01*
X423600Y2071167D01*
X423200Y2070233D01*
X422700Y2069433D01*
X422100Y2068900D01*
X421300Y2068500D01*
X419300D01*
G01X427500D02*
Y2076500D01*
X430000D01*
X430800Y2076100D01*
X431300Y2075567D01*
X431500Y2074500D01*
X431300Y2073433D01*
X430700Y2072767D01*
X430000Y2072367D01*
X427500D01*
G01X430000D02*
X431500Y2068500D01*
G01X436300Y2076500D02*
X438700D01*
G01X437500D02*
Y2068500D01*
G01X436300D02*
X438700D01*
G01X443500Y2076500D02*
Y2068500D01*
X447500D01*
G01X451500Y2076500D02*
Y2068500D01*
X455500D01*
G01X470300Y2072767D02*
X470700Y2073167D01*
X471000Y2073833D01*
X471200Y2074767D01*
X471000Y2075567D01*
X470600Y2076100D01*
X469900Y2076500D01*
X467200D01*
Y2068500D01*
X470500D01*
X471200Y2069033D01*
X471600Y2069833D01*
X471800Y2070767D01*
X471600Y2071700D01*
X471000Y2072500D01*
X470300Y2072767D01*
X467200D01*
G01X476300Y2076500D02*
X478700D01*
G01X477500D02*
Y2068500D01*
G01X476300D02*
X478700D01*
G01X485500Y2076500D02*
Y2068500D01*
G01X483200Y2076500D02*
X487800D01*
G01X493500Y2068233D02*
X493300Y2068367D01*
Y2068633D01*
X493500Y2068767D01*
X493700Y2068633D01*
Y2068367D01*
X493500Y2068233D01*
G01X499600Y2068500D02*
Y2076500D01*
X503400D01*
G01X502000Y2072633D02*
X499600D01*
G01X509500Y2068500D02*
X508700Y2068633D01*
X508000Y2069167D01*
X507400Y2069967D01*
X507000Y2070900D01*
X506800Y2071967D01*
Y2073033D01*
X507000Y2074100D01*
X507400Y2075033D01*
X508000Y2075833D01*
X508700Y2076367D01*
X509500Y2076500D01*
X510300Y2076367D01*
X511000Y2075833D01*
X511600Y2075033D01*
X512000Y2074100D01*
X512200Y2073033D01*
Y2071967D01*
X512000Y2070900D01*
X511600Y2069967D01*
X511000Y2069167D01*
X510300Y2068633D01*
X509500Y2068500D01*
G01X515500D02*
Y2076500D01*
X518000D01*
X518800Y2076100D01*
X519300Y2075567D01*
X519500Y2074500D01*
X519300Y2073433D01*
X518700Y2072767D01*
X518000Y2072367D01*
X515500D01*
G01X518000D02*
X519500Y2068500D01*
G01X531600Y2075167D02*
X532200Y2075967D01*
X532900Y2076367D01*
X533700Y2076500D01*
X534700Y2076233D01*
X535400Y2075567D01*
X535600Y2074767D01*
X535500Y2073966D01*
X535100Y2073300D01*
X533100Y2071967D01*
X532200Y2071033D01*
X531600Y2069700D01*
X531400Y2068500D01*
X535600D01*
G01X541500Y2076500D02*
X540700Y2076233D01*
X540100Y2075567D01*
X539700Y2074767D01*
X539400Y2073700D01*
X539300Y2072500D01*
X539400Y2071300D01*
X539700Y2070233D01*
X540100Y2069433D01*
X540700Y2068767D01*
X541500Y2068500D01*
X542300Y2068767D01*
X542900Y2069433D01*
X543300Y2070233D01*
X543600Y2071300D01*
X543700Y2072500D01*
X543600Y2073700D01*
X543300Y2074767D01*
X542900Y2075567D01*
X542300Y2076233D01*
X541500Y2076500D01*
G01X546900Y2068500D02*
Y2076500D01*
X549500Y2069833D01*
X552100Y2076500D01*
Y2068500D01*
G01X556300Y2076500D02*
X558700D01*
G01X557500D02*
Y2068500D01*
G01X556300D02*
X558700D01*
G01X563500Y2076500D02*
Y2068500D01*
X567500D01*
G01X571400Y2069566D02*
X572200Y2068900D01*
X573100Y2068500D01*
X573900D01*
X574700Y2068900D01*
X575300Y2069566D01*
X575600Y2070500D01*
X575400Y2071433D01*
X574900Y2072233D01*
X574000Y2072767D01*
X572800Y2073033D01*
X572100Y2073567D01*
X571800Y2074500D01*
X572000Y2075433D01*
X572500Y2076100D01*
X573200Y2076500D01*
X573900D01*
X574600Y2076233D01*
X575200Y2075567D01*
G01X587000Y2076500D02*
X589500Y2068500D01*
X592000Y2076500D01*
G01X596300D02*
X598700D01*
G01X597500D02*
Y2068500D01*
G01X596300D02*
X598700D01*
G01X603000D02*
X605500Y2076500D01*
X608000Y2068500D01*
G01X607100Y2071300D02*
X603900D01*
G01X611400Y2069566D02*
X612200Y2068900D01*
X613100Y2068500D01*
X613900D01*
X614700Y2068900D01*
X615300Y2069566D01*
X615600Y2070500D01*
X615400Y2071433D01*
X614900Y2072233D01*
X614000Y2072767D01*
X612800Y2073033D01*
X612100Y2073567D01*
X611800Y2074500D01*
X612000Y2075433D01*
X612500Y2076100D01*
X613200Y2076500D01*
X613900D01*
X614600Y2076233D01*
X615200Y2075567D01*
G01X627300Y2076500D02*
Y2070767D01*
X627700Y2069566D01*
X628500Y2068767D01*
X629500Y2068500D01*
X630500Y2068767D01*
X631300Y2069566D01*
X631700Y2070767D01*
Y2076500D01*
G01X635400Y2069566D02*
X636200Y2068900D01*
X637100Y2068500D01*
X637900D01*
X638700Y2068900D01*
X639300Y2069566D01*
X639600Y2070500D01*
X639400Y2071433D01*
X638900Y2072233D01*
X638000Y2072767D01*
X636800Y2073033D01*
X636100Y2073567D01*
X635800Y2074500D01*
X636000Y2075433D01*
X636500Y2076100D01*
X637200Y2076500D01*
X637900D01*
X638600Y2076233D01*
X639200Y2075567D01*
G01X647500Y2068500D02*
X643500D01*
Y2076500D01*
X647500D01*
G01X645900Y2072633D02*
X643500D01*
G01X661500Y2068500D02*
Y2076500D01*
X660300Y2074900D01*
G01Y2068500D02*
X662700D01*
G01X667800Y2069433D02*
X668500Y2068767D01*
X669300Y2068500D01*
X670100Y2068767D01*
X670800Y2069566D01*
X671300Y2070767D01*
X671500Y2071967D01*
Y2073433D01*
X671300Y2074633D01*
X670800Y2075700D01*
X670200Y2076233D01*
X669500Y2076500D01*
X668700Y2076233D01*
X668100Y2075700D01*
X667700Y2074900D01*
X667500Y2073833D01*
X667700Y2072900D01*
X668200Y2071967D01*
X668800Y2071433D01*
X669500Y2071300D01*
X670300Y2071566D01*
X670900Y2072233D01*
X671500Y2073433D01*
G01X677500Y2068233D02*
X677300Y2068367D01*
Y2068633D01*
X677500Y2068767D01*
X677700Y2068633D01*
Y2068367D01*
X677500Y2068233D01*
G01X685300Y2068500D02*
X685500Y2070233D01*
X685800Y2071700D01*
X686200Y2073033D01*
X686700Y2074500D01*
X687500Y2076500D01*
X683500D01*
G01X690900Y2068500D02*
Y2076500D01*
X693500Y2069833D01*
X696100Y2076500D01*
Y2068500D01*
G01X700300Y2076500D02*
X702700D01*
G01X701500D02*
Y2068500D01*
G01X700300D02*
X702700D01*
G01X707500Y2076500D02*
Y2068500D01*
X711500D01*
G01X715400Y2069566D02*
X716200Y2068900D01*
X717100Y2068500D01*
X717900D01*
X718700Y2068900D01*
X719300Y2069566D01*
X719600Y2070500D01*
X719400Y2071433D01*
X718900Y2072233D01*
X718000Y2072767D01*
X716800Y2073033D01*
X716100Y2073567D01*
X715800Y2074500D01*
X716000Y2075433D01*
X716500Y2076100D01*
X717200Y2076500D01*
X717900D01*
X718600Y2076233D01*
X719200Y2075567D01*
G01X731300Y2068500D02*
Y2076500D01*
X733300D01*
X734100Y2076100D01*
X734700Y2075567D01*
X735200Y2074767D01*
X735600Y2073833D01*
X735700Y2072500D01*
X735600Y2071167D01*
X735200Y2070233D01*
X734700Y2069433D01*
X734100Y2068900D01*
X733300Y2068500D01*
X731300D01*
G01X739500D02*
Y2076500D01*
X742000D01*
X742800Y2076100D01*
X743300Y2075567D01*
X743500Y2074500D01*
X743300Y2073433D01*
X742700Y2072767D01*
X742000Y2072367D01*
X739500D01*
G01X742000D02*
X743500Y2068500D01*
G01X748300Y2076500D02*
X750700D01*
G01X749500D02*
Y2068500D01*
G01X748300D02*
X750700D01*
G01X755500Y2076500D02*
Y2068500D01*
X759500D01*
G01X763500Y2076500D02*
Y2068500D01*
X767500D01*
G01X782300Y2072767D02*
X782700Y2073167D01*
X783000Y2073833D01*
X783200Y2074767D01*
X783000Y2075567D01*
X782600Y2076100D01*
X781900Y2076500D01*
X779200D01*
Y2068500D01*
X782500D01*
X783200Y2069033D01*
X783600Y2069833D01*
X783800Y2070767D01*
X783600Y2071700D01*
X783000Y2072500D01*
X782300Y2072767D01*
X779200D01*
G01X788300Y2076500D02*
X790700D01*
G01X789500D02*
Y2068500D01*
G01X788300D02*
X790700D01*
G01X797500Y2076500D02*
Y2068500D01*
G01X795200Y2076500D02*
X799800D01*
G01X805500Y2068233D02*
X805300Y2068367D01*
Y2068633D01*
X805500Y2068767D01*
X805700Y2068633D01*
Y2068367D01*
X805500Y2068233D01*
G01X-124400Y2086833D02*
X-123700Y2087767D01*
X-123100Y2088300D01*
X-122300Y2088567D01*
X-121600Y2088300D01*
X-121100Y2087767D01*
X-120700Y2086967D01*
X-120600Y2086033D01*
X-120700Y2085233D01*
X-121100Y2084433D01*
X-121700Y2083767D01*
X-122400Y2083500D01*
X-123200Y2083767D01*
X-123900Y2084566D01*
X-124300Y2085767D01*
X-124400Y2087100D01*
X-124200Y2088833D01*
X-123900Y2089767D01*
X-123400Y2090700D01*
X-122700Y2091367D01*
X-122000Y2091500D01*
X-121300Y2091233D01*
X-120800Y2090567D01*
G01X-114500Y2083233D02*
X-114700Y2083367D01*
Y2083633D01*
X-114500Y2083767D01*
X-114300Y2083633D01*
Y2083367D01*
X-114500Y2083233D01*
G01X-108400Y2090167D02*
X-107800Y2090967D01*
X-107100Y2091367D01*
X-106300Y2091500D01*
X-105300Y2091233D01*
X-104600Y2090567D01*
X-104400Y2089767D01*
X-104500Y2088966D01*
X-104900Y2088300D01*
X-106900Y2086967D01*
X-107800Y2086033D01*
X-108400Y2084700D01*
X-108600Y2083500D01*
X-104400D01*
G01X-90500D02*
X-91300Y2083633D01*
X-92000Y2084167D01*
X-92600Y2084967D01*
X-93000Y2085900D01*
X-93200Y2086967D01*
Y2088033D01*
X-93000Y2089100D01*
X-92600Y2090033D01*
X-92000Y2090833D01*
X-91300Y2091367D01*
X-90500Y2091500D01*
X-89700Y2091367D01*
X-89000Y2090833D01*
X-88400Y2090033D01*
X-88000Y2089100D01*
X-87800Y2088033D01*
Y2086967D01*
X-88000Y2085900D01*
X-88400Y2084967D01*
X-89000Y2084167D01*
X-89700Y2083633D01*
X-90500Y2083500D01*
G01X-84700Y2091500D02*
Y2085767D01*
X-84300Y2084566D01*
X-83500Y2083767D01*
X-82500Y2083500D01*
X-81500Y2083767D01*
X-80700Y2084566D01*
X-80300Y2085767D01*
Y2091500D01*
G01X-74500D02*
Y2083500D01*
G01X-76800Y2091500D02*
X-72200D01*
G01X-68600Y2084566D02*
X-67800Y2083900D01*
X-66900Y2083500D01*
X-66100D01*
X-65300Y2083900D01*
X-64700Y2084566D01*
X-64400Y2085500D01*
X-64600Y2086433D01*
X-65100Y2087233D01*
X-66000Y2087767D01*
X-67200Y2088033D01*
X-67900Y2088567D01*
X-68200Y2089500D01*
X-68000Y2090433D01*
X-67500Y2091100D01*
X-66800Y2091500D01*
X-66100D01*
X-65400Y2091233D01*
X-64800Y2090567D01*
G01X-59700Y2091500D02*
X-57300D01*
G01X-58500D02*
Y2083500D01*
G01X-59700D02*
X-57300D01*
G01X-52700D02*
Y2091500D01*
X-50700D01*
X-49900Y2091100D01*
X-49300Y2090567D01*
X-48800Y2089767D01*
X-48400Y2088833D01*
X-48300Y2087500D01*
X-48400Y2086167D01*
X-48800Y2085233D01*
X-49300Y2084433D01*
X-49900Y2083900D01*
X-50700Y2083500D01*
X-52700D01*
G01X-40500D02*
X-44500D01*
Y2091500D01*
X-40500D01*
G01X-42100Y2087633D02*
X-44500D01*
G01X-25700Y2087767D02*
X-25300Y2088167D01*
X-25000Y2088833D01*
X-24800Y2089767D01*
X-25000Y2090567D01*
X-25400Y2091100D01*
X-26100Y2091500D01*
X-28800D01*
Y2083500D01*
X-25500D01*
X-24800Y2084033D01*
X-24400Y2084833D01*
X-24200Y2085767D01*
X-24400Y2086700D01*
X-25000Y2087500D01*
X-25700Y2087767D01*
X-28800D01*
G01X-18500Y2083500D02*
X-19300Y2083633D01*
X-20000Y2084167D01*
X-20600Y2084967D01*
X-21000Y2085900D01*
X-21200Y2086967D01*
Y2088033D01*
X-21000Y2089100D01*
X-20600Y2090033D01*
X-20000Y2090833D01*
X-19300Y2091367D01*
X-18500Y2091500D01*
X-17700Y2091367D01*
X-17000Y2090833D01*
X-16400Y2090033D01*
X-16000Y2089100D01*
X-15800Y2088033D01*
Y2086967D01*
X-16000Y2085900D01*
X-16400Y2084967D01*
X-17000Y2084167D01*
X-17700Y2083633D01*
X-18500Y2083500D01*
G01X-13000D02*
X-10500Y2091500D01*
X-8000Y2083500D01*
G01X-8900Y2086300D02*
X-12100D01*
G01X-4500Y2083500D02*
Y2091500D01*
X-2000D01*
X-1200Y2091100D01*
X-700Y2090567D01*
X-500Y2089500D01*
X-700Y2088433D01*
X-1300Y2087767D01*
X-2000Y2087367D01*
X-4500D01*
G01X-2000D02*
X-500Y2083500D01*
G01X3300D02*
Y2091500D01*
X5300D01*
X6100Y2091100D01*
X6700Y2090567D01*
X7200Y2089767D01*
X7600Y2088833D01*
X7700Y2087500D01*
X7600Y2086167D01*
X7200Y2085233D01*
X6700Y2084433D01*
X6100Y2083900D01*
X5300Y2083500D01*
X3300D01*
G01X21500D02*
X20700Y2083633D01*
X20000Y2084167D01*
X19400Y2084967D01*
X19000Y2085900D01*
X18800Y2086967D01*
Y2088033D01*
X19000Y2089100D01*
X19400Y2090033D01*
X20000Y2090833D01*
X20700Y2091367D01*
X21500Y2091500D01*
X22300Y2091367D01*
X23000Y2090833D01*
X23600Y2090033D01*
X24000Y2089100D01*
X24200Y2088033D01*
Y2086967D01*
X24000Y2085900D01*
X23600Y2084967D01*
X23000Y2084167D01*
X22300Y2083633D01*
X21500Y2083500D01*
G01X27300Y2091500D02*
Y2085767D01*
X27700Y2084566D01*
X28500Y2083767D01*
X29500Y2083500D01*
X30500Y2083767D01*
X31300Y2084566D01*
X31700Y2085767D01*
Y2091500D01*
G01X37500D02*
Y2083500D01*
G01X35200Y2091500D02*
X39800D01*
G01X43500D02*
Y2083500D01*
X47500D01*
G01X52300Y2091500D02*
X54700D01*
G01X53500D02*
Y2083500D01*
G01X52300D02*
X54700D01*
G01X59200D02*
Y2091500D01*
X63800Y2083500D01*
Y2091500D01*
G01X71500Y2083500D02*
X67500D01*
Y2091500D01*
X71500D01*
G01X69900Y2087633D02*
X67500D01*
G01X83600Y2083500D02*
Y2091500D01*
X87400D01*
G01X86000Y2087633D02*
X83600D01*
G01X93500Y2083500D02*
X92700Y2083633D01*
X92000Y2084167D01*
X91400Y2084967D01*
X91000Y2085900D01*
X90800Y2086967D01*
Y2088033D01*
X91000Y2089100D01*
X91400Y2090033D01*
X92000Y2090833D01*
X92700Y2091367D01*
X93500Y2091500D01*
X94300Y2091367D01*
X95000Y2090833D01*
X95600Y2090033D01*
X96000Y2089100D01*
X96200Y2088033D01*
Y2086967D01*
X96000Y2085900D01*
X95600Y2084967D01*
X95000Y2084167D01*
X94300Y2083633D01*
X93500Y2083500D01*
G01X99500Y2091500D02*
Y2083500D01*
X103500D01*
G01X107500Y2091500D02*
Y2083500D01*
X111500D01*
G01X117500D02*
X116700Y2083633D01*
X116000Y2084167D01*
X115400Y2084967D01*
X115000Y2085900D01*
X114800Y2086967D01*
Y2088033D01*
X115000Y2089100D01*
X115400Y2090033D01*
X116000Y2090833D01*
X116700Y2091367D01*
X117500Y2091500D01*
X118300Y2091367D01*
X119000Y2090833D01*
X119600Y2090033D01*
X120000Y2089100D01*
X120200Y2088033D01*
Y2086967D01*
X120000Y2085900D01*
X119600Y2084967D01*
X119000Y2084167D01*
X118300Y2083633D01*
X117500Y2083500D01*
G01X122500Y2091500D02*
X123900Y2083500D01*
X125500Y2091500D01*
X127100Y2083500D01*
X128500Y2091500D01*
G01X139500Y2083500D02*
Y2091500D01*
X141900D01*
X142700Y2091100D01*
X143300Y2090167D01*
X143500Y2089100D01*
X143300Y2088033D01*
X142800Y2087233D01*
X141900Y2086833D01*
X139500D01*
G01X151700Y2090833D02*
X151100Y2091233D01*
X150400Y2091500D01*
X149600D01*
X148700Y2091100D01*
X148000Y2090433D01*
X147500Y2089633D01*
X147100Y2088300D01*
X147000Y2087100D01*
X147200Y2085900D01*
X147500Y2085100D01*
X148100Y2084300D01*
X148800Y2083767D01*
X149500Y2083500D01*
X150200D01*
X150900Y2083767D01*
X151500Y2084167D01*
X152000Y2084700D01*
G01X158300Y2087767D02*
X158700Y2088167D01*
X159000Y2088833D01*
X159200Y2089767D01*
X159000Y2090567D01*
X158600Y2091100D01*
X157900Y2091500D01*
X155200D01*
Y2083500D01*
X158500D01*
X159200Y2084033D01*
X159600Y2084833D01*
X159800Y2085767D01*
X159600Y2086700D01*
X159000Y2087500D01*
X158300Y2087767D01*
X155200D01*
G01X171400Y2084566D02*
X172200Y2083900D01*
X173100Y2083500D01*
X173900D01*
X174700Y2083900D01*
X175300Y2084566D01*
X175600Y2085500D01*
X175400Y2086433D01*
X174900Y2087233D01*
X174000Y2087767D01*
X172800Y2088033D01*
X172100Y2088567D01*
X171800Y2089500D01*
X172000Y2090433D01*
X172500Y2091100D01*
X173200Y2091500D01*
X173900D01*
X174600Y2091233D01*
X175200Y2090567D01*
G01X179400Y2083500D02*
Y2091500D01*
G01X183600D02*
Y2083500D01*
G01Y2087500D02*
X179400D01*
G01X189500Y2083500D02*
X188700Y2083633D01*
X188000Y2084167D01*
X187400Y2084967D01*
X187000Y2085900D01*
X186800Y2086967D01*
Y2088033D01*
X187000Y2089100D01*
X187400Y2090033D01*
X188000Y2090833D01*
X188700Y2091367D01*
X189500Y2091500D01*
X190300Y2091367D01*
X191000Y2090833D01*
X191600Y2090033D01*
X192000Y2089100D01*
X192200Y2088033D01*
Y2086967D01*
X192000Y2085900D01*
X191600Y2084967D01*
X191000Y2084167D01*
X190300Y2083633D01*
X189500Y2083500D01*
G01X195500D02*
Y2091500D01*
X197900D01*
X198700Y2091100D01*
X199300Y2090167D01*
X199500Y2089100D01*
X199300Y2088033D01*
X198800Y2087233D01*
X197900Y2086833D01*
X195500D01*
G01X211500Y2083500D02*
Y2091500D01*
X213900D01*
X214700Y2091100D01*
X215300Y2090167D01*
X215500Y2089100D01*
X215300Y2088033D01*
X214800Y2087233D01*
X213900Y2086833D01*
X211500D01*
G01X219500Y2083500D02*
Y2091500D01*
X222000D01*
X222800Y2091100D01*
X223300Y2090567D01*
X223500Y2089500D01*
X223300Y2088433D01*
X222700Y2087767D01*
X222000Y2087367D01*
X219500D01*
G01X222000D02*
X223500Y2083500D01*
G01X231500D02*
X227500D01*
Y2091500D01*
X231500D01*
G01X229900Y2087633D02*
X227500D01*
G01X235600Y2083500D02*
Y2091500D01*
X239400D01*
G01X238000Y2087633D02*
X235600D01*
G01X247500Y2083500D02*
X243500D01*
Y2091500D01*
X247500D01*
G01X245900Y2087633D02*
X243500D01*
G01X251500Y2083500D02*
Y2091500D01*
X254000D01*
X254800Y2091100D01*
X255300Y2090567D01*
X255500Y2089500D01*
X255300Y2088433D01*
X254700Y2087767D01*
X254000Y2087367D01*
X251500D01*
G01X254000D02*
X255500Y2083500D01*
G01X263500D02*
X259500D01*
Y2091500D01*
X263500D01*
G01X261900Y2087633D02*
X259500D01*
G01X267200Y2083500D02*
Y2091500D01*
X271800Y2083500D01*
Y2091500D01*
G01X279700Y2090833D02*
X279100Y2091233D01*
X278400Y2091500D01*
X277600D01*
X276700Y2091100D01*
X276000Y2090433D01*
X275500Y2089633D01*
X275100Y2088300D01*
X275000Y2087100D01*
X275200Y2085900D01*
X275500Y2085100D01*
X276100Y2084300D01*
X276800Y2083767D01*
X277500Y2083500D01*
X278200D01*
X278900Y2083767D01*
X279500Y2084167D01*
X280000Y2084700D01*
G01X287500Y2083500D02*
X283500D01*
Y2091500D01*
X287500D01*
G01X285900Y2087633D02*
X283500D01*
G01X302300Y2087767D02*
X302700Y2088167D01*
X303000Y2088833D01*
X303200Y2089767D01*
X303000Y2090567D01*
X302600Y2091100D01*
X301900Y2091500D01*
X299200D01*
Y2083500D01*
X302500D01*
X303200Y2084033D01*
X303600Y2084833D01*
X303800Y2085767D01*
X303600Y2086700D01*
X303000Y2087500D01*
X302300Y2087767D01*
X299200D01*
G01X307300Y2091500D02*
Y2085767D01*
X307700Y2084566D01*
X308500Y2083767D01*
X309500Y2083500D01*
X310500Y2083767D01*
X311300Y2084566D01*
X311700Y2085767D01*
Y2091500D01*
G01X317500D02*
Y2083500D01*
G01X315200Y2091500D02*
X319800D01*
G01X335700Y2090833D02*
X335100Y2091233D01*
X334400Y2091500D01*
X333600D01*
X332700Y2091100D01*
X332000Y2090433D01*
X331500Y2089633D01*
X331100Y2088300D01*
X331000Y2087100D01*
X331200Y2085900D01*
X331500Y2085100D01*
X332100Y2084300D01*
X332800Y2083767D01*
X333500Y2083500D01*
X334200D01*
X334900Y2083767D01*
X335500Y2084167D01*
X336000Y2084700D01*
G01X341500Y2083500D02*
X340700Y2083633D01*
X340000Y2084167D01*
X339400Y2084967D01*
X339000Y2085900D01*
X338800Y2086967D01*
Y2088033D01*
X339000Y2089100D01*
X339400Y2090033D01*
X340000Y2090833D01*
X340700Y2091367D01*
X341500Y2091500D01*
X342300Y2091367D01*
X343000Y2090833D01*
X343600Y2090033D01*
X344000Y2089100D01*
X344200Y2088033D01*
Y2086967D01*
X344000Y2085900D01*
X343600Y2084967D01*
X343000Y2084167D01*
X342300Y2083633D01*
X341500Y2083500D01*
G01X347300Y2091500D02*
Y2085767D01*
X347700Y2084566D01*
X348500Y2083767D01*
X349500Y2083500D01*
X350500Y2083767D01*
X351300Y2084566D01*
X351700Y2085767D01*
Y2091500D01*
G01X355500Y2083500D02*
Y2091500D01*
X357900D01*
X358700Y2091100D01*
X359300Y2090167D01*
X359500Y2089100D01*
X359300Y2088033D01*
X358800Y2087233D01*
X357900Y2086833D01*
X355500D01*
G01X365500Y2083500D02*
X364700Y2083633D01*
X364000Y2084167D01*
X363400Y2084967D01*
X363000Y2085900D01*
X362800Y2086967D01*
Y2088033D01*
X363000Y2089100D01*
X363400Y2090033D01*
X364000Y2090833D01*
X364700Y2091367D01*
X365500Y2091500D01*
X366300Y2091367D01*
X367000Y2090833D01*
X367600Y2090033D01*
X368000Y2089100D01*
X368200Y2088033D01*
Y2086967D01*
X368000Y2085900D01*
X367600Y2084967D01*
X367000Y2084167D01*
X366300Y2083633D01*
X365500Y2083500D01*
G01X371200D02*
Y2091500D01*
X375800Y2083500D01*
Y2091500D01*
G01X379700Y2083233D02*
X383300Y2091500D01*
G01X387600Y2083500D02*
Y2091500D01*
X391400D01*
G01X390000Y2087633D02*
X387600D01*
G01X396300Y2091500D02*
X398700D01*
G01X397500D02*
Y2083500D01*
G01X396300D02*
X398700D01*
G01X403300D02*
Y2091500D01*
X405300D01*
X406100Y2091100D01*
X406700Y2090567D01*
X407200Y2089767D01*
X407600Y2088833D01*
X407700Y2087500D01*
X407600Y2086167D01*
X407200Y2085233D01*
X406700Y2084433D01*
X406100Y2083900D01*
X405300Y2083500D01*
X403300D01*
G01X411300Y2091500D02*
Y2085767D01*
X411700Y2084566D01*
X412500Y2083767D01*
X413500Y2083500D01*
X414500Y2083767D01*
X415300Y2084566D01*
X415700Y2085767D01*
Y2091500D01*
G01X423700Y2090833D02*
X423100Y2091233D01*
X422400Y2091500D01*
X421600D01*
X420700Y2091100D01*
X420000Y2090433D01*
X419500Y2089633D01*
X419100Y2088300D01*
X419000Y2087100D01*
X419200Y2085900D01*
X419500Y2085100D01*
X420100Y2084300D01*
X420800Y2083767D01*
X421500Y2083500D01*
X422200D01*
X422900Y2083767D01*
X423500Y2084167D01*
X424000Y2084700D01*
G01X428300Y2091500D02*
X430700D01*
G01X429500D02*
Y2083500D01*
G01X428300D02*
X430700D01*
G01X435000D02*
X437500Y2091500D01*
X440000Y2083500D01*
G01X439100Y2086300D02*
X435900D01*
G01X443500Y2091500D02*
Y2083500D01*
X447500D01*
G01X458900D02*
Y2091500D01*
X461500Y2084833D01*
X464100Y2091500D01*
Y2083500D01*
G01X467000D02*
X469500Y2091500D01*
X472000Y2083500D01*
G01X471100Y2086300D02*
X467900D01*
G01X475500Y2083500D02*
Y2091500D01*
X478000D01*
X478800Y2091100D01*
X479300Y2090567D01*
X479500Y2089500D01*
X479300Y2088433D01*
X478700Y2087767D01*
X478000Y2087367D01*
X475500D01*
G01X478000D02*
X479500Y2083500D01*
G01X483300D02*
Y2091500D01*
G01X487100D02*
X483300Y2086566D01*
G01X487700Y2083500D02*
X485000Y2088833D01*
G01X491700Y2083233D02*
X495300Y2091500D01*
G01X501500D02*
Y2083500D01*
G01X499200Y2091500D02*
X503800D01*
G01X509500Y2083500D02*
X508700Y2083633D01*
X508000Y2084167D01*
X507400Y2084967D01*
X507000Y2085900D01*
X506800Y2086967D01*
Y2088033D01*
X507000Y2089100D01*
X507400Y2090033D01*
X508000Y2090833D01*
X508700Y2091367D01*
X509500Y2091500D01*
X510300Y2091367D01*
X511000Y2090833D01*
X511600Y2090033D01*
X512000Y2089100D01*
X512200Y2088033D01*
Y2086967D01*
X512000Y2085900D01*
X511600Y2084967D01*
X511000Y2084167D01*
X510300Y2083633D01*
X509500Y2083500D01*
G01X517500D02*
X516700Y2083633D01*
X516000Y2084167D01*
X515400Y2084967D01*
X515000Y2085900D01*
X514800Y2086967D01*
Y2088033D01*
X515000Y2089100D01*
X515400Y2090033D01*
X516000Y2090833D01*
X516700Y2091367D01*
X517500Y2091500D01*
X518300Y2091367D01*
X519000Y2090833D01*
X519600Y2090033D01*
X520000Y2089100D01*
X520200Y2088033D01*
Y2086967D01*
X520000Y2085900D01*
X519600Y2084967D01*
X519000Y2084167D01*
X518300Y2083633D01*
X517500Y2083500D01*
G01X523500Y2091500D02*
Y2083500D01*
X527500D01*
G01X532300Y2091500D02*
X534700D01*
G01X533500D02*
Y2083500D01*
G01X532300D02*
X534700D01*
G01X539200D02*
Y2091500D01*
X543800Y2083500D01*
Y2091500D01*
G01X550100Y2087500D02*
X552100D01*
Y2085100D01*
X551500Y2084300D01*
X550800Y2083767D01*
X549800Y2083500D01*
X548800Y2083767D01*
X548100Y2084300D01*
X547500Y2085100D01*
X547100Y2086033D01*
X546900Y2087100D01*
Y2088033D01*
X547100Y2088833D01*
X547500Y2089767D01*
X548100Y2090567D01*
X548700Y2091100D01*
X549500Y2091500D01*
X550200D01*
X551000Y2091233D01*
X551600Y2090700D01*
G01X563400Y2083500D02*
Y2091500D01*
G01X567600D02*
Y2083500D01*
G01Y2087500D02*
X563400D01*
G01X573500Y2083500D02*
X572700Y2083633D01*
X572000Y2084167D01*
X571400Y2084967D01*
X571000Y2085900D01*
X570800Y2086967D01*
Y2088033D01*
X571000Y2089100D01*
X571400Y2090033D01*
X572000Y2090833D01*
X572700Y2091367D01*
X573500Y2091500D01*
X574300Y2091367D01*
X575000Y2090833D01*
X575600Y2090033D01*
X576000Y2089100D01*
X576200Y2088033D01*
Y2086967D01*
X576000Y2085900D01*
X575600Y2084967D01*
X575000Y2084167D01*
X574300Y2083633D01*
X573500Y2083500D01*
G01X579500Y2091500D02*
Y2083500D01*
X583500D01*
G01X591500D02*
X587500D01*
Y2091500D01*
X591500D01*
G01X589900Y2087633D02*
X587500D01*
G01X603400Y2084566D02*
X604200Y2083900D01*
X605100Y2083500D01*
X605900D01*
X606700Y2083900D01*
X607300Y2084566D01*
X607600Y2085500D01*
X607400Y2086433D01*
X606900Y2087233D01*
X606000Y2087767D01*
X604800Y2088033D01*
X604100Y2088567D01*
X603800Y2089500D01*
X604000Y2090433D01*
X604500Y2091100D01*
X605200Y2091500D01*
X605900D01*
X606600Y2091233D01*
X607200Y2090567D01*
G01X611500Y2083500D02*
Y2091500D01*
X613900D01*
X614700Y2091100D01*
X615300Y2090167D01*
X615500Y2089100D01*
X615300Y2088033D01*
X614800Y2087233D01*
X613900Y2086833D01*
X611500D01*
G01X619000Y2083500D02*
X621500Y2091500D01*
X624000Y2083500D01*
G01X623100Y2086300D02*
X619900D01*
G01X631700Y2090833D02*
X631100Y2091233D01*
X630400Y2091500D01*
X629600D01*
X628700Y2091100D01*
X628000Y2090433D01*
X627500Y2089633D01*
X627100Y2088300D01*
X627000Y2087100D01*
X627200Y2085900D01*
X627500Y2085100D01*
X628100Y2084300D01*
X628800Y2083767D01*
X629500Y2083500D01*
X630200D01*
X630900Y2083767D01*
X631500Y2084167D01*
X632000Y2084700D01*
G01X636300Y2091500D02*
X638700D01*
G01X637500D02*
Y2083500D01*
G01X636300D02*
X638700D01*
G01X643200D02*
Y2091500D01*
X647800Y2083500D01*
Y2091500D01*
G01X654100Y2087500D02*
X656100D01*
Y2085100D01*
X655500Y2084300D01*
X654800Y2083767D01*
X653800Y2083500D01*
X652800Y2083767D01*
X652100Y2084300D01*
X651500Y2085100D01*
X651100Y2086033D01*
X650900Y2087100D01*
Y2088033D01*
X651100Y2088833D01*
X651500Y2089767D01*
X652100Y2090567D01*
X652700Y2091100D01*
X653500Y2091500D01*
X654200D01*
X655000Y2091233D01*
X655600Y2090700D01*
G01X667000Y2083500D02*
X669500Y2091500D01*
X672000Y2083500D01*
G01X671100Y2086300D02*
X667900D01*
G01X675500Y2091500D02*
Y2083500D01*
X679500D01*
G01X683500Y2091500D02*
Y2083500D01*
X687500D01*
G01X699300Y2091500D02*
Y2085767D01*
X699700Y2084566D01*
X700500Y2083767D01*
X701500Y2083500D01*
X702500Y2083767D01*
X703300Y2084566D01*
X703700Y2085767D01*
Y2091500D01*
G01X707400Y2084566D02*
X708200Y2083900D01*
X709100Y2083500D01*
X709900D01*
X710700Y2083900D01*
X711300Y2084566D01*
X711600Y2085500D01*
X711400Y2086433D01*
X710900Y2087233D01*
X710000Y2087767D01*
X708800Y2088033D01*
X708100Y2088567D01*
X707800Y2089500D01*
X708000Y2090433D01*
X708500Y2091100D01*
X709200Y2091500D01*
X709900D01*
X710600Y2091233D01*
X711200Y2090567D01*
G01X716300Y2091500D02*
X718700D01*
G01X717500D02*
Y2083500D01*
G01X716300D02*
X718700D01*
G01X723200D02*
Y2091500D01*
X727800Y2083500D01*
Y2091500D01*
G01X734100Y2087500D02*
X736100D01*
Y2085100D01*
X735500Y2084300D01*
X734800Y2083767D01*
X733800Y2083500D01*
X732800Y2083767D01*
X732100Y2084300D01*
X731500Y2085100D01*
X731100Y2086033D01*
X730900Y2087100D01*
Y2088033D01*
X731100Y2088833D01*
X731500Y2089767D01*
X732100Y2090567D01*
X732700Y2091100D01*
X733500Y2091500D01*
X734200D01*
X735000Y2091233D01*
X735600Y2090700D01*
G01X747300Y2084700D02*
X747900Y2084033D01*
X748600Y2083633D01*
X749500Y2083500D01*
X750400Y2083767D01*
X751100Y2084300D01*
X751600Y2085233D01*
X751700Y2086300D01*
X751500Y2087367D01*
X751000Y2088033D01*
X750300Y2088567D01*
X749600Y2088700D01*
X748900Y2088567D01*
X748000Y2088033D01*
X748300Y2091500D01*
X751000D01*
G01X757500D02*
X756700Y2091233D01*
X756100Y2090567D01*
X755700Y2089767D01*
X755400Y2088700D01*
X755300Y2087500D01*
X755400Y2086300D01*
X755700Y2085233D01*
X756100Y2084433D01*
X756700Y2083767D01*
X757500Y2083500D01*
X758300Y2083767D01*
X758900Y2084433D01*
X759300Y2085233D01*
X759600Y2086300D01*
X759700Y2087500D01*
X759600Y2088700D01*
X759300Y2089767D01*
X758900Y2090567D01*
X758300Y2091233D01*
X757500Y2091500D01*
G01X762900Y2083500D02*
Y2091500D01*
X765500Y2084833D01*
X768100Y2091500D01*
Y2083500D01*
G01X772300Y2091500D02*
X774700D01*
G01X773500D02*
Y2083500D01*
G01X772300D02*
X774700D01*
G01X779500Y2091500D02*
Y2083500D01*
X783500D01*
G01X787400Y2084566D02*
X788200Y2083900D01*
X789100Y2083500D01*
X789900D01*
X790700Y2083900D01*
X791300Y2084566D01*
X791600Y2085500D01*
X791400Y2086433D01*
X790900Y2087233D01*
X790000Y2087767D01*
X788800Y2088033D01*
X788100Y2088567D01*
X787800Y2089500D01*
X788000Y2090433D01*
X788500Y2091100D01*
X789200Y2091500D01*
X789900D01*
X790600Y2091233D01*
X791200Y2090567D01*
G01X797500Y2083233D02*
X797300Y2083367D01*
Y2083633D01*
X797500Y2083767D01*
X797700Y2083633D01*
Y2083367D01*
X797500Y2083233D01*
G01X-124400Y2101833D02*
X-123700Y2102767D01*
X-123100Y2103300D01*
X-122300Y2103567D01*
X-121600Y2103300D01*
X-121100Y2102767D01*
X-120700Y2101967D01*
X-120600Y2101033D01*
X-120700Y2100233D01*
X-121100Y2099433D01*
X-121700Y2098767D01*
X-122400Y2098500D01*
X-123200Y2098767D01*
X-123900Y2099566D01*
X-124300Y2100767D01*
X-124400Y2102100D01*
X-124200Y2103833D01*
X-123900Y2104767D01*
X-123400Y2105700D01*
X-122700Y2106367D01*
X-122000Y2106500D01*
X-121300Y2106233D01*
X-120800Y2105567D01*
G01X-114500Y2098233D02*
X-114700Y2098367D01*
Y2098633D01*
X-114500Y2098767D01*
X-114300Y2098633D01*
Y2098367D01*
X-114500Y2098233D01*
G01X-106500Y2098500D02*
Y2106500D01*
X-107700Y2104900D01*
G01Y2098500D02*
X-105300D01*
G01X-91700Y2106500D02*
X-89300D01*
G01X-90500D02*
Y2098500D01*
G01X-91700D02*
X-89300D01*
G01X-84800D02*
Y2106500D01*
X-80200Y2098500D01*
Y2106500D01*
G01X-76600Y2099566D02*
X-75800Y2098900D01*
X-74900Y2098500D01*
X-74100D01*
X-73300Y2098900D01*
X-72700Y2099566D01*
X-72400Y2100500D01*
X-72600Y2101433D01*
X-73100Y2102233D01*
X-74000Y2102767D01*
X-75200Y2103033D01*
X-75900Y2103567D01*
X-76200Y2104500D01*
X-76000Y2105433D01*
X-75500Y2106100D01*
X-74800Y2106500D01*
X-74100D01*
X-73400Y2106233D01*
X-72800Y2105567D01*
G01X-67700Y2106500D02*
X-65300D01*
G01X-66500D02*
Y2098500D01*
G01X-67700D02*
X-65300D01*
G01X-60700D02*
Y2106500D01*
X-58700D01*
X-57900Y2106100D01*
X-57300Y2105567D01*
X-56800Y2104767D01*
X-56400Y2103833D01*
X-56300Y2102500D01*
X-56400Y2101167D01*
X-56800Y2100233D01*
X-57300Y2099433D01*
X-57900Y2098900D01*
X-58700Y2098500D01*
X-60700D01*
G01X-48500D02*
X-52500D01*
Y2106500D01*
X-48500D01*
G01X-50100Y2102633D02*
X-52500D01*
G01X-33700Y2102767D02*
X-33300Y2103167D01*
X-33000Y2103833D01*
X-32800Y2104767D01*
X-33000Y2105567D01*
X-33400Y2106100D01*
X-34100Y2106500D01*
X-36800D01*
Y2098500D01*
X-33500D01*
X-32800Y2099033D01*
X-32400Y2099833D01*
X-32200Y2100767D01*
X-32400Y2101700D01*
X-33000Y2102500D01*
X-33700Y2102767D01*
X-36800D01*
G01X-26500Y2098500D02*
X-27300Y2098633D01*
X-28000Y2099167D01*
X-28600Y2099967D01*
X-29000Y2100900D01*
X-29200Y2101967D01*
Y2103033D01*
X-29000Y2104100D01*
X-28600Y2105033D01*
X-28000Y2105833D01*
X-27300Y2106367D01*
X-26500Y2106500D01*
X-25700Y2106367D01*
X-25000Y2105833D01*
X-24400Y2105033D01*
X-24000Y2104100D01*
X-23800Y2103033D01*
Y2101967D01*
X-24000Y2100900D01*
X-24400Y2099967D01*
X-25000Y2099167D01*
X-25700Y2098633D01*
X-26500Y2098500D01*
G01X-21000D02*
X-18500Y2106500D01*
X-16000Y2098500D01*
G01X-16900Y2101300D02*
X-20100D01*
G01X-12500Y2098500D02*
Y2106500D01*
X-10000D01*
X-9200Y2106100D01*
X-8700Y2105567D01*
X-8500Y2104500D01*
X-8700Y2103433D01*
X-9300Y2102767D01*
X-10000Y2102367D01*
X-12500D01*
G01X-10000D02*
X-8500Y2098500D01*
G01X-4700D02*
Y2106500D01*
X-2700D01*
X-1900Y2106100D01*
X-1300Y2105567D01*
X-800Y2104767D01*
X-400Y2103833D01*
X-300Y2102500D01*
X-400Y2101167D01*
X-800Y2100233D01*
X-1300Y2099433D01*
X-1900Y2098900D01*
X-2700Y2098500D01*
X-4700D01*
G01X13500D02*
X12700Y2098633D01*
X12000Y2099167D01*
X11400Y2099967D01*
X11000Y2100900D01*
X10800Y2101967D01*
Y2103033D01*
X11000Y2104100D01*
X11400Y2105033D01*
X12000Y2105833D01*
X12700Y2106367D01*
X13500Y2106500D01*
X14300Y2106367D01*
X15000Y2105833D01*
X15600Y2105033D01*
X16000Y2104100D01*
X16200Y2103033D01*
Y2101967D01*
X16000Y2100900D01*
X15600Y2099967D01*
X15000Y2099167D01*
X14300Y2098633D01*
X13500Y2098500D01*
G01X19300Y2106500D02*
Y2100767D01*
X19700Y2099566D01*
X20500Y2098767D01*
X21500Y2098500D01*
X22500Y2098767D01*
X23300Y2099566D01*
X23700Y2100767D01*
Y2106500D01*
G01X29500D02*
Y2098500D01*
G01X27200Y2106500D02*
X31800D01*
G01X35500D02*
Y2098500D01*
X39500D01*
G01X44300Y2106500D02*
X46700D01*
G01X45500D02*
Y2098500D01*
G01X44300D02*
X46700D01*
G01X51200D02*
Y2106500D01*
X55800Y2098500D01*
Y2106500D01*
G01X63500Y2098500D02*
X59500D01*
Y2106500D01*
X63500D01*
G01X61900Y2102633D02*
X59500D01*
G01X75300Y2098500D02*
Y2106500D01*
X77300D01*
X78100Y2106100D01*
X78700Y2105567D01*
X79200Y2104767D01*
X79600Y2103833D01*
X79700Y2102500D01*
X79600Y2101167D01*
X79200Y2100233D01*
X78700Y2099433D01*
X78100Y2098900D01*
X77300Y2098500D01*
X75300D01*
G01X83300Y2106500D02*
Y2100767D01*
X83700Y2099566D01*
X84500Y2098767D01*
X85500Y2098500D01*
X86500Y2098767D01*
X87300Y2099566D01*
X87700Y2100767D01*
Y2106500D01*
G01X90900Y2098500D02*
Y2106500D01*
X93500Y2099833D01*
X96100Y2106500D01*
Y2098500D01*
G01X98900D02*
Y2106500D01*
X101500Y2099833D01*
X104100Y2106500D01*
Y2098500D01*
G01X109500D02*
Y2102100D01*
X107500Y2106500D01*
G01X111500D02*
X109500Y2102100D01*
G01X123500Y2098500D02*
Y2106500D01*
X125900D01*
X126700Y2106100D01*
X127300Y2105167D01*
X127500Y2104100D01*
X127300Y2103033D01*
X126800Y2102233D01*
X125900Y2101833D01*
X123500D01*
G01X131000Y2098500D02*
X133500Y2106500D01*
X136000Y2098500D01*
G01X135100Y2101300D02*
X131900D01*
G01X139300Y2098500D02*
Y2106500D01*
X141300D01*
X142100Y2106100D01*
X142700Y2105567D01*
X143200Y2104767D01*
X143600Y2103833D01*
X143700Y2102500D01*
X143600Y2101167D01*
X143200Y2100233D01*
X142700Y2099433D01*
X142100Y2098900D01*
X141300Y2098500D01*
X139300D01*
G01X155300D02*
Y2106500D01*
X157300D01*
X158100Y2106100D01*
X158700Y2105567D01*
X159200Y2104767D01*
X159600Y2103833D01*
X159700Y2102500D01*
X159600Y2101167D01*
X159200Y2100233D01*
X158700Y2099433D01*
X158100Y2098900D01*
X157300Y2098500D01*
X155300D01*
G01X167500D02*
X163500D01*
Y2106500D01*
X167500D01*
G01X165900Y2102633D02*
X163500D01*
G01X171400Y2099566D02*
X172200Y2098900D01*
X173100Y2098500D01*
X173900D01*
X174700Y2098900D01*
X175300Y2099566D01*
X175600Y2100500D01*
X175400Y2101433D01*
X174900Y2102233D01*
X174000Y2102767D01*
X172800Y2103033D01*
X172100Y2103567D01*
X171800Y2104500D01*
X172000Y2105433D01*
X172500Y2106100D01*
X173200Y2106500D01*
X173900D01*
X174600Y2106233D01*
X175200Y2105567D01*
G01X180300Y2106500D02*
X182700D01*
G01X181500D02*
Y2098500D01*
G01X180300D02*
X182700D01*
G01X190100Y2102500D02*
X192100D01*
Y2100100D01*
X191500Y2099300D01*
X190800Y2098767D01*
X189800Y2098500D01*
X188800Y2098767D01*
X188100Y2099300D01*
X187500Y2100100D01*
X187100Y2101033D01*
X186900Y2102100D01*
Y2103033D01*
X187100Y2103833D01*
X187500Y2104767D01*
X188100Y2105567D01*
X188700Y2106100D01*
X189500Y2106500D01*
X190200D01*
X191000Y2106233D01*
X191600Y2105700D01*
G01X195200Y2098500D02*
Y2106500D01*
X199800Y2098500D01*
Y2106500D01*
G01X212300D02*
X214700D01*
G01X213500D02*
Y2098500D01*
G01X212300D02*
X214700D01*
G01X219200D02*
Y2106500D01*
X223800Y2098500D01*
Y2106500D01*
G01X235400Y2099566D02*
X236200Y2098900D01*
X237100Y2098500D01*
X237900D01*
X238700Y2098900D01*
X239300Y2099566D01*
X239600Y2100500D01*
X239400Y2101433D01*
X238900Y2102233D01*
X238000Y2102767D01*
X236800Y2103033D01*
X236100Y2103567D01*
X235800Y2104500D01*
X236000Y2105433D01*
X236500Y2106100D01*
X237200Y2106500D01*
X237900D01*
X238600Y2106233D01*
X239200Y2105567D01*
G01X245500Y2098500D02*
X244700Y2098633D01*
X244000Y2099167D01*
X243400Y2099967D01*
X243000Y2100900D01*
X242800Y2101967D01*
Y2103033D01*
X243000Y2104100D01*
X243400Y2105033D01*
X244000Y2105833D01*
X244700Y2106367D01*
X245500Y2106500D01*
X246300Y2106367D01*
X247000Y2105833D01*
X247600Y2105033D01*
X248000Y2104100D01*
X248200Y2103033D01*
Y2101967D01*
X248000Y2100900D01*
X247600Y2099967D01*
X247000Y2099167D01*
X246300Y2098633D01*
X245500Y2098500D01*
G01X246300Y2100633D02*
X247500Y2098500D01*
G01X251300Y2106500D02*
Y2100767D01*
X251700Y2099566D01*
X252500Y2098767D01*
X253500Y2098500D01*
X254500Y2098767D01*
X255300Y2099566D01*
X255700Y2100767D01*
Y2106500D01*
G01X259000Y2098500D02*
X261500Y2106500D01*
X264000Y2098500D01*
G01X263100Y2101300D02*
X259900D01*
G01X267500Y2098500D02*
Y2106500D01*
X270000D01*
X270800Y2106100D01*
X271300Y2105567D01*
X271500Y2104500D01*
X271300Y2103433D01*
X270700Y2102767D01*
X270000Y2102367D01*
X267500D01*
G01X270000D02*
X271500Y2098500D01*
G01X279500D02*
X275500D01*
Y2106500D01*
X279500D01*
G01X277900Y2102633D02*
X275500D01*
G01X291400Y2099566D02*
X292200Y2098900D01*
X293100Y2098500D01*
X293900D01*
X294700Y2098900D01*
X295300Y2099566D01*
X295600Y2100500D01*
X295400Y2101433D01*
X294900Y2102233D01*
X294000Y2102767D01*
X292800Y2103033D01*
X292100Y2103567D01*
X291800Y2104500D01*
X292000Y2105433D01*
X292500Y2106100D01*
X293200Y2106500D01*
X293900D01*
X294600Y2106233D01*
X295200Y2105567D01*
G01X299400Y2098500D02*
Y2106500D01*
G01X303600D02*
Y2098500D01*
G01Y2102500D02*
X299400D01*
G01X307000Y2098500D02*
X309500Y2106500D01*
X312000Y2098500D01*
G01X311100Y2101300D02*
X307900D01*
G01X315500Y2098500D02*
Y2106500D01*
X317900D01*
X318700Y2106100D01*
X319300Y2105167D01*
X319500Y2104100D01*
X319300Y2103033D01*
X318800Y2102233D01*
X317900Y2101833D01*
X315500D01*
G01X327500Y2098500D02*
X323500D01*
Y2106500D01*
X327500D01*
G01X325900Y2102633D02*
X323500D01*
G01X332200Y2101167D02*
X334800D01*
G01X347400Y2099566D02*
X348200Y2098900D01*
X349100Y2098500D01*
X349900D01*
X350700Y2098900D01*
X351300Y2099566D01*
X351600Y2100500D01*
X351400Y2101433D01*
X350900Y2102233D01*
X350000Y2102767D01*
X348800Y2103033D01*
X348100Y2103567D01*
X347800Y2104500D01*
X348000Y2105433D01*
X348500Y2106100D01*
X349200Y2106500D01*
X349900D01*
X350600Y2106233D01*
X351200Y2105567D01*
G01X355400Y2098500D02*
Y2106500D01*
G01X359600D02*
Y2098500D01*
G01Y2102500D02*
X355400D01*
G01X363000Y2098500D02*
X365500Y2106500D01*
X368000Y2098500D01*
G01X367100Y2101300D02*
X363900D01*
G01X371500Y2098500D02*
Y2106500D01*
X373900D01*
X374700Y2106100D01*
X375300Y2105167D01*
X375500Y2104100D01*
X375300Y2103033D01*
X374800Y2102233D01*
X373900Y2101833D01*
X371500D01*
G01X383500Y2098500D02*
X379500D01*
Y2106500D01*
X383500D01*
G01X381900Y2102633D02*
X379500D01*
G01X395400Y2099566D02*
X396200Y2098900D01*
X397100Y2098500D01*
X397900D01*
X398700Y2098900D01*
X399300Y2099566D01*
X399600Y2100500D01*
X399400Y2101433D01*
X398900Y2102233D01*
X398000Y2102767D01*
X396800Y2103033D01*
X396100Y2103567D01*
X395800Y2104500D01*
X396000Y2105433D01*
X396500Y2106100D01*
X397200Y2106500D01*
X397900D01*
X398600Y2106233D01*
X399200Y2105567D01*
G01X404300Y2106500D02*
X406700D01*
G01X405500D02*
Y2098500D01*
G01X404300D02*
X406700D01*
G01X411600Y2106500D02*
X415400D01*
X411600Y2098500D01*
X415400D01*
G01X423500D02*
X419500D01*
Y2106500D01*
X423500D01*
G01X421900Y2102633D02*
X419500D01*
G01X435300Y2099700D02*
X435900Y2099033D01*
X436600Y2098633D01*
X437500Y2098500D01*
X438400Y2098767D01*
X439100Y2099300D01*
X439600Y2100233D01*
X439700Y2101300D01*
X439500Y2102367D01*
X439000Y2103033D01*
X438300Y2103567D01*
X437600Y2103700D01*
X436900Y2103567D01*
X436000Y2103033D01*
X436300Y2106500D01*
X439000D01*
G01X445500D02*
X444700Y2106233D01*
X444100Y2105567D01*
X443700Y2104767D01*
X443400Y2103700D01*
X443300Y2102500D01*
X443400Y2101300D01*
X443700Y2100233D01*
X444100Y2099433D01*
X444700Y2098767D01*
X445500Y2098500D01*
X446300Y2098767D01*
X446900Y2099433D01*
X447300Y2100233D01*
X447600Y2101300D01*
X447700Y2102500D01*
X447600Y2103700D01*
X447300Y2104767D01*
X446900Y2105567D01*
X446300Y2106233D01*
X445500Y2106500D01*
G01X450900Y2098500D02*
Y2106500D01*
X453500Y2099833D01*
X456100Y2106500D01*
Y2098500D01*
G01X460300Y2106500D02*
X462700D01*
G01X461500D02*
Y2098500D01*
G01X460300D02*
X462700D01*
G01X467500Y2106500D02*
Y2098500D01*
X471500D01*
G01X475400Y2099566D02*
X476200Y2098900D01*
X477100Y2098500D01*
X477900D01*
X478700Y2098900D01*
X479300Y2099566D01*
X479600Y2100500D01*
X479400Y2101433D01*
X478900Y2102233D01*
X478000Y2102767D01*
X476800Y2103033D01*
X476100Y2103567D01*
X475800Y2104500D01*
X476000Y2105433D01*
X476500Y2106100D01*
X477200Y2106500D01*
X477900D01*
X478600Y2106233D01*
X479200Y2105567D01*
G01X485300Y2097033D02*
X485700Y2098767D01*
G01X499500Y2098500D02*
Y2106500D01*
X501900D01*
X502700Y2106100D01*
X503300Y2105167D01*
X503500Y2104100D01*
X503300Y2103033D01*
X502800Y2102233D01*
X501900Y2101833D01*
X499500D01*
G01X508300Y2106500D02*
X510700D01*
G01X509500D02*
Y2098500D01*
G01X508300D02*
X510700D01*
G01X517500Y2106500D02*
Y2098500D01*
G01X515200Y2106500D02*
X519800D01*
G01X527700Y2105833D02*
X527100Y2106233D01*
X526400Y2106500D01*
X525600D01*
X524700Y2106100D01*
X524000Y2105433D01*
X523500Y2104633D01*
X523100Y2103300D01*
X523000Y2102100D01*
X523200Y2100900D01*
X523500Y2100100D01*
X524100Y2099300D01*
X524800Y2098767D01*
X525500Y2098500D01*
X526200D01*
X526900Y2098767D01*
X527500Y2099167D01*
X528000Y2099700D01*
G01X531400Y2098500D02*
Y2106500D01*
G01X535600D02*
Y2098500D01*
G01Y2102500D02*
X531400D01*
G01X549000Y2095833D02*
X548000Y2097167D01*
X547500Y2098500D01*
Y2103833D01*
X548000Y2105167D01*
X549000Y2106500D01*
G01X555400Y2099566D02*
X556200Y2098900D01*
X557100Y2098500D01*
X557900D01*
X558700Y2098900D01*
X559300Y2099566D01*
X559600Y2100500D01*
X559400Y2101433D01*
X558900Y2102233D01*
X558000Y2102767D01*
X556800Y2103033D01*
X556100Y2103567D01*
X555800Y2104500D01*
X556000Y2105433D01*
X556500Y2106100D01*
X557200Y2106500D01*
X557900D01*
X558600Y2106233D01*
X559200Y2105567D01*
G01X563400Y2098500D02*
Y2106500D01*
G01X567600D02*
Y2098500D01*
G01Y2102500D02*
X563400D01*
G01X571000Y2098500D02*
X573500Y2106500D01*
X576000Y2098500D01*
G01X575100Y2101300D02*
X571900D01*
G01X579500Y2098500D02*
Y2106500D01*
X581900D01*
X582700Y2106100D01*
X583300Y2105167D01*
X583500Y2104100D01*
X583300Y2103033D01*
X582800Y2102233D01*
X581900Y2101833D01*
X579500D01*
G01X591500Y2098500D02*
X587500D01*
Y2106500D01*
X591500D01*
G01X589900Y2102633D02*
X587500D01*
G01X607700Y2105833D02*
X607100Y2106233D01*
X606400Y2106500D01*
X605600D01*
X604700Y2106100D01*
X604000Y2105433D01*
X603500Y2104633D01*
X603100Y2103300D01*
X603000Y2102100D01*
X603200Y2100900D01*
X603500Y2100100D01*
X604100Y2099300D01*
X604800Y2098767D01*
X605500Y2098500D01*
X606200D01*
X606900Y2098767D01*
X607500Y2099167D01*
X608000Y2099700D01*
G01X615500Y2098500D02*
X611500D01*
Y2106500D01*
X615500D01*
G01X613900Y2102633D02*
X611500D01*
G01X619200Y2098500D02*
Y2106500D01*
X623800Y2098500D01*
Y2106500D01*
G01X629500D02*
Y2098500D01*
G01X627200Y2106500D02*
X631800D01*
G01X639500Y2098500D02*
X635500D01*
Y2106500D01*
X639500D01*
G01X637900Y2102633D02*
X635500D01*
G01X643500Y2098500D02*
Y2106500D01*
X646000D01*
X646800Y2106100D01*
X647300Y2105567D01*
X647500Y2104500D01*
X647300Y2103433D01*
X646700Y2102767D01*
X646000Y2102367D01*
X643500D01*
G01X646000D02*
X647500Y2098500D01*
G01X661500Y2106500D02*
Y2098500D01*
G01X659200Y2106500D02*
X663800D01*
G01X669500Y2098500D02*
X668700Y2098633D01*
X668000Y2099167D01*
X667400Y2099967D01*
X667000Y2100900D01*
X666800Y2101967D01*
Y2103033D01*
X667000Y2104100D01*
X667400Y2105033D01*
X668000Y2105833D01*
X668700Y2106367D01*
X669500Y2106500D01*
X670300Y2106367D01*
X671000Y2105833D01*
X671600Y2105033D01*
X672000Y2104100D01*
X672200Y2103033D01*
Y2101967D01*
X672000Y2100900D01*
X671600Y2099967D01*
X671000Y2099167D01*
X670300Y2098633D01*
X669500Y2098500D01*
G01X687700Y2105833D02*
X687100Y2106233D01*
X686400Y2106500D01*
X685600D01*
X684700Y2106100D01*
X684000Y2105433D01*
X683500Y2104633D01*
X683100Y2103300D01*
X683000Y2102100D01*
X683200Y2100900D01*
X683500Y2100100D01*
X684100Y2099300D01*
X684800Y2098767D01*
X685500Y2098500D01*
X686200D01*
X686900Y2098767D01*
X687500Y2099167D01*
X688000Y2099700D01*
G01X695500Y2098500D02*
X691500D01*
Y2106500D01*
X695500D01*
G01X693900Y2102633D02*
X691500D01*
G01X699200Y2098500D02*
Y2106500D01*
X703800Y2098500D01*
Y2106500D01*
G01X709500D02*
Y2098500D01*
G01X707200Y2106500D02*
X711800D01*
G01X719500Y2098500D02*
X715500D01*
Y2106500D01*
X719500D01*
G01X717900Y2102633D02*
X715500D01*
G01X723500Y2098500D02*
Y2106500D01*
X726000D01*
X726800Y2106100D01*
X727300Y2105567D01*
X727500Y2104500D01*
X727300Y2103433D01*
X726700Y2102767D01*
X726000Y2102367D01*
X723500D01*
G01X726000D02*
X727500Y2098500D01*
G01X734000Y2095833D02*
X735000Y2097167D01*
X735500Y2098500D01*
Y2103833D01*
X735000Y2105167D01*
X734000Y2106500D01*
G01X741500Y2098233D02*
X741300Y2098367D01*
Y2098633D01*
X741500Y2098767D01*
X741700Y2098633D01*
Y2098367D01*
X741500Y2098233D01*
G01Y2101833D02*
X741300Y2101967D01*
Y2102233D01*
X741500Y2102367D01*
X741700Y2102233D01*
Y2101967D01*
X741500Y2101833D01*
G01X757500Y2098500D02*
Y2106500D01*
X756300Y2104900D01*
G01Y2098500D02*
X758700D01*
G01X765500Y2106500D02*
X764700Y2106233D01*
X764100Y2105567D01*
X763700Y2104767D01*
X763400Y2103700D01*
X763300Y2102500D01*
X763400Y2101300D01*
X763700Y2100233D01*
X764100Y2099433D01*
X764700Y2098767D01*
X765500Y2098500D01*
X766300Y2098767D01*
X766900Y2099433D01*
X767300Y2100233D01*
X767600Y2101300D01*
X767700Y2102500D01*
X767600Y2103700D01*
X767300Y2104767D01*
X766900Y2105567D01*
X766300Y2106233D01*
X765500Y2106500D01*
G01X773500D02*
X772700Y2106233D01*
X772100Y2105567D01*
X771700Y2104767D01*
X771400Y2103700D01*
X771300Y2102500D01*
X771400Y2101300D01*
X771700Y2100233D01*
X772100Y2099433D01*
X772700Y2098767D01*
X773500Y2098500D01*
X774300Y2098767D01*
X774900Y2099433D01*
X775300Y2100233D01*
X775600Y2101300D01*
X775700Y2102500D01*
X775600Y2103700D01*
X775300Y2104767D01*
X774900Y2105567D01*
X774300Y2106233D01*
X773500Y2106500D01*
G01X778900Y2098500D02*
Y2106500D01*
X781500Y2099833D01*
X784100Y2106500D01*
Y2098500D01*
G01X788300Y2106500D02*
X790700D01*
G01X789500D02*
Y2098500D01*
G01X788300D02*
X790700D01*
G01X795500Y2106500D02*
Y2098500D01*
X799500D01*
G01X803400Y2099566D02*
X804200Y2098900D01*
X805100Y2098500D01*
X805900D01*
X806700Y2098900D01*
X807300Y2099566D01*
X807600Y2100500D01*
X807400Y2101433D01*
X806900Y2102233D01*
X806000Y2102767D01*
X804800Y2103033D01*
X804100Y2103567D01*
X803800Y2104500D01*
X804000Y2105433D01*
X804500Y2106100D01*
X805200Y2106500D01*
X805900D01*
X806600Y2106233D01*
X807200Y2105567D01*
G01X813500Y2098233D02*
X813300Y2098367D01*
Y2098633D01*
X813500Y2098767D01*
X813700Y2098633D01*
Y2098367D01*
X813500Y2098233D01*
G01X827300Y2098500D02*
Y2106500D01*
X829300D01*
X830100Y2106100D01*
X830700Y2105567D01*
X831200Y2104767D01*
X831600Y2103833D01*
X831700Y2102500D01*
X831600Y2101167D01*
X831200Y2100233D01*
X830700Y2099433D01*
X830100Y2098900D01*
X829300Y2098500D01*
X827300D01*
G01X835500D02*
Y2106500D01*
X838000D01*
X838800Y2106100D01*
X839300Y2105567D01*
X839500Y2104500D01*
X839300Y2103433D01*
X838700Y2102767D01*
X838000Y2102367D01*
X835500D01*
G01X838000D02*
X839500Y2098500D01*
G01X844300Y2106500D02*
X846700D01*
G01X845500D02*
Y2098500D01*
G01X844300D02*
X846700D01*
G01X851500Y2106500D02*
Y2098500D01*
X855500D01*
G01X859500Y2106500D02*
Y2098500D01*
X863500D01*
G01X867700Y2098233D02*
X871300Y2106500D01*
G01X875600Y2098500D02*
Y2106500D01*
X879400D01*
G01X878000Y2102633D02*
X875600D01*
G01X887500Y2098500D02*
X883500D01*
Y2106500D01*
X887500D01*
G01X885900Y2102633D02*
X883500D01*
G01X891000Y2098500D02*
X893500Y2106500D01*
X896000Y2098500D01*
G01X895100Y2101300D02*
X891900D01*
G01X901500Y2106500D02*
Y2098500D01*
G01X899200Y2106500D02*
X903800D01*
G01X907300D02*
Y2100767D01*
X907700Y2099566D01*
X908500Y2098767D01*
X909500Y2098500D01*
X910500Y2098767D01*
X911300Y2099566D01*
X911700Y2100767D01*
Y2106500D01*
G01X915500Y2098500D02*
Y2106500D01*
X918000D01*
X918800Y2106100D01*
X919300Y2105567D01*
X919500Y2104500D01*
X919300Y2103433D01*
X918700Y2102767D01*
X918000Y2102367D01*
X915500D01*
G01X918000D02*
X919500Y2098500D01*
G01X927500D02*
X923500D01*
Y2106500D01*
X927500D01*
G01X925900Y2102633D02*
X923500D01*
G01X931700Y2098233D02*
X935300Y2106500D01*
G01X939500Y2098500D02*
Y2106500D01*
X942000D01*
X942800Y2106100D01*
X943300Y2105567D01*
X943500Y2104500D01*
X943300Y2103433D01*
X942700Y2102767D01*
X942000Y2102367D01*
X939500D01*
G01X942000D02*
X943500Y2098500D01*
G01X949500D02*
X948700Y2098633D01*
X948000Y2099167D01*
X947400Y2099967D01*
X947000Y2100900D01*
X946800Y2101967D01*
Y2103033D01*
X947000Y2104100D01*
X947400Y2105033D01*
X948000Y2105833D01*
X948700Y2106367D01*
X949500Y2106500D01*
X950300Y2106367D01*
X951000Y2105833D01*
X951600Y2105033D01*
X952000Y2104100D01*
X952200Y2103033D01*
Y2101967D01*
X952000Y2100900D01*
X951600Y2099967D01*
X951000Y2099167D01*
X950300Y2098633D01*
X949500Y2098500D01*
G01X955300Y2106500D02*
Y2100767D01*
X955700Y2099566D01*
X956500Y2098767D01*
X957500Y2098500D01*
X958500Y2098767D01*
X959300Y2099566D01*
X959700Y2100767D01*
Y2106500D01*
G01X965500D02*
Y2098500D01*
G01X963200Y2106500D02*
X967800D01*
G01X975500Y2098500D02*
X971500D01*
Y2106500D01*
X975500D01*
G01X973900Y2102633D02*
X971500D01*
G01X979700Y2098233D02*
X983300Y2106500D01*
G01X987500Y2098500D02*
Y2106500D01*
X989900D01*
X990700Y2106100D01*
X991300Y2105167D01*
X991500Y2104100D01*
X991300Y2103033D01*
X990800Y2102233D01*
X989900Y2101833D01*
X987500D01*
G01X995500Y2098500D02*
Y2106500D01*
X998000D01*
X998800Y2106100D01*
X999300Y2105567D01*
X999500Y2104500D01*
X999300Y2103433D01*
X998700Y2102767D01*
X998000Y2102367D01*
X995500D01*
G01X998000D02*
X999500Y2098500D01*
G01X1005500D02*
X1004700Y2098633D01*
X1004000Y2099167D01*
X1003400Y2099967D01*
X1003000Y2100900D01*
X1002800Y2101967D01*
Y2103033D01*
X1003000Y2104100D01*
X1003400Y2105033D01*
X1004000Y2105833D01*
X1004700Y2106367D01*
X1005500Y2106500D01*
X1006300Y2106367D01*
X1007000Y2105833D01*
X1007600Y2105033D01*
X1008000Y2104100D01*
X1008200Y2103033D01*
Y2101967D01*
X1008000Y2100900D01*
X1007600Y2099967D01*
X1007000Y2099167D01*
X1006300Y2098633D01*
X1005500Y2098500D01*
G01X1011600D02*
Y2106500D01*
X1015400D01*
G01X1014000Y2102633D02*
X1011600D01*
G01X1020300Y2106500D02*
X1022700D01*
G01X1021500D02*
Y2098500D01*
G01X1020300D02*
X1022700D01*
G01X1027500Y2106500D02*
Y2098500D01*
X1031500D01*
G01X1039500D02*
X1035500D01*
Y2106500D01*
X1039500D01*
G01X1037900Y2102633D02*
X1035500D01*
G01X1051400Y2099566D02*
X1052200Y2098900D01*
X1053100Y2098500D01*
X1053900D01*
X1054700Y2098900D01*
X1055300Y2099566D01*
X1055600Y2100500D01*
X1055400Y2101433D01*
X1054900Y2102233D01*
X1054000Y2102767D01*
X1052800Y2103033D01*
X1052100Y2103567D01*
X1051800Y2104500D01*
X1052000Y2105433D01*
X1052500Y2106100D01*
X1053200Y2106500D01*
X1053900D01*
X1054600Y2106233D01*
X1055200Y2105567D01*
G01X1059500Y2098500D02*
Y2106500D01*
X1061900D01*
X1062700Y2106100D01*
X1063300Y2105167D01*
X1063500Y2104100D01*
X1063300Y2103033D01*
X1062800Y2102233D01*
X1061900Y2101833D01*
X1059500D01*
G01X1067000Y2098500D02*
X1069500Y2106500D01*
X1072000Y2098500D01*
G01X1071100Y2101300D02*
X1067900D01*
G01X1079700Y2105833D02*
X1079100Y2106233D01*
X1078400Y2106500D01*
X1077600D01*
X1076700Y2106100D01*
X1076000Y2105433D01*
X1075500Y2104633D01*
X1075100Y2103300D01*
X1075000Y2102100D01*
X1075200Y2100900D01*
X1075500Y2100100D01*
X1076100Y2099300D01*
X1076800Y2098767D01*
X1077500Y2098500D01*
X1078200D01*
X1078900Y2098767D01*
X1079500Y2099167D01*
X1080000Y2099700D01*
G01X1084300Y2106500D02*
X1086700D01*
G01X1085500D02*
Y2098500D01*
G01X1084300D02*
X1086700D01*
G01X1091200D02*
Y2106500D01*
X1095800Y2098500D01*
Y2106500D01*
G01X1102100Y2102500D02*
X1104100D01*
Y2100100D01*
X1103500Y2099300D01*
X1102800Y2098767D01*
X1101800Y2098500D01*
X1100800Y2098767D01*
X1100100Y2099300D01*
X1099500Y2100100D01*
X1099100Y2101033D01*
X1098900Y2102100D01*
Y2103033D01*
X1099100Y2103833D01*
X1099500Y2104767D01*
X1100100Y2105567D01*
X1100700Y2106100D01*
X1101500Y2106500D01*
X1102200D01*
X1103000Y2106233D01*
X1103600Y2105700D01*
G01X1115000Y2098500D02*
X1117500Y2106500D01*
X1120000Y2098500D01*
G01X1119100Y2101300D02*
X1115900D01*
G01X1123500Y2106500D02*
Y2098500D01*
X1127500D01*
G01X1131500Y2106500D02*
Y2098500D01*
X1135500D01*
G01X1147300Y2106500D02*
Y2100767D01*
X1147700Y2099566D01*
X1148500Y2098767D01*
X1149500Y2098500D01*
X1150500Y2098767D01*
X1151300Y2099566D01*
X1151700Y2100767D01*
Y2106500D01*
G01X1155400Y2099566D02*
X1156200Y2098900D01*
X1157100Y2098500D01*
X1157900D01*
X1158700Y2098900D01*
X1159300Y2099566D01*
X1159600Y2100500D01*
X1159400Y2101433D01*
X1158900Y2102233D01*
X1158000Y2102767D01*
X1156800Y2103033D01*
X1156100Y2103567D01*
X1155800Y2104500D01*
X1156000Y2105433D01*
X1156500Y2106100D01*
X1157200Y2106500D01*
X1157900D01*
X1158600Y2106233D01*
X1159200Y2105567D01*
G01X1164300Y2106500D02*
X1166700D01*
G01X1165500D02*
Y2098500D01*
G01X1164300D02*
X1166700D01*
G01X1171200D02*
Y2106500D01*
X1175800Y2098500D01*
Y2106500D01*
G01X1182100Y2102500D02*
X1184100D01*
Y2100100D01*
X1183500Y2099300D01*
X1182800Y2098767D01*
X1181800Y2098500D01*
X1180800Y2098767D01*
X1180100Y2099300D01*
X1179500Y2100100D01*
X1179100Y2101033D01*
X1178900Y2102100D01*
Y2103033D01*
X1179100Y2103833D01*
X1179500Y2104767D01*
X1180100Y2105567D01*
X1180700Y2106100D01*
X1181500Y2106500D01*
X1182200D01*
X1183000Y2106233D01*
X1183600Y2105700D01*
G01X1197500Y2098500D02*
Y2106500D01*
X1196300Y2104900D01*
G01Y2098500D02*
X1198700D01*
G01X1205500Y2106500D02*
X1204700Y2106233D01*
X1204100Y2105567D01*
X1203700Y2104767D01*
X1203400Y2103700D01*
X1203300Y2102500D01*
X1203400Y2101300D01*
X1203700Y2100233D01*
X1204100Y2099433D01*
X1204700Y2098767D01*
X1205500Y2098500D01*
X1206300Y2098767D01*
X1206900Y2099433D01*
X1207300Y2100233D01*
X1207600Y2101300D01*
X1207700Y2102500D01*
X1207600Y2103700D01*
X1207300Y2104767D01*
X1206900Y2105567D01*
X1206300Y2106233D01*
X1205500Y2106500D01*
G01X1213500D02*
X1212700Y2106233D01*
X1212100Y2105567D01*
X1211700Y2104767D01*
X1211400Y2103700D01*
X1211300Y2102500D01*
X1211400Y2101300D01*
X1211700Y2100233D01*
X1212100Y2099433D01*
X1212700Y2098767D01*
X1213500Y2098500D01*
X1214300Y2098767D01*
X1214900Y2099433D01*
X1215300Y2100233D01*
X1215600Y2101300D01*
X1215700Y2102500D01*
X1215600Y2103700D01*
X1215300Y2104767D01*
X1214900Y2105567D01*
X1214300Y2106233D01*
X1213500Y2106500D01*
G01X1218900Y2098500D02*
Y2106500D01*
X1221500Y2099833D01*
X1224100Y2106500D01*
Y2098500D01*
G01X1228300Y2106500D02*
X1230700D01*
G01X1229500D02*
Y2098500D01*
G01X1228300D02*
X1230700D01*
G01X1235500Y2106500D02*
Y2098500D01*
X1239500D01*
G01X1243400Y2099566D02*
X1244200Y2098900D01*
X1245100Y2098500D01*
X1245900D01*
X1246700Y2098900D01*
X1247300Y2099566D01*
X1247600Y2100500D01*
X1247400Y2101433D01*
X1246900Y2102233D01*
X1246000Y2102767D01*
X1244800Y2103033D01*
X1244100Y2103567D01*
X1243800Y2104500D01*
X1244000Y2105433D01*
X1244500Y2106100D01*
X1245200Y2106500D01*
X1245900D01*
X1246600Y2106233D01*
X1247200Y2105567D01*
G01X1253500Y2098233D02*
X1253300Y2098367D01*
Y2098633D01*
X1253500Y2098767D01*
X1253700Y2098633D01*
Y2098367D01*
X1253500Y2098233D01*
G01X1275500Y2106500D02*
Y2098500D01*
X1279500D01*
G01X1283000D02*
X1285500Y2106500D01*
X1288000Y2098500D01*
G01X1287100Y2101300D02*
X1283900D01*
G01X1294300Y2102767D02*
X1294700Y2103167D01*
X1295000Y2103833D01*
X1295200Y2104767D01*
X1295000Y2105567D01*
X1294600Y2106100D01*
X1293900Y2106500D01*
X1291200D01*
Y2098500D01*
X1294500D01*
X1295200Y2099033D01*
X1295600Y2099833D01*
X1295800Y2100767D01*
X1295600Y2101700D01*
X1295000Y2102500D01*
X1294300Y2102767D01*
X1291200D01*
G01X1303500Y2098500D02*
X1299500D01*
Y2106500D01*
X1303500D01*
G01X1301900Y2102633D02*
X1299500D01*
G01X1307500Y2106500D02*
Y2098500D01*
X1311500D01*
G01X1323000D02*
X1325500Y2106500D01*
X1328000Y2098500D01*
G01X1327100Y2101300D02*
X1323900D01*
G01X1331500Y2098500D02*
Y2106500D01*
X1334000D01*
X1334800Y2106100D01*
X1335300Y2105567D01*
X1335500Y2104500D01*
X1335300Y2103433D01*
X1334700Y2102767D01*
X1334000Y2102367D01*
X1331500D01*
G01X1334000D02*
X1335500Y2098500D01*
G01X1343500D02*
X1339500D01*
Y2106500D01*
X1343500D01*
G01X1341900Y2102633D02*
X1339500D01*
G01X1347000Y2098500D02*
X1349500Y2106500D01*
X1352000Y2098500D01*
G01X1351100Y2101300D02*
X1347900D01*
G01X1363200Y2098500D02*
Y2106500D01*
X1367800Y2098500D01*
Y2106500D01*
G01X1373500Y2098500D02*
X1372700Y2098633D01*
X1372000Y2099167D01*
X1371400Y2099967D01*
X1371000Y2100900D01*
X1370800Y2101967D01*
Y2103033D01*
X1371000Y2104100D01*
X1371400Y2105033D01*
X1372000Y2105833D01*
X1372700Y2106367D01*
X1373500Y2106500D01*
X1374300Y2106367D01*
X1375000Y2105833D01*
X1375600Y2105033D01*
X1376000Y2104100D01*
X1376200Y2103033D01*
Y2101967D01*
X1376000Y2100900D01*
X1375600Y2099967D01*
X1375000Y2099167D01*
X1374300Y2098633D01*
X1373500Y2098500D01*
G01X1387000D02*
X1389500Y2106500D01*
X1392000Y2098500D01*
G01X1391100Y2101300D02*
X1387900D01*
G01X1395300Y2098500D02*
Y2106500D01*
X1397300D01*
X1398100Y2106100D01*
X1398700Y2105567D01*
X1399200Y2104767D01*
X1399600Y2103833D01*
X1399700Y2102500D01*
X1399600Y2101167D01*
X1399200Y2100233D01*
X1398700Y2099433D01*
X1398100Y2098900D01*
X1397300Y2098500D01*
X1395300D01*
G01X1403300D02*
Y2106500D01*
X1405300D01*
X1406100Y2106100D01*
X1406700Y2105567D01*
X1407200Y2104767D01*
X1407600Y2103833D01*
X1407700Y2102500D01*
X1407600Y2101167D01*
X1407200Y2100233D01*
X1406700Y2099433D01*
X1406100Y2098900D01*
X1405300Y2098500D01*
X1403300D01*
G01X1419300D02*
Y2106500D01*
X1421300D01*
X1422100Y2106100D01*
X1422700Y2105567D01*
X1423200Y2104767D01*
X1423600Y2103833D01*
X1423700Y2102500D01*
X1423600Y2101167D01*
X1423200Y2100233D01*
X1422700Y2099433D01*
X1422100Y2098900D01*
X1421300Y2098500D01*
X1419300D01*
G01X1427300Y2106500D02*
Y2100767D01*
X1427700Y2099566D01*
X1428500Y2098767D01*
X1429500Y2098500D01*
X1430500Y2098767D01*
X1431300Y2099566D01*
X1431700Y2100767D01*
Y2106500D01*
G01X1434900Y2098500D02*
Y2106500D01*
X1437500Y2099833D01*
X1440100Y2106500D01*
Y2098500D01*
G01X1442900D02*
Y2106500D01*
X1445500Y2099833D01*
X1448100Y2106500D01*
Y2098500D01*
G01X1453500D02*
Y2102100D01*
X1451500Y2106500D01*
G01X1455500D02*
X1453500Y2102100D01*
G01X1467500Y2098500D02*
Y2106500D01*
X1469900D01*
X1470700Y2106100D01*
X1471300Y2105167D01*
X1471500Y2104100D01*
X1471300Y2103033D01*
X1470800Y2102233D01*
X1469900Y2101833D01*
X1467500D01*
G01X1475000Y2098500D02*
X1477500Y2106500D01*
X1480000Y2098500D01*
G01X1479100Y2101300D02*
X1475900D01*
G01X1483300Y2098500D02*
Y2106500D01*
X1485300D01*
X1486100Y2106100D01*
X1486700Y2105567D01*
X1487200Y2104767D01*
X1487600Y2103833D01*
X1487700Y2102500D01*
X1487600Y2101167D01*
X1487200Y2100233D01*
X1486700Y2099433D01*
X1486100Y2098900D01*
X1485300Y2098500D01*
X1483300D01*
G01X1493500Y2098233D02*
X1493300Y2098367D01*
Y2098633D01*
X1493500Y2098767D01*
X1493700Y2098633D01*
Y2098367D01*
X1493500Y2098233D01*
G01X-106900Y2117500D02*
X-104900D01*
Y2115100D01*
X-105500Y2114300D01*
X-106200Y2113767D01*
X-107200Y2113500D01*
X-108200Y2113767D01*
X-108900Y2114300D01*
X-109500Y2115100D01*
X-109900Y2116033D01*
X-110100Y2117100D01*
Y2118033D01*
X-109900Y2118833D01*
X-109500Y2119767D01*
X-108900Y2120567D01*
X-108300Y2121100D01*
X-107500Y2121500D01*
X-106800D01*
X-106000Y2121233D01*
X-105400Y2120700D01*
G01X-101500Y2113500D02*
Y2121500D01*
X-99000D01*
X-98200Y2121100D01*
X-97700Y2120567D01*
X-97500Y2119500D01*
X-97700Y2118433D01*
X-98300Y2117767D01*
X-99000Y2117367D01*
X-101500D01*
G01X-99000D02*
X-97500Y2113500D01*
G01X-91500D02*
X-92300Y2113633D01*
X-93000Y2114167D01*
X-93600Y2114967D01*
X-94000Y2115900D01*
X-94200Y2116967D01*
Y2118033D01*
X-94000Y2119100D01*
X-93600Y2120033D01*
X-93000Y2120833D01*
X-92300Y2121367D01*
X-91500Y2121500D01*
X-90700Y2121367D01*
X-90000Y2120833D01*
X-89400Y2120033D01*
X-89000Y2119100D01*
X-88800Y2118033D01*
Y2116967D01*
X-89000Y2115900D01*
X-89400Y2114967D01*
X-90000Y2114167D01*
X-90700Y2113633D01*
X-91500Y2113500D01*
G01X-85700Y2121500D02*
Y2115767D01*
X-85300Y2114566D01*
X-84500Y2113767D01*
X-83500Y2113500D01*
X-82500Y2113767D01*
X-81700Y2114566D01*
X-81300Y2115767D01*
Y2121500D01*
G01X-77500Y2113500D02*
Y2121500D01*
X-75100D01*
X-74300Y2121100D01*
X-73700Y2120167D01*
X-73500Y2119100D01*
X-73700Y2118033D01*
X-74200Y2117233D01*
X-75100Y2116833D01*
X-77500D01*
G01X-69600Y2114566D02*
X-68800Y2113900D01*
X-67900Y2113500D01*
X-67100D01*
X-66300Y2113900D01*
X-65700Y2114566D01*
X-65400Y2115500D01*
X-65600Y2116433D01*
X-66100Y2117233D01*
X-67000Y2117767D01*
X-68200Y2118033D01*
X-68900Y2118567D01*
X-69200Y2119500D01*
X-69000Y2120433D01*
X-68500Y2121100D01*
X-67800Y2121500D01*
X-67100D01*
X-66400Y2121233D01*
X-65800Y2120567D01*
G01X-54000Y2113500D02*
X-51500Y2121500D01*
X-49000Y2113500D01*
G01X-49900Y2116300D02*
X-53100D01*
G01X-38000Y2113500D02*
X-35500Y2121500D01*
X-33000Y2113500D01*
G01X-33900Y2116300D02*
X-37100D01*
G01X-29800Y2113500D02*
Y2121500D01*
X-25200Y2113500D01*
Y2121500D01*
G01X-21700Y2113500D02*
Y2121500D01*
X-19700D01*
X-18900Y2121100D01*
X-18300Y2120567D01*
X-17800Y2119767D01*
X-17400Y2118833D01*
X-17300Y2117500D01*
X-17400Y2116167D01*
X-17800Y2115233D01*
X-18300Y2114433D01*
X-18900Y2113900D01*
X-19700Y2113500D01*
X-21700D01*
G01X-2700Y2117767D02*
X-2300Y2118167D01*
X-2000Y2118833D01*
X-1800Y2119767D01*
X-2000Y2120567D01*
X-2400Y2121100D01*
X-3100Y2121500D01*
X-5800D01*
Y2113500D01*
X-2500D01*
X-1800Y2114033D01*
X-1400Y2114833D01*
X-1200Y2115767D01*
X-1400Y2116700D01*
X-2000Y2117500D01*
X-2700Y2117767D01*
X-5800D01*
G01X4300Y2112033D02*
X4700Y2113767D01*
G01X12500Y2121500D02*
Y2113500D01*
G01X10200Y2121500D02*
X14800D01*
G01X18400Y2113500D02*
Y2121500D01*
G01X22600D02*
Y2113500D01*
G01Y2117500D02*
X18400D01*
G01X30500Y2113500D02*
X26500D01*
Y2121500D01*
X30500D01*
G01X28900Y2117633D02*
X26500D01*
G01X34200Y2113500D02*
Y2121500D01*
X38800Y2113500D01*
Y2121500D01*
G01X53100Y2117500D02*
X55100D01*
Y2115100D01*
X54500Y2114300D01*
X53800Y2113767D01*
X52800Y2113500D01*
X51800Y2113767D01*
X51100Y2114300D01*
X50500Y2115100D01*
X50100Y2116033D01*
X49900Y2117100D01*
Y2118033D01*
X50100Y2118833D01*
X50500Y2119767D01*
X51100Y2120567D01*
X51700Y2121100D01*
X52500Y2121500D01*
X53200D01*
X54000Y2121233D01*
X54600Y2120700D01*
G01X58500Y2113500D02*
Y2121500D01*
X61000D01*
X61800Y2121100D01*
X62300Y2120567D01*
X62500Y2119500D01*
X62300Y2118433D01*
X61700Y2117767D01*
X61000Y2117367D01*
X58500D01*
G01X61000D02*
X62500Y2113500D01*
G01X68500D02*
X67700Y2113633D01*
X67000Y2114167D01*
X66400Y2114967D01*
X66000Y2115900D01*
X65800Y2116967D01*
Y2118033D01*
X66000Y2119100D01*
X66400Y2120033D01*
X67000Y2120833D01*
X67700Y2121367D01*
X68500Y2121500D01*
X69300Y2121367D01*
X70000Y2120833D01*
X70600Y2120033D01*
X71000Y2119100D01*
X71200Y2118033D01*
Y2116967D01*
X71000Y2115900D01*
X70600Y2114967D01*
X70000Y2114167D01*
X69300Y2113633D01*
X68500Y2113500D01*
G01X74300Y2121500D02*
Y2115767D01*
X74700Y2114566D01*
X75500Y2113767D01*
X76500Y2113500D01*
X77500Y2113767D01*
X78300Y2114566D01*
X78700Y2115767D01*
Y2121500D01*
G01X82500Y2113500D02*
Y2121500D01*
X84900D01*
X85700Y2121100D01*
X86300Y2120167D01*
X86500Y2119100D01*
X86300Y2118033D01*
X85800Y2117233D01*
X84900Y2116833D01*
X82500D01*
G01X98000Y2113500D02*
X100500Y2121500D01*
X103000Y2113500D01*
G01X102100Y2116300D02*
X98900D01*
G01X118700Y2120833D02*
X118100Y2121233D01*
X117400Y2121500D01*
X116600D01*
X115700Y2121100D01*
X115000Y2120433D01*
X114500Y2119633D01*
X114100Y2118300D01*
X114000Y2117100D01*
X114200Y2115900D01*
X114500Y2115100D01*
X115100Y2114300D01*
X115800Y2113767D01*
X116500Y2113500D01*
X117200D01*
X117900Y2113767D01*
X118500Y2114167D01*
X119000Y2114700D01*
G01X122000Y2113500D02*
X124500Y2121500D01*
X127000Y2113500D01*
G01X126100Y2116300D02*
X122900D01*
G01X130200Y2113500D02*
Y2121500D01*
X134800Y2113500D01*
Y2121500D01*
G01X149300Y2117767D02*
X149700Y2118167D01*
X150000Y2118833D01*
X150200Y2119767D01*
X150000Y2120567D01*
X149600Y2121100D01*
X148900Y2121500D01*
X146200D01*
Y2113500D01*
X149500D01*
X150200Y2114033D01*
X150600Y2114833D01*
X150800Y2115767D01*
X150600Y2116700D01*
X150000Y2117500D01*
X149300Y2117767D01*
X146200D01*
G01X158500Y2113500D02*
X154500D01*
Y2121500D01*
X158500D01*
G01X156900Y2117633D02*
X154500D01*
G01X170500Y2113500D02*
Y2121500D01*
X172900D01*
X173700Y2121100D01*
X174300Y2120167D01*
X174500Y2119100D01*
X174300Y2118033D01*
X173800Y2117233D01*
X172900Y2116833D01*
X170500D01*
G01X178500Y2121500D02*
Y2113500D01*
X182500D01*
G01X186000D02*
X188500Y2121500D01*
X191000Y2113500D01*
G01X190100Y2116300D02*
X186900D01*
G01X198700Y2120833D02*
X198100Y2121233D01*
X197400Y2121500D01*
X196600D01*
X195700Y2121100D01*
X195000Y2120433D01*
X194500Y2119633D01*
X194100Y2118300D01*
X194000Y2117100D01*
X194200Y2115900D01*
X194500Y2115100D01*
X195100Y2114300D01*
X195800Y2113767D01*
X196500Y2113500D01*
X197200D01*
X197900Y2113767D01*
X198500Y2114167D01*
X199000Y2114700D01*
G01X206500Y2113500D02*
X202500D01*
Y2121500D01*
X206500D01*
G01X204900Y2117633D02*
X202500D01*
G01X210300Y2113500D02*
Y2121500D01*
X212300D01*
X213100Y2121100D01*
X213700Y2120567D01*
X214200Y2119767D01*
X214600Y2118833D01*
X214700Y2117500D01*
X214600Y2116167D01*
X214200Y2115233D01*
X213700Y2114433D01*
X213100Y2113900D01*
X212300Y2113500D01*
X210300D01*
G01X226400Y2114566D02*
X227200Y2113900D01*
X228100Y2113500D01*
X228900D01*
X229700Y2113900D01*
X230300Y2114566D01*
X230600Y2115500D01*
X230400Y2116433D01*
X229900Y2117233D01*
X229000Y2117767D01*
X227800Y2118033D01*
X227100Y2118567D01*
X226800Y2119500D01*
X227000Y2120433D01*
X227500Y2121100D01*
X228200Y2121500D01*
X228900D01*
X229600Y2121233D01*
X230200Y2120567D01*
G01X238500Y2113500D02*
X234500D01*
Y2121500D01*
X238500D01*
G01X236900Y2117633D02*
X234500D01*
G01X242500Y2113500D02*
Y2121500D01*
X244900D01*
X245700Y2121100D01*
X246300Y2120167D01*
X246500Y2119100D01*
X246300Y2118033D01*
X245800Y2117233D01*
X244900Y2116833D01*
X242500D01*
G01X250000Y2113500D02*
X252500Y2121500D01*
X255000Y2113500D01*
G01X254100Y2116300D02*
X250900D01*
G01X258500Y2113500D02*
Y2121500D01*
X261000D01*
X261800Y2121100D01*
X262300Y2120567D01*
X262500Y2119500D01*
X262300Y2118433D01*
X261700Y2117767D01*
X261000Y2117367D01*
X258500D01*
G01X261000D02*
X262500Y2113500D01*
G01X266000D02*
X268500Y2121500D01*
X271000Y2113500D01*
G01X270100Y2116300D02*
X266900D01*
G01X276500Y2121500D02*
Y2113500D01*
G01X274200Y2121500D02*
X278800D01*
G01X286500Y2113500D02*
X282500D01*
Y2121500D01*
X286500D01*
G01X284900Y2117633D02*
X282500D01*
G01X290500Y2121500D02*
Y2113500D01*
X294500D01*
G01X300500D02*
Y2117100D01*
X298500Y2121500D01*
G01X302500D02*
X300500Y2117100D01*
G01X314600Y2113500D02*
Y2121500D01*
X318400D01*
G01X317000Y2117633D02*
X314600D01*
G01X322500Y2113500D02*
Y2121500D01*
X325000D01*
X325800Y2121100D01*
X326300Y2120567D01*
X326500Y2119500D01*
X326300Y2118433D01*
X325700Y2117767D01*
X325000Y2117367D01*
X322500D01*
G01X325000D02*
X326500Y2113500D01*
G01X332500D02*
X331700Y2113633D01*
X331000Y2114167D01*
X330400Y2114967D01*
X330000Y2115900D01*
X329800Y2116967D01*
Y2118033D01*
X330000Y2119100D01*
X330400Y2120033D01*
X331000Y2120833D01*
X331700Y2121367D01*
X332500Y2121500D01*
X333300Y2121367D01*
X334000Y2120833D01*
X334600Y2120033D01*
X335000Y2119100D01*
X335200Y2118033D01*
Y2116967D01*
X335000Y2115900D01*
X334600Y2114967D01*
X334000Y2114167D01*
X333300Y2113633D01*
X332500Y2113500D01*
G01X337900D02*
Y2121500D01*
X340500Y2114833D01*
X343100Y2121500D01*
Y2113500D01*
G01X357100Y2117500D02*
X359100D01*
Y2115100D01*
X358500Y2114300D01*
X357800Y2113767D01*
X356800Y2113500D01*
X355800Y2113767D01*
X355100Y2114300D01*
X354500Y2115100D01*
X354100Y2116033D01*
X353900Y2117100D01*
Y2118033D01*
X354100Y2118833D01*
X354500Y2119767D01*
X355100Y2120567D01*
X355700Y2121100D01*
X356500Y2121500D01*
X357200D01*
X358000Y2121233D01*
X358600Y2120700D01*
G01X362500Y2113500D02*
Y2121500D01*
X365000D01*
X365800Y2121100D01*
X366300Y2120567D01*
X366500Y2119500D01*
X366300Y2118433D01*
X365700Y2117767D01*
X365000Y2117367D01*
X362500D01*
G01X365000D02*
X366500Y2113500D01*
G01X372500D02*
X371700Y2113633D01*
X371000Y2114167D01*
X370400Y2114967D01*
X370000Y2115900D01*
X369800Y2116967D01*
Y2118033D01*
X370000Y2119100D01*
X370400Y2120033D01*
X371000Y2120833D01*
X371700Y2121367D01*
X372500Y2121500D01*
X373300Y2121367D01*
X374000Y2120833D01*
X374600Y2120033D01*
X375000Y2119100D01*
X375200Y2118033D01*
Y2116967D01*
X375000Y2115900D01*
X374600Y2114967D01*
X374000Y2114167D01*
X373300Y2113633D01*
X372500Y2113500D01*
G01X378300Y2121500D02*
Y2115767D01*
X378700Y2114566D01*
X379500Y2113767D01*
X380500Y2113500D01*
X381500Y2113767D01*
X382300Y2114566D01*
X382700Y2115767D01*
Y2121500D01*
G01X386500Y2113500D02*
Y2121500D01*
X388900D01*
X389700Y2121100D01*
X390300Y2120167D01*
X390500Y2119100D01*
X390300Y2118033D01*
X389800Y2117233D01*
X388900Y2116833D01*
X386500D01*
G01X405300Y2117767D02*
X405700Y2118167D01*
X406000Y2118833D01*
X406200Y2119767D01*
X406000Y2120567D01*
X405600Y2121100D01*
X404900Y2121500D01*
X402200D01*
Y2113500D01*
X405500D01*
X406200Y2114033D01*
X406600Y2114833D01*
X406800Y2115767D01*
X406600Y2116700D01*
X406000Y2117500D01*
X405300Y2117767D01*
X402200D01*
G01X412500Y2113233D02*
X412300Y2113367D01*
Y2113633D01*
X412500Y2113767D01*
X412700Y2113633D01*
Y2113367D01*
X412500Y2113233D01*
G01X-107500Y2136500D02*
Y2128500D01*
G01X-109800Y2136500D02*
X-105200D01*
G01X-99500Y2128500D02*
X-100300Y2128633D01*
X-101000Y2129167D01*
X-101600Y2129967D01*
X-102000Y2130900D01*
X-102200Y2131967D01*
Y2133033D01*
X-102000Y2134100D01*
X-101600Y2135033D01*
X-101000Y2135833D01*
X-100300Y2136367D01*
X-99500Y2136500D01*
X-98700Y2136367D01*
X-98000Y2135833D01*
X-97400Y2135033D01*
X-97000Y2134100D01*
X-96800Y2133033D01*
Y2131967D01*
X-97000Y2130900D01*
X-97400Y2129967D01*
X-98000Y2129167D01*
X-98700Y2128633D01*
X-99500Y2128500D01*
G01X-83500Y2136500D02*
Y2128500D01*
G01X-85800Y2136500D02*
X-81200D01*
G01X-77600Y2128500D02*
Y2136500D01*
G01X-73400D02*
Y2128500D01*
G01Y2132500D02*
X-77600D01*
G01X-65500Y2128500D02*
X-69500D01*
Y2136500D01*
X-65500D01*
G01X-67100Y2132633D02*
X-69500D01*
G01X-50700Y2132767D02*
X-50300Y2133167D01*
X-50000Y2133833D01*
X-49800Y2134767D01*
X-50000Y2135567D01*
X-50400Y2136100D01*
X-51100Y2136500D01*
X-53800D01*
Y2128500D01*
X-50500D01*
X-49800Y2129033D01*
X-49400Y2129833D01*
X-49200Y2130767D01*
X-49400Y2131700D01*
X-50000Y2132500D01*
X-50700Y2132767D01*
X-53800D01*
G01X-43500Y2128500D02*
X-44300Y2128633D01*
X-45000Y2129167D01*
X-45600Y2129967D01*
X-46000Y2130900D01*
X-46200Y2131967D01*
Y2133033D01*
X-46000Y2134100D01*
X-45600Y2135033D01*
X-45000Y2135833D01*
X-44300Y2136367D01*
X-43500Y2136500D01*
X-42700Y2136367D01*
X-42000Y2135833D01*
X-41400Y2135033D01*
X-41000Y2134100D01*
X-40800Y2133033D01*
Y2131967D01*
X-41000Y2130900D01*
X-41400Y2129967D01*
X-42000Y2129167D01*
X-42700Y2128633D01*
X-43500Y2128500D01*
G01X-38000D02*
X-35500Y2136500D01*
X-33000Y2128500D01*
G01X-33900Y2131300D02*
X-37100D01*
G01X-29500Y2128500D02*
Y2136500D01*
X-27000D01*
X-26200Y2136100D01*
X-25700Y2135567D01*
X-25500Y2134500D01*
X-25700Y2133433D01*
X-26300Y2132767D01*
X-27000Y2132367D01*
X-29500D01*
G01X-27000D02*
X-25500Y2128500D01*
G01X-21700D02*
Y2136500D01*
X-19700D01*
X-18900Y2136100D01*
X-18300Y2135567D01*
X-17800Y2134767D01*
X-17400Y2133833D01*
X-17300Y2132500D01*
X-17400Y2131167D01*
X-17800Y2130233D01*
X-18300Y2129433D01*
X-18900Y2128900D01*
X-19700Y2128500D01*
X-21700D01*
G01X-1300Y2135833D02*
X-1900Y2136233D01*
X-2600Y2136500D01*
X-3400D01*
X-4300Y2136100D01*
X-5000Y2135433D01*
X-5500Y2134633D01*
X-5900Y2133300D01*
X-6000Y2132100D01*
X-5800Y2130900D01*
X-5500Y2130100D01*
X-4900Y2129300D01*
X-4200Y2128767D01*
X-3500Y2128500D01*
X-2800D01*
X-2100Y2128767D01*
X-1500Y2129167D01*
X-1000Y2129700D01*
G01X4500Y2128500D02*
X3700Y2128633D01*
X3000Y2129167D01*
X2400Y2129967D01*
X2000Y2130900D01*
X1800Y2131967D01*
Y2133033D01*
X2000Y2134100D01*
X2400Y2135033D01*
X3000Y2135833D01*
X3700Y2136367D01*
X4500Y2136500D01*
X5300Y2136367D01*
X6000Y2135833D01*
X6600Y2135033D01*
X7000Y2134100D01*
X7200Y2133033D01*
Y2131967D01*
X7000Y2130900D01*
X6600Y2129967D01*
X6000Y2129167D01*
X5300Y2128633D01*
X4500Y2128500D01*
G01X10300Y2136500D02*
Y2130767D01*
X10700Y2129566D01*
X11500Y2128767D01*
X12500Y2128500D01*
X13500Y2128767D01*
X14300Y2129566D01*
X14700Y2130767D01*
Y2136500D01*
G01X18500Y2128500D02*
Y2136500D01*
X20900D01*
X21700Y2136100D01*
X22300Y2135167D01*
X22500Y2134100D01*
X22300Y2133033D01*
X21800Y2132233D01*
X20900Y2131833D01*
X18500D01*
G01X28500Y2128500D02*
X27700Y2128633D01*
X27000Y2129167D01*
X26400Y2129967D01*
X26000Y2130900D01*
X25800Y2131967D01*
Y2133033D01*
X26000Y2134100D01*
X26400Y2135033D01*
X27000Y2135833D01*
X27700Y2136367D01*
X28500Y2136500D01*
X29300Y2136367D01*
X30000Y2135833D01*
X30600Y2135033D01*
X31000Y2134100D01*
X31200Y2133033D01*
Y2131967D01*
X31000Y2130900D01*
X30600Y2129967D01*
X30000Y2129167D01*
X29300Y2128633D01*
X28500Y2128500D01*
G01X34200D02*
Y2136500D01*
X38800Y2128500D01*
Y2136500D01*
G01X42400Y2129566D02*
X43200Y2128900D01*
X44100Y2128500D01*
X44900D01*
X45700Y2128900D01*
X46300Y2129566D01*
X46600Y2130500D01*
X46400Y2131433D01*
X45900Y2132233D01*
X45000Y2132767D01*
X43800Y2133033D01*
X43100Y2133567D01*
X42800Y2134500D01*
X43000Y2135433D01*
X43500Y2136100D01*
X44200Y2136500D01*
X44900D01*
X45600Y2136233D01*
X46200Y2135567D01*
G01X52500Y2128233D02*
X52300Y2128367D01*
Y2128633D01*
X52500Y2128767D01*
X52700Y2128633D01*
Y2128367D01*
X52500Y2128233D01*
G01X59300Y2136500D02*
X61700D01*
G01X60500D02*
Y2128500D01*
G01X59300D02*
X61700D01*
G01X66600D02*
Y2136500D01*
X70400D01*
G01X69000Y2132633D02*
X66600D01*
G01X83300Y2136500D02*
X85700D01*
G01X84500D02*
Y2128500D01*
G01X83300D02*
X85700D01*
G01X92500Y2136500D02*
Y2128500D01*
G01X90200Y2136500D02*
X94800D01*
G01X107300D02*
X109700D01*
G01X108500D02*
Y2128500D01*
G01X107300D02*
X109700D01*
G01X114400Y2129566D02*
X115200Y2128900D01*
X116100Y2128500D01*
X116900D01*
X117700Y2128900D01*
X118300Y2129566D01*
X118600Y2130500D01*
X118400Y2131433D01*
X117900Y2132233D01*
X117000Y2132767D01*
X115800Y2133033D01*
X115100Y2133567D01*
X114800Y2134500D01*
X115000Y2135433D01*
X115500Y2136100D01*
X116200Y2136500D01*
X116900D01*
X117600Y2136233D01*
X118200Y2135567D01*
G01X130200Y2128500D02*
Y2136500D01*
X134800Y2128500D01*
Y2136500D01*
G01X140500Y2128500D02*
X139700Y2128633D01*
X139000Y2129167D01*
X138400Y2129967D01*
X138000Y2130900D01*
X137800Y2131967D01*
Y2133033D01*
X138000Y2134100D01*
X138400Y2135033D01*
X139000Y2135833D01*
X139700Y2136367D01*
X140500Y2136500D01*
X141300Y2136367D01*
X142000Y2135833D01*
X142600Y2135033D01*
X143000Y2134100D01*
X143200Y2133033D01*
Y2131967D01*
X143000Y2130900D01*
X142600Y2129967D01*
X142000Y2129167D01*
X141300Y2128633D01*
X140500Y2128500D01*
G01X148500Y2136500D02*
Y2128500D01*
G01X146200Y2136500D02*
X150800D01*
G01X162500Y2128500D02*
Y2136500D01*
X164900D01*
X165700Y2136100D01*
X166300Y2135167D01*
X166500Y2134100D01*
X166300Y2133033D01*
X165800Y2132233D01*
X164900Y2131833D01*
X162500D01*
G01X172500Y2128500D02*
X171700Y2128633D01*
X171000Y2129167D01*
X170400Y2129967D01*
X170000Y2130900D01*
X169800Y2131967D01*
Y2133033D01*
X170000Y2134100D01*
X170400Y2135033D01*
X171000Y2135833D01*
X171700Y2136367D01*
X172500Y2136500D01*
X173300Y2136367D01*
X174000Y2135833D01*
X174600Y2135033D01*
X175000Y2134100D01*
X175200Y2133033D01*
Y2131967D01*
X175000Y2130900D01*
X174600Y2129967D01*
X174000Y2129167D01*
X173300Y2128633D01*
X172500Y2128500D01*
G01X178400Y2129566D02*
X179200Y2128900D01*
X180100Y2128500D01*
X180900D01*
X181700Y2128900D01*
X182300Y2129566D01*
X182600Y2130500D01*
X182400Y2131433D01*
X181900Y2132233D01*
X181000Y2132767D01*
X179800Y2133033D01*
X179100Y2133567D01*
X178800Y2134500D01*
X179000Y2135433D01*
X179500Y2136100D01*
X180200Y2136500D01*
X180900D01*
X181600Y2136233D01*
X182200Y2135567D01*
G01X186400Y2129566D02*
X187200Y2128900D01*
X188100Y2128500D01*
X188900D01*
X189700Y2128900D01*
X190300Y2129566D01*
X190600Y2130500D01*
X190400Y2131433D01*
X189900Y2132233D01*
X189000Y2132767D01*
X187800Y2133033D01*
X187100Y2133567D01*
X186800Y2134500D01*
X187000Y2135433D01*
X187500Y2136100D01*
X188200Y2136500D01*
X188900D01*
X189600Y2136233D01*
X190200Y2135567D01*
G01X195300Y2136500D02*
X197700D01*
G01X196500D02*
Y2128500D01*
G01X195300D02*
X197700D01*
G01X205300Y2132767D02*
X205700Y2133167D01*
X206000Y2133833D01*
X206200Y2134767D01*
X206000Y2135567D01*
X205600Y2136100D01*
X204900Y2136500D01*
X202200D01*
Y2128500D01*
X205500D01*
X206200Y2129033D01*
X206600Y2129833D01*
X206800Y2130767D01*
X206600Y2131700D01*
X206000Y2132500D01*
X205300Y2132767D01*
X202200D01*
G01X210500Y2136500D02*
Y2128500D01*
X214500D01*
G01X222500D02*
X218500D01*
Y2136500D01*
X222500D01*
G01X220900Y2132633D02*
X218500D01*
G01X236500Y2136500D02*
Y2128500D01*
G01X234200Y2136500D02*
X238800D01*
G01X244500Y2128500D02*
X243700Y2128633D01*
X243000Y2129167D01*
X242400Y2129967D01*
X242000Y2130900D01*
X241800Y2131967D01*
Y2133033D01*
X242000Y2134100D01*
X242400Y2135033D01*
X243000Y2135833D01*
X243700Y2136367D01*
X244500Y2136500D01*
X245300Y2136367D01*
X246000Y2135833D01*
X246600Y2135033D01*
X247000Y2134100D01*
X247200Y2133033D01*
Y2131967D01*
X247000Y2130900D01*
X246600Y2129967D01*
X246000Y2129167D01*
X245300Y2128633D01*
X244500Y2128500D01*
G01X258600D02*
Y2136500D01*
X262400D01*
G01X261000Y2132633D02*
X258600D01*
G01X267300Y2136500D02*
X269700D01*
G01X268500D02*
Y2128500D01*
G01X267300D02*
X269700D01*
G01X276500Y2136500D02*
Y2128500D01*
G01X274200Y2136500D02*
X278800D01*
G01X291300D02*
X293700D01*
G01X292500D02*
Y2128500D01*
G01X291300D02*
X293700D01*
G01X298200D02*
Y2136500D01*
X302800Y2128500D01*
Y2136500D01*
G01X316500D02*
Y2128500D01*
G01X314200Y2136500D02*
X318800D01*
G01X322400Y2128500D02*
Y2136500D01*
G01X326600D02*
Y2128500D01*
G01Y2132500D02*
X322400D01*
G01X334500Y2128500D02*
X330500D01*
Y2136500D01*
X334500D01*
G01X332900Y2132633D02*
X330500D01*
G01X346500Y2136500D02*
Y2128500D01*
X350500D01*
G01X356500D02*
X355700Y2128633D01*
X355000Y2129167D01*
X354400Y2129967D01*
X354000Y2130900D01*
X353800Y2131967D01*
Y2133033D01*
X354000Y2134100D01*
X354400Y2135033D01*
X355000Y2135833D01*
X355700Y2136367D01*
X356500Y2136500D01*
X357300Y2136367D01*
X358000Y2135833D01*
X358600Y2135033D01*
X359000Y2134100D01*
X359200Y2133033D01*
Y2131967D01*
X359000Y2130900D01*
X358600Y2129967D01*
X358000Y2129167D01*
X357300Y2128633D01*
X356500Y2128500D01*
G01X366700Y2135833D02*
X366100Y2136233D01*
X365400Y2136500D01*
X364600D01*
X363700Y2136100D01*
X363000Y2135433D01*
X362500Y2134633D01*
X362100Y2133300D01*
X362000Y2132100D01*
X362200Y2130900D01*
X362500Y2130100D01*
X363100Y2129300D01*
X363800Y2128767D01*
X364500Y2128500D01*
X365200D01*
X365900Y2128767D01*
X366500Y2129167D01*
X367000Y2129700D01*
G01X370000Y2128500D02*
X372500Y2136500D01*
X375000Y2128500D01*
G01X374100Y2131300D02*
X370900D01*
G01X380500Y2136500D02*
Y2128500D01*
G01X378200Y2136500D02*
X382800D01*
G01X387300D02*
X389700D01*
G01X388500D02*
Y2128500D01*
G01X387300D02*
X389700D01*
G01X396500D02*
X395700Y2128633D01*
X395000Y2129167D01*
X394400Y2129967D01*
X394000Y2130900D01*
X393800Y2131967D01*
Y2133033D01*
X394000Y2134100D01*
X394400Y2135033D01*
X395000Y2135833D01*
X395700Y2136367D01*
X396500Y2136500D01*
X397300Y2136367D01*
X398000Y2135833D01*
X398600Y2135033D01*
X399000Y2134100D01*
X399200Y2133033D01*
Y2131967D01*
X399000Y2130900D01*
X398600Y2129967D01*
X398000Y2129167D01*
X397300Y2128633D01*
X396500Y2128500D01*
G01X402200D02*
Y2136500D01*
X406800Y2128500D01*
Y2136500D01*
G01X410400Y2129566D02*
X411200Y2128900D01*
X412100Y2128500D01*
X412900D01*
X413700Y2128900D01*
X414300Y2129566D01*
X414600Y2130500D01*
X414400Y2131433D01*
X413900Y2132233D01*
X413000Y2132767D01*
X411800Y2133033D01*
X411100Y2133567D01*
X410800Y2134500D01*
X411000Y2135433D01*
X411500Y2136100D01*
X412200Y2136500D01*
X412900D01*
X413600Y2136233D01*
X414200Y2135567D01*
G01X426600Y2128500D02*
Y2136500D01*
X430400D01*
G01X429000Y2132633D02*
X426600D01*
G01X436500Y2128500D02*
X435700Y2128633D01*
X435000Y2129167D01*
X434400Y2129967D01*
X434000Y2130900D01*
X433800Y2131967D01*
Y2133033D01*
X434000Y2134100D01*
X434400Y2135033D01*
X435000Y2135833D01*
X435700Y2136367D01*
X436500Y2136500D01*
X437300Y2136367D01*
X438000Y2135833D01*
X438600Y2135033D01*
X439000Y2134100D01*
X439200Y2133033D01*
Y2131967D01*
X439000Y2130900D01*
X438600Y2129967D01*
X438000Y2129167D01*
X437300Y2128633D01*
X436500Y2128500D01*
G01X442500D02*
Y2136500D01*
X445000D01*
X445800Y2136100D01*
X446300Y2135567D01*
X446500Y2134500D01*
X446300Y2133433D01*
X445700Y2132767D01*
X445000Y2132367D01*
X442500D01*
G01X445000D02*
X446500Y2128500D01*
G01X461300Y2132767D02*
X461700Y2133167D01*
X462000Y2133833D01*
X462200Y2134767D01*
X462000Y2135567D01*
X461600Y2136100D01*
X460900Y2136500D01*
X458200D01*
Y2128500D01*
X461500D01*
X462200Y2129033D01*
X462600Y2129833D01*
X462800Y2130767D01*
X462600Y2131700D01*
X462000Y2132500D01*
X461300Y2132767D01*
X458200D01*
G01X468500Y2128500D02*
X467700Y2128633D01*
X467000Y2129167D01*
X466400Y2129967D01*
X466000Y2130900D01*
X465800Y2131967D01*
Y2133033D01*
X466000Y2134100D01*
X466400Y2135033D01*
X467000Y2135833D01*
X467700Y2136367D01*
X468500Y2136500D01*
X469300Y2136367D01*
X470000Y2135833D01*
X470600Y2135033D01*
X471000Y2134100D01*
X471200Y2133033D01*
Y2131967D01*
X471000Y2130900D01*
X470600Y2129967D01*
X470000Y2129167D01*
X469300Y2128633D01*
X468500Y2128500D01*
G01X476500Y2136500D02*
Y2128500D01*
G01X474200Y2136500D02*
X478800D01*
G01X482400Y2128500D02*
Y2136500D01*
G01X486600D02*
Y2128500D01*
G01Y2132500D02*
X482400D01*
G01X-109500Y2143500D02*
Y2151500D01*
X-107100D01*
X-106300Y2151100D01*
X-105700Y2150167D01*
X-105500Y2149100D01*
X-105700Y2148033D01*
X-106200Y2147233D01*
X-107100Y2146833D01*
X-109500D01*
G01X-101500Y2151500D02*
Y2143500D01*
X-97500D01*
G01X-89500D02*
X-93500D01*
Y2151500D01*
X-89500D01*
G01X-91100Y2147633D02*
X-93500D01*
G01X-86000Y2143500D02*
X-83500Y2151500D01*
X-81000Y2143500D01*
G01X-81900Y2146300D02*
X-85100D01*
G01X-77600Y2144566D02*
X-76800Y2143900D01*
X-75900Y2143500D01*
X-75100D01*
X-74300Y2143900D01*
X-73700Y2144566D01*
X-73400Y2145500D01*
X-73600Y2146433D01*
X-74100Y2147233D01*
X-75000Y2147767D01*
X-76200Y2148033D01*
X-76900Y2148567D01*
X-77200Y2149500D01*
X-77000Y2150433D01*
X-76500Y2151100D01*
X-75800Y2151500D01*
X-75100D01*
X-74400Y2151233D01*
X-73800Y2150567D01*
G01X-65500Y2143500D02*
X-69500D01*
Y2151500D01*
X-65500D01*
G01X-67100Y2147633D02*
X-69500D01*
G01X-53400Y2143500D02*
Y2151500D01*
X-49600D01*
G01X-51000Y2147633D02*
X-53400D01*
G01X-43500Y2143500D02*
X-44300Y2143633D01*
X-45000Y2144167D01*
X-45600Y2144967D01*
X-46000Y2145900D01*
X-46200Y2146967D01*
Y2148033D01*
X-46000Y2149100D01*
X-45600Y2150033D01*
X-45000Y2150833D01*
X-44300Y2151367D01*
X-43500Y2151500D01*
X-42700Y2151367D01*
X-42000Y2150833D01*
X-41400Y2150033D01*
X-41000Y2149100D01*
X-40800Y2148033D01*
Y2146967D01*
X-41000Y2145900D01*
X-41400Y2144967D01*
X-42000Y2144167D01*
X-42700Y2143633D01*
X-43500Y2143500D01*
G01X-37500Y2151500D02*
Y2143500D01*
X-33500D01*
G01X-29500Y2151500D02*
Y2143500D01*
X-25500D01*
G01X-19500D02*
X-20300Y2143633D01*
X-21000Y2144167D01*
X-21600Y2144967D01*
X-22000Y2145900D01*
X-22200Y2146967D01*
Y2148033D01*
X-22000Y2149100D01*
X-21600Y2150033D01*
X-21000Y2150833D01*
X-20300Y2151367D01*
X-19500Y2151500D01*
X-18700Y2151367D01*
X-18000Y2150833D01*
X-17400Y2150033D01*
X-17000Y2149100D01*
X-16800Y2148033D01*
Y2146967D01*
X-17000Y2145900D01*
X-17400Y2144967D01*
X-18000Y2144167D01*
X-18700Y2143633D01*
X-19500Y2143500D01*
G01X-14500Y2151500D02*
X-13100Y2143500D01*
X-11500Y2151500D01*
X-9900Y2143500D01*
X-8500Y2151500D01*
G01X4500D02*
Y2143500D01*
G01X2200Y2151500D02*
X6800D01*
G01X10400Y2143500D02*
Y2151500D01*
G01X14600D02*
Y2143500D01*
G01Y2147500D02*
X10400D01*
G01X22500Y2143500D02*
X18500D01*
Y2151500D01*
X22500D01*
G01X20900Y2147633D02*
X18500D01*
G01X34400Y2144566D02*
X35200Y2143900D01*
X36100Y2143500D01*
X36900D01*
X37700Y2143900D01*
X38300Y2144566D01*
X38600Y2145500D01*
X38400Y2146433D01*
X37900Y2147233D01*
X37000Y2147767D01*
X35800Y2148033D01*
X35100Y2148567D01*
X34800Y2149500D01*
X35000Y2150433D01*
X35500Y2151100D01*
X36200Y2151500D01*
X36900D01*
X37600Y2151233D01*
X38200Y2150567D01*
G01X42500Y2151500D02*
Y2143500D01*
X46500D01*
G01X51300Y2151500D02*
X53700D01*
G01X52500D02*
Y2143500D01*
G01X51300D02*
X53700D01*
G01X58300D02*
Y2151500D01*
X60300D01*
X61100Y2151100D01*
X61700Y2150567D01*
X62200Y2149767D01*
X62600Y2148833D01*
X62700Y2147500D01*
X62600Y2146167D01*
X62200Y2145233D01*
X61700Y2144433D01*
X61100Y2143900D01*
X60300Y2143500D01*
X58300D01*
G01X70500D02*
X66500D01*
Y2151500D01*
X70500D01*
G01X68900Y2147633D02*
X66500D01*
G01X74400Y2144566D02*
X75200Y2143900D01*
X76100Y2143500D01*
X76900D01*
X77700Y2143900D01*
X78300Y2144566D01*
X78600Y2145500D01*
X78400Y2146433D01*
X77900Y2147233D01*
X77000Y2147767D01*
X75800Y2148033D01*
X75100Y2148567D01*
X74800Y2149500D01*
X75000Y2150433D01*
X75500Y2151100D01*
X76200Y2151500D01*
X76900D01*
X77600Y2151233D01*
X78200Y2150567D01*
G01X92500Y2151500D02*
Y2143500D01*
G01X90200Y2151500D02*
X94800D01*
G01X100500Y2143500D02*
X99700Y2143633D01*
X99000Y2144167D01*
X98400Y2144967D01*
X98000Y2145900D01*
X97800Y2146967D01*
Y2148033D01*
X98000Y2149100D01*
X98400Y2150033D01*
X99000Y2150833D01*
X99700Y2151367D01*
X100500Y2151500D01*
X101300Y2151367D01*
X102000Y2150833D01*
X102600Y2150033D01*
X103000Y2149100D01*
X103200Y2148033D01*
Y2146967D01*
X103000Y2145900D01*
X102600Y2144967D01*
X102000Y2144167D01*
X101300Y2143633D01*
X100500Y2143500D01*
G01X117100Y2147500D02*
X119100D01*
Y2145100D01*
X118500Y2144300D01*
X117800Y2143767D01*
X116800Y2143500D01*
X115800Y2143767D01*
X115100Y2144300D01*
X114500Y2145100D01*
X114100Y2146033D01*
X113900Y2147100D01*
Y2148033D01*
X114100Y2148833D01*
X114500Y2149767D01*
X115100Y2150567D01*
X115700Y2151100D01*
X116500Y2151500D01*
X117200D01*
X118000Y2151233D01*
X118600Y2150700D01*
G01X126500Y2143500D02*
X122500D01*
Y2151500D01*
X126500D01*
G01X124900Y2147633D02*
X122500D01*
G01X130200Y2143500D02*
Y2151500D01*
X134800Y2143500D01*
Y2151500D01*
G01X142500Y2143500D02*
X138500D01*
Y2151500D01*
X142500D01*
G01X140900Y2147633D02*
X138500D01*
G01X146500Y2143500D02*
Y2151500D01*
X149000D01*
X149800Y2151100D01*
X150300Y2150567D01*
X150500Y2149500D01*
X150300Y2148433D01*
X149700Y2147767D01*
X149000Y2147367D01*
X146500D01*
G01X149000D02*
X150500Y2143500D01*
G01X154000D02*
X156500Y2151500D01*
X159000Y2143500D01*
G01X158100Y2146300D02*
X154900D01*
G01X164500Y2151500D02*
Y2143500D01*
G01X162200Y2151500D02*
X166800D01*
G01X174500Y2143500D02*
X170500D01*
Y2151500D01*
X174500D01*
G01X172900Y2147633D02*
X170500D01*
G01X188500Y2151500D02*
Y2143500D01*
G01X186200Y2151500D02*
X190800D01*
G01X194400Y2143500D02*
Y2151500D01*
G01X198600D02*
Y2143500D01*
G01Y2147500D02*
X194400D01*
G01X206500Y2143500D02*
X202500D01*
Y2151500D01*
X206500D01*
G01X204900Y2147633D02*
X202500D01*
G01X218500Y2143500D02*
Y2151500D01*
X220900D01*
X221700Y2151100D01*
X222300Y2150167D01*
X222500Y2149100D01*
X222300Y2148033D01*
X221800Y2147233D01*
X220900Y2146833D01*
X218500D01*
G01X226000Y2143500D02*
X228500Y2151500D01*
X231000Y2143500D01*
G01X230100Y2146300D02*
X226900D01*
G01X234300Y2143500D02*
Y2151500D01*
X236300D01*
X237100Y2151100D01*
X237700Y2150567D01*
X238200Y2149767D01*
X238600Y2148833D01*
X238700Y2147500D01*
X238600Y2146167D01*
X238200Y2145233D01*
X237700Y2144433D01*
X237100Y2143900D01*
X236300Y2143500D01*
X234300D01*
G01X242400Y2144566D02*
X243200Y2143900D01*
X244100Y2143500D01*
X244900D01*
X245700Y2143900D01*
X246300Y2144566D01*
X246600Y2145500D01*
X246400Y2146433D01*
X245900Y2147233D01*
X245000Y2147767D01*
X243800Y2148033D01*
X243100Y2148567D01*
X242800Y2149500D01*
X243000Y2150433D01*
X243500Y2151100D01*
X244200Y2151500D01*
X244900D01*
X245600Y2151233D01*
X246200Y2150567D01*
G01X258000Y2143500D02*
X260500Y2151500D01*
X263000Y2143500D01*
G01X262100Y2146300D02*
X258900D01*
G01X266200Y2143500D02*
Y2151500D01*
X270800Y2143500D01*
Y2151500D01*
G01X274300Y2143500D02*
Y2151500D01*
X276300D01*
X277100Y2151100D01*
X277700Y2150567D01*
X278200Y2149767D01*
X278600Y2148833D01*
X278700Y2147500D01*
X278600Y2146167D01*
X278200Y2145233D01*
X277700Y2144433D01*
X277100Y2143900D01*
X276300Y2143500D01*
X274300D01*
G01X289900D02*
Y2151500D01*
X292500Y2144833D01*
X295100Y2151500D01*
Y2143500D01*
G01X298000D02*
X300500Y2151500D01*
X303000Y2143500D01*
G01X302100Y2146300D02*
X298900D01*
G01X306400Y2144566D02*
X307200Y2143900D01*
X308100Y2143500D01*
X308900D01*
X309700Y2143900D01*
X310300Y2144566D01*
X310600Y2145500D01*
X310400Y2146433D01*
X309900Y2147233D01*
X309000Y2147767D01*
X307800Y2148033D01*
X307100Y2148567D01*
X306800Y2149500D01*
X307000Y2150433D01*
X307500Y2151100D01*
X308200Y2151500D01*
X308900D01*
X309600Y2151233D01*
X310200Y2150567D01*
G01X314300Y2143500D02*
Y2151500D01*
G01X318100D02*
X314300Y2146566D01*
G01X318700Y2143500D02*
X316000Y2148833D01*
G01X330000Y2143500D02*
X332500Y2151500D01*
X335000Y2143500D01*
G01X334100Y2146300D02*
X330900D01*
G01X338200Y2143500D02*
Y2151500D01*
X342800Y2143500D01*
Y2151500D01*
G01X346300Y2143500D02*
Y2151500D01*
X348300D01*
X349100Y2151100D01*
X349700Y2150567D01*
X350200Y2149767D01*
X350600Y2148833D01*
X350700Y2147500D01*
X350600Y2146167D01*
X350200Y2145233D01*
X349700Y2144433D01*
X349100Y2143900D01*
X348300Y2143500D01*
X346300D01*
G01X362000D02*
X364500Y2151500D01*
X367000Y2143500D01*
G01X366100Y2146300D02*
X362900D01*
G01X370300Y2143500D02*
Y2151500D01*
X372300D01*
X373100Y2151100D01*
X373700Y2150567D01*
X374200Y2149767D01*
X374600Y2148833D01*
X374700Y2147500D01*
X374600Y2146167D01*
X374200Y2145233D01*
X373700Y2144433D01*
X373100Y2143900D01*
X372300Y2143500D01*
X370300D01*
G01X378300D02*
Y2151500D01*
X380300D01*
X381100Y2151100D01*
X381700Y2150567D01*
X382200Y2149767D01*
X382600Y2148833D01*
X382700Y2147500D01*
X382600Y2146167D01*
X382200Y2145233D01*
X381700Y2144433D01*
X381100Y2143900D01*
X380300Y2143500D01*
X378300D01*
G01X396500Y2151500D02*
Y2143500D01*
G01X394200Y2151500D02*
X398800D01*
G01X402400Y2143500D02*
Y2151500D01*
G01X406600D02*
Y2143500D01*
G01Y2147500D02*
X402400D01*
G01X414500Y2143500D02*
X410500D01*
Y2151500D01*
X414500D01*
G01X412900Y2147633D02*
X410500D01*
G01X428500Y2151500D02*
Y2143500D01*
G01X426200Y2151500D02*
X430800D01*
G01X438500Y2143500D02*
X434500D01*
Y2151500D01*
X438500D01*
G01X436900Y2147633D02*
X434500D01*
G01X442400Y2144566D02*
X443200Y2143900D01*
X444100Y2143500D01*
X444900D01*
X445700Y2143900D01*
X446300Y2144566D01*
X446600Y2145500D01*
X446400Y2146433D01*
X445900Y2147233D01*
X445000Y2147767D01*
X443800Y2148033D01*
X443100Y2148567D01*
X442800Y2149500D01*
X443000Y2150433D01*
X443500Y2151100D01*
X444200Y2151500D01*
X444900D01*
X445600Y2151233D01*
X446200Y2150567D01*
G01X452500Y2151500D02*
Y2143500D01*
G01X450200Y2151500D02*
X454800D01*
G01X466500Y2143500D02*
Y2151500D01*
X468900D01*
X469700Y2151100D01*
X470300Y2150167D01*
X470500Y2149100D01*
X470300Y2148033D01*
X469800Y2147233D01*
X468900Y2146833D01*
X466500D01*
G01X474000Y2143500D02*
X476500Y2151500D01*
X479000Y2143500D01*
G01X478100Y2146300D02*
X474900D01*
G01X482300Y2143500D02*
Y2151500D01*
X484300D01*
X485100Y2151100D01*
X485700Y2150567D01*
X486200Y2149767D01*
X486600Y2148833D01*
X486700Y2147500D01*
X486600Y2146167D01*
X486200Y2145233D01*
X485700Y2144433D01*
X485100Y2143900D01*
X484300Y2143500D01*
X482300D01*
G01X490400Y2144566D02*
X491200Y2143900D01*
X492100Y2143500D01*
X492900D01*
X493700Y2143900D01*
X494300Y2144566D01*
X494600Y2145500D01*
X494400Y2146433D01*
X493900Y2147233D01*
X493000Y2147767D01*
X491800Y2148033D01*
X491100Y2148567D01*
X490800Y2149500D01*
X491000Y2150433D01*
X491500Y2151100D01*
X492200Y2151500D01*
X492900D01*
X493600Y2151233D01*
X494200Y2150567D01*
G01X-124700Y2159700D02*
X-124100Y2159033D01*
X-123400Y2158633D01*
X-122500Y2158500D01*
X-121600Y2158767D01*
X-120900Y2159300D01*
X-120400Y2160233D01*
X-120300Y2161300D01*
X-120500Y2162367D01*
X-121000Y2163033D01*
X-121700Y2163567D01*
X-122400Y2163700D01*
X-123100Y2163567D01*
X-124000Y2163033D01*
X-123700Y2166500D01*
X-121000D01*
G01X-114500Y2158233D02*
X-114700Y2158367D01*
Y2158633D01*
X-114500Y2158767D01*
X-114300Y2158633D01*
Y2158367D01*
X-114500Y2158233D01*
G01X-108500Y2158500D02*
Y2166500D01*
X-106100D01*
X-105300Y2166100D01*
X-104700Y2165167D01*
X-104500Y2164100D01*
X-104700Y2163033D01*
X-105200Y2162233D01*
X-106100Y2161833D01*
X-108500D01*
G01X-96500Y2158500D02*
X-100500D01*
Y2166500D01*
X-96500D01*
G01X-98100Y2162633D02*
X-100500D01*
G01X-88500Y2158500D02*
X-92500D01*
Y2166500D01*
X-88500D01*
G01X-90100Y2162633D02*
X-92500D01*
G01X-84500Y2166500D02*
Y2158500D01*
X-80500D01*
G01X-75700Y2166500D02*
X-73300D01*
G01X-74500D02*
Y2158500D01*
G01X-75700D02*
X-73300D01*
G01X-68800D02*
Y2166500D01*
X-64200Y2158500D01*
Y2166500D01*
G01X-57900Y2162500D02*
X-55900D01*
Y2160100D01*
X-56500Y2159300D01*
X-57200Y2158767D01*
X-58200Y2158500D01*
X-59200Y2158767D01*
X-59900Y2159300D01*
X-60500Y2160100D01*
X-60900Y2161033D01*
X-61100Y2162100D01*
Y2163033D01*
X-60900Y2163833D01*
X-60500Y2164767D01*
X-59900Y2165567D01*
X-59300Y2166100D01*
X-58500Y2166500D01*
X-57800D01*
X-57000Y2166233D01*
X-56400Y2165700D01*
G01X-44600Y2159566D02*
X-43800Y2158900D01*
X-42900Y2158500D01*
X-42100D01*
X-41300Y2158900D01*
X-40700Y2159566D01*
X-40400Y2160500D01*
X-40600Y2161433D01*
X-41100Y2162233D01*
X-42000Y2162767D01*
X-43200Y2163033D01*
X-43900Y2163567D01*
X-44200Y2164500D01*
X-44000Y2165433D01*
X-43500Y2166100D01*
X-42800Y2166500D01*
X-42100D01*
X-41400Y2166233D01*
X-40800Y2165567D01*
G01X-34500Y2166500D02*
Y2158500D01*
G01X-36800Y2166500D02*
X-32200D01*
G01X-28500Y2158500D02*
Y2166500D01*
X-26000D01*
X-25200Y2166100D01*
X-24700Y2165567D01*
X-24500Y2164500D01*
X-24700Y2163433D01*
X-25300Y2162767D01*
X-26000Y2162367D01*
X-28500D01*
G01X-26000D02*
X-24500Y2158500D01*
G01X-16500D02*
X-20500D01*
Y2166500D01*
X-16500D01*
G01X-18100Y2162633D02*
X-20500D01*
G01X-12800Y2158500D02*
Y2166500D01*
X-8200Y2158500D01*
Y2166500D01*
G01X-1900Y2162500D02*
X100D01*
Y2160100D01*
X-500Y2159300D01*
X-1200Y2158767D01*
X-2200Y2158500D01*
X-3200Y2158767D01*
X-3900Y2159300D01*
X-4500Y2160100D01*
X-4900Y2161033D01*
X-5100Y2162100D01*
Y2163033D01*
X-4900Y2163833D01*
X-4500Y2164767D01*
X-3900Y2165567D01*
X-3300Y2166100D01*
X-2500Y2166500D01*
X-1800D01*
X-1000Y2166233D01*
X-400Y2165700D01*
G01X5500Y2166500D02*
Y2158500D01*
G01X3200Y2166500D02*
X7800D01*
G01X11400Y2158500D02*
Y2166500D01*
G01X15600D02*
Y2158500D01*
G01Y2162500D02*
X11400D01*
G01X27000Y2158500D02*
X29500Y2166500D01*
X32000Y2158500D01*
G01X31100Y2161300D02*
X27900D01*
G01X35200Y2158500D02*
Y2166500D01*
X39800Y2158500D01*
Y2166500D01*
G01X43300Y2158500D02*
Y2166500D01*
X45300D01*
X46100Y2166100D01*
X46700Y2165567D01*
X47200Y2164767D01*
X47600Y2163833D01*
X47700Y2162500D01*
X47600Y2161167D01*
X47200Y2160233D01*
X46700Y2159433D01*
X46100Y2158900D01*
X45300Y2158500D01*
X43300D01*
G01X62300Y2162767D02*
X62700Y2163167D01*
X63000Y2163833D01*
X63200Y2164767D01*
X63000Y2165567D01*
X62600Y2166100D01*
X61900Y2166500D01*
X59200D01*
Y2158500D01*
X62500D01*
X63200Y2159033D01*
X63600Y2159833D01*
X63800Y2160767D01*
X63600Y2161700D01*
X63000Y2162500D01*
X62300Y2162767D01*
X59200D01*
G01X70100Y2162500D02*
X72100D01*
Y2160100D01*
X71500Y2159300D01*
X70800Y2158767D01*
X69800Y2158500D01*
X68800Y2158767D01*
X68100Y2159300D01*
X67500Y2160100D01*
X67100Y2161033D01*
X66900Y2162100D01*
Y2163033D01*
X67100Y2163833D01*
X67500Y2164767D01*
X68100Y2165567D01*
X68700Y2166100D01*
X69500Y2166500D01*
X70200D01*
X71000Y2166233D01*
X71600Y2165700D01*
G01X75000Y2158500D02*
X77500Y2166500D01*
X80000Y2158500D01*
G01X79100Y2161300D02*
X75900D01*
G01X91500Y2158500D02*
Y2166500D01*
X93900D01*
X94700Y2166100D01*
X95300Y2165167D01*
X95500Y2164100D01*
X95300Y2163033D01*
X94800Y2162233D01*
X93900Y2161833D01*
X91500D01*
G01X99000Y2158500D02*
X101500Y2166500D01*
X104000Y2158500D01*
G01X103100Y2161300D02*
X99900D01*
G01X107300Y2158500D02*
Y2166500D01*
X109300D01*
X110100Y2166100D01*
X110700Y2165567D01*
X111200Y2164767D01*
X111600Y2163833D01*
X111700Y2162500D01*
X111600Y2161167D01*
X111200Y2160233D01*
X110700Y2159433D01*
X110100Y2158900D01*
X109300Y2158500D01*
X107300D01*
G01X115400Y2159566D02*
X116200Y2158900D01*
X117100Y2158500D01*
X117900D01*
X118700Y2158900D01*
X119300Y2159566D01*
X119600Y2160500D01*
X119400Y2161433D01*
X118900Y2162233D01*
X118000Y2162767D01*
X116800Y2163033D01*
X116100Y2163567D01*
X115800Y2164500D01*
X116000Y2165433D01*
X116500Y2166100D01*
X117200Y2166500D01*
X117900D01*
X118600Y2166233D01*
X119200Y2165567D01*
G01X131000Y2158500D02*
X133500Y2166500D01*
X136000Y2158500D01*
G01X135100Y2161300D02*
X131900D01*
G01X139300Y2158500D02*
Y2166500D01*
X141300D01*
X142100Y2166100D01*
X142700Y2165567D01*
X143200Y2164767D01*
X143600Y2163833D01*
X143700Y2162500D01*
X143600Y2161167D01*
X143200Y2160233D01*
X142700Y2159433D01*
X142100Y2158900D01*
X141300Y2158500D01*
X139300D01*
G01X147400D02*
Y2166500D01*
G01X151600D02*
Y2158500D01*
G01Y2162500D02*
X147400D01*
G01X159500Y2158500D02*
X155500D01*
Y2166500D01*
X159500D01*
G01X157900Y2162633D02*
X155500D01*
G01X163400Y2159566D02*
X164200Y2158900D01*
X165100Y2158500D01*
X165900D01*
X166700Y2158900D01*
X167300Y2159566D01*
X167600Y2160500D01*
X167400Y2161433D01*
X166900Y2162233D01*
X166000Y2162767D01*
X164800Y2163033D01*
X164100Y2163567D01*
X163800Y2164500D01*
X164000Y2165433D01*
X164500Y2166100D01*
X165200Y2166500D01*
X165900D01*
X166600Y2166233D01*
X167200Y2165567D01*
G01X172300Y2166500D02*
X174700D01*
G01X173500D02*
Y2158500D01*
G01X172300D02*
X174700D01*
G01X181500D02*
X180700Y2158633D01*
X180000Y2159167D01*
X179400Y2159967D01*
X179000Y2160900D01*
X178800Y2161967D01*
Y2163033D01*
X179000Y2164100D01*
X179400Y2165033D01*
X180000Y2165833D01*
X180700Y2166367D01*
X181500Y2166500D01*
X182300Y2166367D01*
X183000Y2165833D01*
X183600Y2165033D01*
X184000Y2164100D01*
X184200Y2163033D01*
Y2161967D01*
X184000Y2160900D01*
X183600Y2159967D01*
X183000Y2159167D01*
X182300Y2158633D01*
X181500Y2158500D01*
G01X187200D02*
Y2166500D01*
X191800Y2158500D01*
Y2166500D01*
G01X205500D02*
Y2158500D01*
G01X203200Y2166500D02*
X207800D01*
G01X215500Y2158500D02*
X211500D01*
Y2166500D01*
X215500D01*
G01X213900Y2162633D02*
X211500D01*
G01X219400Y2159566D02*
X220200Y2158900D01*
X221100Y2158500D01*
X221900D01*
X222700Y2158900D01*
X223300Y2159566D01*
X223600Y2160500D01*
X223400Y2161433D01*
X222900Y2162233D01*
X222000Y2162767D01*
X220800Y2163033D01*
X220100Y2163567D01*
X219800Y2164500D01*
X220000Y2165433D01*
X220500Y2166100D01*
X221200Y2166500D01*
X221900D01*
X222600Y2166233D01*
X223200Y2165567D01*
G01X229500Y2166500D02*
Y2158500D01*
G01X227200Y2166500D02*
X231800D01*
G01X243500Y2158500D02*
Y2166500D01*
X245900D01*
X246700Y2166100D01*
X247300Y2165167D01*
X247500Y2164100D01*
X247300Y2163033D01*
X246800Y2162233D01*
X245900Y2161833D01*
X243500D01*
G01X251000Y2158500D02*
X253500Y2166500D01*
X256000Y2158500D01*
G01X255100Y2161300D02*
X251900D01*
G01X261500Y2166500D02*
Y2158500D01*
G01X259200Y2166500D02*
X263800D01*
G01X269500D02*
Y2158500D01*
G01X267200Y2166500D02*
X271800D01*
G01X279500Y2158500D02*
X275500D01*
Y2166500D01*
X279500D01*
G01X277900Y2162633D02*
X275500D01*
G01X283500Y2158500D02*
Y2166500D01*
X286000D01*
X286800Y2166100D01*
X287300Y2165567D01*
X287500Y2164500D01*
X287300Y2163433D01*
X286700Y2162767D01*
X286000Y2162367D01*
X283500D01*
G01X286000D02*
X287500Y2158500D01*
G01X291200D02*
Y2166500D01*
X295800Y2158500D01*
Y2166500D01*
G01X299400Y2159566D02*
X300200Y2158900D01*
X301100Y2158500D01*
X301900D01*
X302700Y2158900D01*
X303300Y2159566D01*
X303600Y2160500D01*
X303400Y2161433D01*
X302900Y2162233D01*
X302000Y2162767D01*
X300800Y2163033D01*
X300100Y2163567D01*
X299800Y2164500D01*
X300000Y2165433D01*
X300500Y2166100D01*
X301200Y2166500D01*
X301900D01*
X302600Y2166233D01*
X303200Y2165567D01*
G01X309500Y2158233D02*
X309300Y2158367D01*
Y2158633D01*
X309500Y2158767D01*
X309700Y2158633D01*
Y2158367D01*
X309500Y2158233D01*
G01X-110000Y2173500D02*
X-107500Y2181500D01*
X-105000Y2173500D01*
G01X-105900Y2176300D02*
X-109100D01*
G01X-101800Y2173500D02*
Y2181500D01*
X-97200Y2173500D01*
Y2181500D01*
G01X-91500Y2173500D02*
Y2177100D01*
X-93500Y2181500D01*
G01X-89500D02*
X-91500Y2177100D01*
G01X-77500Y2173500D02*
Y2181500D01*
X-75100D01*
X-74300Y2181100D01*
X-73700Y2180167D01*
X-73500Y2179100D01*
X-73700Y2178033D01*
X-74200Y2177233D01*
X-75100Y2176833D01*
X-77500D01*
G01X-69500Y2173500D02*
Y2181500D01*
X-67000D01*
X-66200Y2181100D01*
X-65700Y2180567D01*
X-65500Y2179500D01*
X-65700Y2178433D01*
X-66300Y2177767D01*
X-67000Y2177367D01*
X-69500D01*
G01X-67000D02*
X-65500Y2173500D01*
G01X-59500D02*
X-60300Y2173633D01*
X-61000Y2174167D01*
X-61600Y2174967D01*
X-62000Y2175900D01*
X-62200Y2176967D01*
Y2178033D01*
X-62000Y2179100D01*
X-61600Y2180033D01*
X-61000Y2180833D01*
X-60300Y2181367D01*
X-59500Y2181500D01*
X-58700Y2181367D01*
X-58000Y2180833D01*
X-57400Y2180033D01*
X-57000Y2179100D01*
X-56800Y2178033D01*
Y2176967D01*
X-57000Y2175900D01*
X-57400Y2174967D01*
X-58000Y2174167D01*
X-58700Y2173633D01*
X-59500Y2173500D01*
G01X-53500D02*
Y2181500D01*
X-51100D01*
X-50300Y2181100D01*
X-49700Y2180167D01*
X-49500Y2179100D01*
X-49700Y2178033D01*
X-50200Y2177233D01*
X-51100Y2176833D01*
X-53500D01*
G01X-43500Y2173500D02*
X-44300Y2173633D01*
X-45000Y2174167D01*
X-45600Y2174967D01*
X-46000Y2175900D01*
X-46200Y2176967D01*
Y2178033D01*
X-46000Y2179100D01*
X-45600Y2180033D01*
X-45000Y2180833D01*
X-44300Y2181367D01*
X-43500Y2181500D01*
X-42700Y2181367D01*
X-42000Y2180833D01*
X-41400Y2180033D01*
X-41000Y2179100D01*
X-40800Y2178033D01*
Y2176967D01*
X-41000Y2175900D01*
X-41400Y2174967D01*
X-42000Y2174167D01*
X-42700Y2173633D01*
X-43500Y2173500D01*
G01X-37600Y2174566D02*
X-36800Y2173900D01*
X-35900Y2173500D01*
X-35100D01*
X-34300Y2173900D01*
X-33700Y2174566D01*
X-33400Y2175500D01*
X-33600Y2176433D01*
X-34100Y2177233D01*
X-35000Y2177767D01*
X-36200Y2178033D01*
X-36900Y2178567D01*
X-37200Y2179500D01*
X-37000Y2180433D01*
X-36500Y2181100D01*
X-35800Y2181500D01*
X-35100D01*
X-34400Y2181233D01*
X-33800Y2180567D01*
G01X-25500Y2173500D02*
X-29500D01*
Y2181500D01*
X-25500D01*
G01X-27100Y2177633D02*
X-29500D01*
G01X-21700Y2173500D02*
Y2181500D01*
X-19700D01*
X-18900Y2181100D01*
X-18300Y2180567D01*
X-17800Y2179767D01*
X-17400Y2178833D01*
X-17300Y2177500D01*
X-17400Y2176167D01*
X-17800Y2175233D01*
X-18300Y2174433D01*
X-18900Y2173900D01*
X-19700Y2173500D01*
X-21700D01*
G01X-1300Y2180833D02*
X-1900Y2181233D01*
X-2600Y2181500D01*
X-3400D01*
X-4300Y2181100D01*
X-5000Y2180433D01*
X-5500Y2179633D01*
X-5900Y2178300D01*
X-6000Y2177100D01*
X-5800Y2175900D01*
X-5500Y2175100D01*
X-4900Y2174300D01*
X-4200Y2173767D01*
X-3500Y2173500D01*
X-2800D01*
X-2100Y2173767D01*
X-1500Y2174167D01*
X-1000Y2174700D01*
G01X2400Y2173500D02*
Y2181500D01*
G01X6600D02*
Y2173500D01*
G01Y2177500D02*
X2400D01*
G01X10000Y2173500D02*
X12500Y2181500D01*
X15000Y2173500D01*
G01X14100Y2176300D02*
X10900D01*
G01X18200Y2173500D02*
Y2181500D01*
X22800Y2173500D01*
Y2181500D01*
G01X29100Y2177500D02*
X31100D01*
Y2175100D01*
X30500Y2174300D01*
X29800Y2173767D01*
X28800Y2173500D01*
X27800Y2173767D01*
X27100Y2174300D01*
X26500Y2175100D01*
X26100Y2176033D01*
X25900Y2177100D01*
Y2178033D01*
X26100Y2178833D01*
X26500Y2179767D01*
X27100Y2180567D01*
X27700Y2181100D01*
X28500Y2181500D01*
X29200D01*
X30000Y2181233D01*
X30600Y2180700D01*
G01X38500Y2173500D02*
X34500D01*
Y2181500D01*
X38500D01*
G01X36900Y2177633D02*
X34500D01*
G01X50500Y2173500D02*
Y2181500D01*
X53000D01*
X53800Y2181100D01*
X54300Y2180567D01*
X54500Y2179500D01*
X54300Y2178433D01*
X53700Y2177767D01*
X53000Y2177367D01*
X50500D01*
G01X53000D02*
X54500Y2173500D01*
G01X62500D02*
X58500D01*
Y2181500D01*
X62500D01*
G01X60900Y2177633D02*
X58500D01*
G01X68500Y2173500D02*
X67700Y2173633D01*
X67000Y2174167D01*
X66400Y2174967D01*
X66000Y2175900D01*
X65800Y2176967D01*
Y2178033D01*
X66000Y2179100D01*
X66400Y2180033D01*
X67000Y2180833D01*
X67700Y2181367D01*
X68500Y2181500D01*
X69300Y2181367D01*
X70000Y2180833D01*
X70600Y2180033D01*
X71000Y2179100D01*
X71200Y2178033D01*
Y2176967D01*
X71000Y2175900D01*
X70600Y2174967D01*
X70000Y2174167D01*
X69300Y2173633D01*
X68500Y2173500D01*
G01X69300Y2175633D02*
X70500Y2173500D01*
G01X74300Y2181500D02*
Y2175767D01*
X74700Y2174566D01*
X75500Y2173767D01*
X76500Y2173500D01*
X77500Y2173767D01*
X78300Y2174566D01*
X78700Y2175767D01*
Y2181500D01*
G01X86500Y2173500D02*
X82500D01*
Y2181500D01*
X86500D01*
G01X84900Y2177633D02*
X82500D01*
G01X90400Y2174566D02*
X91200Y2173900D01*
X92100Y2173500D01*
X92900D01*
X93700Y2173900D01*
X94300Y2174566D01*
X94600Y2175500D01*
X94400Y2176433D01*
X93900Y2177233D01*
X93000Y2177767D01*
X91800Y2178033D01*
X91100Y2178567D01*
X90800Y2179500D01*
X91000Y2180433D01*
X91500Y2181100D01*
X92200Y2181500D01*
X92900D01*
X93600Y2181233D01*
X94200Y2180567D01*
G01X100500Y2181500D02*
Y2173500D01*
G01X98200Y2181500D02*
X102800D01*
G01X113900Y2173500D02*
Y2181500D01*
X116500Y2174833D01*
X119100Y2181500D01*
Y2173500D01*
G01X122300Y2181500D02*
Y2175767D01*
X122700Y2174566D01*
X123500Y2173767D01*
X124500Y2173500D01*
X125500Y2173767D01*
X126300Y2174566D01*
X126700Y2175767D01*
Y2181500D01*
G01X130400Y2174566D02*
X131200Y2173900D01*
X132100Y2173500D01*
X132900D01*
X133700Y2173900D01*
X134300Y2174566D01*
X134600Y2175500D01*
X134400Y2176433D01*
X133900Y2177233D01*
X133000Y2177767D01*
X131800Y2178033D01*
X131100Y2178567D01*
X130800Y2179500D01*
X131000Y2180433D01*
X131500Y2181100D01*
X132200Y2181500D01*
X132900D01*
X133600Y2181233D01*
X134200Y2180567D01*
G01X140500Y2181500D02*
Y2173500D01*
G01X138200Y2181500D02*
X142800D01*
G01X157300Y2177767D02*
X157700Y2178167D01*
X158000Y2178833D01*
X158200Y2179767D01*
X158000Y2180567D01*
X157600Y2181100D01*
X156900Y2181500D01*
X154200D01*
Y2173500D01*
X157500D01*
X158200Y2174033D01*
X158600Y2174833D01*
X158800Y2175767D01*
X158600Y2176700D01*
X158000Y2177500D01*
X157300Y2177767D01*
X154200D01*
G01X166500Y2173500D02*
X162500D01*
Y2181500D01*
X166500D01*
G01X164900Y2177633D02*
X162500D01*
G01X178000Y2173500D02*
X180500Y2181500D01*
X183000Y2173500D01*
G01X182100Y2176300D02*
X178900D01*
G01X186500Y2173500D02*
Y2181500D01*
X188900D01*
X189700Y2181100D01*
X190300Y2180167D01*
X190500Y2179100D01*
X190300Y2178033D01*
X189800Y2177233D01*
X188900Y2176833D01*
X186500D01*
G01X194500Y2173500D02*
Y2181500D01*
X196900D01*
X197700Y2181100D01*
X198300Y2180167D01*
X198500Y2179100D01*
X198300Y2178033D01*
X197800Y2177233D01*
X196900Y2176833D01*
X194500D01*
G01X202500Y2173500D02*
Y2181500D01*
X205000D01*
X205800Y2181100D01*
X206300Y2180567D01*
X206500Y2179500D01*
X206300Y2178433D01*
X205700Y2177767D01*
X205000Y2177367D01*
X202500D01*
G01X205000D02*
X206500Y2173500D01*
G01X212500D02*
X211700Y2173633D01*
X211000Y2174167D01*
X210400Y2174967D01*
X210000Y2175900D01*
X209800Y2176967D01*
Y2178033D01*
X210000Y2179100D01*
X210400Y2180033D01*
X211000Y2180833D01*
X211700Y2181367D01*
X212500Y2181500D01*
X213300Y2181367D01*
X214000Y2180833D01*
X214600Y2180033D01*
X215000Y2179100D01*
X215200Y2178033D01*
Y2176967D01*
X215000Y2175900D01*
X214600Y2174967D01*
X214000Y2174167D01*
X213300Y2173633D01*
X212500Y2173500D01*
G01X218000Y2181500D02*
X220500Y2173500D01*
X223000Y2181500D01*
G01X230500Y2173500D02*
X226500D01*
Y2181500D01*
X230500D01*
G01X228900Y2177633D02*
X226500D01*
G01X234300Y2173500D02*
Y2181500D01*
X236300D01*
X237100Y2181100D01*
X237700Y2180567D01*
X238200Y2179767D01*
X238600Y2178833D01*
X238700Y2177500D01*
X238600Y2176167D01*
X238200Y2175233D01*
X237700Y2174433D01*
X237100Y2173900D01*
X236300Y2173500D01*
X234300D01*
G01X253300Y2177767D02*
X253700Y2178167D01*
X254000Y2178833D01*
X254200Y2179767D01*
X254000Y2180567D01*
X253600Y2181100D01*
X252900Y2181500D01*
X250200D01*
Y2173500D01*
X253500D01*
X254200Y2174033D01*
X254600Y2174833D01*
X254800Y2175767D01*
X254600Y2176700D01*
X254000Y2177500D01*
X253300Y2177767D01*
X250200D01*
G01X260500Y2173500D02*
Y2177100D01*
X258500Y2181500D01*
G01X262500D02*
X260500Y2177100D01*
G01X276500Y2173500D02*
X275700Y2173633D01*
X275000Y2174167D01*
X274400Y2174967D01*
X274000Y2175900D01*
X273800Y2176967D01*
Y2178033D01*
X274000Y2179100D01*
X274400Y2180033D01*
X275000Y2180833D01*
X275700Y2181367D01*
X276500Y2181500D01*
X277300Y2181367D01*
X278000Y2180833D01*
X278600Y2180033D01*
X279000Y2179100D01*
X279200Y2178033D01*
Y2176967D01*
X279000Y2175900D01*
X278600Y2174967D01*
X278000Y2174167D01*
X277300Y2173633D01*
X276500Y2173500D01*
G01X277300Y2175633D02*
X278500Y2173500D01*
G01X282300Y2181500D02*
Y2175767D01*
X282700Y2174566D01*
X283500Y2173767D01*
X284500Y2173500D01*
X285500Y2173767D01*
X286300Y2174566D01*
X286700Y2175767D01*
Y2181500D01*
G01X290000Y2173500D02*
X292500Y2181500D01*
X295000Y2173500D01*
G01X294100Y2176300D02*
X290900D01*
G01X298200Y2173500D02*
Y2181500D01*
X302800Y2173500D01*
Y2181500D01*
G01X308500D02*
Y2173500D01*
G01X306200Y2181500D02*
X310800D01*
G01X314000Y2173500D02*
X316500Y2181500D01*
X319000Y2173500D01*
G01X318100Y2176300D02*
X314900D01*
G01X330500Y2173500D02*
Y2181500D01*
X332900D01*
X333700Y2181100D01*
X334300Y2180167D01*
X334500Y2179100D01*
X334300Y2178033D01*
X333800Y2177233D01*
X332900Y2176833D01*
X330500D01*
G01X338500Y2173500D02*
Y2181500D01*
X341000D01*
X341800Y2181100D01*
X342300Y2180567D01*
X342500Y2179500D01*
X342300Y2178433D01*
X341700Y2177767D01*
X341000Y2177367D01*
X338500D01*
G01X341000D02*
X342500Y2173500D01*
G01X347300Y2181500D02*
X349700D01*
G01X348500D02*
Y2173500D01*
G01X347300D02*
X349700D01*
G01X356500D02*
X355700Y2173633D01*
X355000Y2174167D01*
X354400Y2174967D01*
X354000Y2175900D01*
X353800Y2176967D01*
Y2178033D01*
X354000Y2179100D01*
X354400Y2180033D01*
X355000Y2180833D01*
X355700Y2181367D01*
X356500Y2181500D01*
X357300Y2181367D01*
X358000Y2180833D01*
X358600Y2180033D01*
X359000Y2179100D01*
X359200Y2178033D01*
Y2176967D01*
X359000Y2175900D01*
X358600Y2174967D01*
X358000Y2174167D01*
X357300Y2173633D01*
X356500Y2173500D01*
G01X362500D02*
Y2181500D01*
X365000D01*
X365800Y2181100D01*
X366300Y2180567D01*
X366500Y2179500D01*
X366300Y2178433D01*
X365700Y2177767D01*
X365000Y2177367D01*
X362500D01*
G01X365000D02*
X366500Y2173500D01*
G01X380500Y2181500D02*
Y2173500D01*
G01X378200Y2181500D02*
X382800D01*
G01X388500Y2173500D02*
X387700Y2173633D01*
X387000Y2174167D01*
X386400Y2174967D01*
X386000Y2175900D01*
X385800Y2176967D01*
Y2178033D01*
X386000Y2179100D01*
X386400Y2180033D01*
X387000Y2180833D01*
X387700Y2181367D01*
X388500Y2181500D01*
X389300Y2181367D01*
X390000Y2180833D01*
X390600Y2180033D01*
X391000Y2179100D01*
X391200Y2178033D01*
Y2176967D01*
X391000Y2175900D01*
X390600Y2174967D01*
X390000Y2174167D01*
X389300Y2173633D01*
X388500Y2173500D01*
G01X403300Y2181500D02*
X405700D01*
G01X404500D02*
Y2173500D01*
G01X403300D02*
X405700D01*
G01X412500Y2181500D02*
Y2173500D01*
G01X410200Y2181500D02*
X414800D01*
G01X418400Y2174566D02*
X419200Y2173900D01*
X420100Y2173500D01*
X420900D01*
X421700Y2173900D01*
X422300Y2174566D01*
X422600Y2175500D01*
X422400Y2176433D01*
X421900Y2177233D01*
X421000Y2177767D01*
X419800Y2178033D01*
X419100Y2178567D01*
X418800Y2179500D01*
X419000Y2180433D01*
X419500Y2181100D01*
X420200Y2181500D01*
X420900D01*
X421600Y2181233D01*
X422200Y2180567D01*
G01X435300Y2181500D02*
X437700D01*
G01X436500D02*
Y2173500D01*
G01X435300D02*
X437700D01*
G01X441900D02*
Y2181500D01*
X444500Y2174833D01*
X447100Y2181500D01*
Y2173500D01*
G01X450500D02*
Y2181500D01*
X452900D01*
X453700Y2181100D01*
X454300Y2180167D01*
X454500Y2179100D01*
X454300Y2178033D01*
X453800Y2177233D01*
X452900Y2176833D01*
X450500D01*
G01X458500Y2181500D02*
Y2173500D01*
X462500D01*
G01X470500D02*
X466500D01*
Y2181500D01*
X470500D01*
G01X468900Y2177633D02*
X466500D01*
G01X473900Y2173500D02*
Y2181500D01*
X476500Y2174833D01*
X479100Y2181500D01*
Y2173500D01*
G01X486500D02*
X482500D01*
Y2181500D01*
X486500D01*
G01X484900Y2177633D02*
X482500D01*
G01X490200Y2173500D02*
Y2181500D01*
X494800Y2173500D01*
Y2181500D01*
G01X500500D02*
Y2173500D01*
G01X498200Y2181500D02*
X502800D01*
G01X506000Y2173500D02*
X508500Y2181500D01*
X511000Y2173500D01*
G01X510100Y2176300D02*
X506900D01*
G01X516500Y2181500D02*
Y2173500D01*
G01X514200Y2181500D02*
X518800D01*
G01X523300D02*
X525700D01*
G01X524500D02*
Y2173500D01*
G01X523300D02*
X525700D01*
G01X532500D02*
X531700Y2173633D01*
X531000Y2174167D01*
X530400Y2174967D01*
X530000Y2175900D01*
X529800Y2176967D01*
Y2178033D01*
X530000Y2179100D01*
X530400Y2180033D01*
X531000Y2180833D01*
X531700Y2181367D01*
X532500Y2181500D01*
X533300Y2181367D01*
X534000Y2180833D01*
X534600Y2180033D01*
X535000Y2179100D01*
X535200Y2178033D01*
Y2176967D01*
X535000Y2175900D01*
X534600Y2174967D01*
X534000Y2174167D01*
X533300Y2173633D01*
X532500Y2173500D01*
G01X538200D02*
Y2181500D01*
X542800Y2173500D01*
Y2181500D01*
G01X548500Y2173233D02*
X548300Y2173367D01*
Y2173633D01*
X548500Y2173767D01*
X548700Y2173633D01*
Y2173367D01*
X548500Y2173233D01*
G01X-108700Y2196500D02*
X-106300D01*
G01X-107500D02*
Y2188500D01*
G01X-108700D02*
X-106300D01*
G01X-102100D02*
Y2196500D01*
X-99500Y2189833D01*
X-96900Y2196500D01*
Y2188500D01*
G01X-93500D02*
Y2196500D01*
X-91100D01*
X-90300Y2196100D01*
X-89700Y2195167D01*
X-89500Y2194100D01*
X-89700Y2193033D01*
X-90200Y2192233D01*
X-91100Y2191833D01*
X-93500D01*
G01X-81500Y2188500D02*
X-85500D01*
Y2196500D01*
X-81500D01*
G01X-83100Y2192633D02*
X-85500D01*
G01X-77700Y2188500D02*
Y2196500D01*
X-75700D01*
X-74900Y2196100D01*
X-74300Y2195567D01*
X-73800Y2194767D01*
X-73400Y2193833D01*
X-73300Y2192500D01*
X-73400Y2191167D01*
X-73800Y2190233D01*
X-74300Y2189433D01*
X-74900Y2188900D01*
X-75700Y2188500D01*
X-77700D01*
G01X-70000D02*
X-67500Y2196500D01*
X-65000Y2188500D01*
G01X-65900Y2191300D02*
X-69100D01*
G01X-61800Y2188500D02*
Y2196500D01*
X-57200Y2188500D01*
Y2196500D01*
G01X-49300Y2195833D02*
X-49900Y2196233D01*
X-50600Y2196500D01*
X-51400D01*
X-52300Y2196100D01*
X-53000Y2195433D01*
X-53500Y2194633D01*
X-53900Y2193300D01*
X-54000Y2192100D01*
X-53800Y2190900D01*
X-53500Y2190100D01*
X-52900Y2189300D01*
X-52200Y2188767D01*
X-51500Y2188500D01*
X-50800D01*
X-50100Y2188767D01*
X-49500Y2189167D01*
X-49000Y2189700D01*
G01X-41500Y2188500D02*
X-45500D01*
Y2196500D01*
X-41500D01*
G01X-43100Y2192633D02*
X-45500D01*
G01X-37600Y2189566D02*
X-36800Y2188900D01*
X-35900Y2188500D01*
X-35100D01*
X-34300Y2188900D01*
X-33700Y2189566D01*
X-33400Y2190500D01*
X-33600Y2191433D01*
X-34100Y2192233D01*
X-35000Y2192767D01*
X-36200Y2193033D01*
X-36900Y2193567D01*
X-37200Y2194500D01*
X-37000Y2195433D01*
X-36500Y2196100D01*
X-35800Y2196500D01*
X-35100D01*
X-34400Y2196233D01*
X-33800Y2195567D01*
G01X-22000Y2188500D02*
X-19500Y2196500D01*
X-17000Y2188500D01*
G01X-17900Y2191300D02*
X-21100D01*
G01X-13800Y2188500D02*
Y2196500D01*
X-9200Y2188500D01*
Y2196500D01*
G01X-5700Y2188500D02*
Y2196500D01*
X-3700D01*
X-2900Y2196100D01*
X-2300Y2195567D01*
X-1800Y2194767D01*
X-1400Y2193833D01*
X-1300Y2192500D01*
X-1400Y2191167D01*
X-1800Y2190233D01*
X-2300Y2189433D01*
X-2900Y2188900D01*
X-3700Y2188500D01*
X-5700D01*
G01X13300Y2192767D02*
X13700Y2193167D01*
X14000Y2193833D01*
X14200Y2194767D01*
X14000Y2195567D01*
X13600Y2196100D01*
X12900Y2196500D01*
X10200D01*
Y2188500D01*
X13500D01*
X14200Y2189033D01*
X14600Y2189833D01*
X14800Y2190767D01*
X14600Y2191700D01*
X14000Y2192500D01*
X13300Y2192767D01*
X10200D01*
G01X20500Y2188500D02*
X19700Y2188633D01*
X19000Y2189167D01*
X18400Y2189967D01*
X18000Y2190900D01*
X17800Y2191967D01*
Y2193033D01*
X18000Y2194100D01*
X18400Y2195033D01*
X19000Y2195833D01*
X19700Y2196367D01*
X20500Y2196500D01*
X21300Y2196367D01*
X22000Y2195833D01*
X22600Y2195033D01*
X23000Y2194100D01*
X23200Y2193033D01*
Y2191967D01*
X23000Y2190900D01*
X22600Y2189967D01*
X22000Y2189167D01*
X21300Y2188633D01*
X20500Y2188500D01*
G01X26000D02*
X28500Y2196500D01*
X31000Y2188500D01*
G01X30100Y2191300D02*
X26900D01*
G01X34500Y2188500D02*
Y2196500D01*
X37000D01*
X37800Y2196100D01*
X38300Y2195567D01*
X38500Y2194500D01*
X38300Y2193433D01*
X37700Y2192767D01*
X37000Y2192367D01*
X34500D01*
G01X37000D02*
X38500Y2188500D01*
G01X42300D02*
Y2196500D01*
X44300D01*
X45100Y2196100D01*
X45700Y2195567D01*
X46200Y2194767D01*
X46600Y2193833D01*
X46700Y2192500D01*
X46600Y2191167D01*
X46200Y2190233D01*
X45700Y2189433D01*
X45100Y2188900D01*
X44300Y2188500D01*
X42300D01*
G01X60500Y2196500D02*
Y2188500D01*
G01X58200Y2196500D02*
X62800D01*
G01X66400Y2188500D02*
Y2196500D01*
G01X70600D02*
Y2188500D01*
G01Y2192500D02*
X66400D01*
G01X75300Y2196500D02*
X77700D01*
G01X76500D02*
Y2188500D01*
G01X75300D02*
X77700D01*
G01X86700Y2195833D02*
X86100Y2196233D01*
X85400Y2196500D01*
X84600D01*
X83700Y2196100D01*
X83000Y2195433D01*
X82500Y2194633D01*
X82100Y2193300D01*
X82000Y2192100D01*
X82200Y2190900D01*
X82500Y2190100D01*
X83100Y2189300D01*
X83800Y2188767D01*
X84500Y2188500D01*
X85200D01*
X85900Y2188767D01*
X86500Y2189167D01*
X87000Y2189700D01*
G01X90300Y2188500D02*
Y2196500D01*
G01X94100D02*
X90300Y2191566D01*
G01X94700Y2188500D02*
X92000Y2193833D01*
G01X98200Y2188500D02*
Y2196500D01*
X102800Y2188500D01*
Y2196500D01*
G01X110500Y2188500D02*
X106500D01*
Y2196500D01*
X110500D01*
G01X108900Y2192633D02*
X106500D01*
G01X114400Y2189566D02*
X115200Y2188900D01*
X116100Y2188500D01*
X116900D01*
X117700Y2188900D01*
X118300Y2189566D01*
X118600Y2190500D01*
X118400Y2191433D01*
X117900Y2192233D01*
X117000Y2192767D01*
X115800Y2193033D01*
X115100Y2193567D01*
X114800Y2194500D01*
X115000Y2195433D01*
X115500Y2196100D01*
X116200Y2196500D01*
X116900D01*
X117600Y2196233D01*
X118200Y2195567D01*
G01X122400Y2189566D02*
X123200Y2188900D01*
X124100Y2188500D01*
X124900D01*
X125700Y2188900D01*
X126300Y2189566D01*
X126600Y2190500D01*
X126400Y2191433D01*
X125900Y2192233D01*
X125000Y2192767D01*
X123800Y2193033D01*
X123100Y2193567D01*
X122800Y2194500D01*
X123000Y2195433D01*
X123500Y2196100D01*
X124200Y2196500D01*
X124900D01*
X125600Y2196233D01*
X126200Y2195567D01*
G01X132500Y2188233D02*
X132300Y2188367D01*
Y2188633D01*
X132500Y2188767D01*
X132700Y2188633D01*
Y2188367D01*
X132500Y2188233D01*
G01X-109600Y2204566D02*
X-108800Y2203900D01*
X-107900Y2203500D01*
X-107100D01*
X-106300Y2203900D01*
X-105700Y2204566D01*
X-105400Y2205500D01*
X-105600Y2206433D01*
X-106100Y2207233D01*
X-107000Y2207767D01*
X-108200Y2208033D01*
X-108900Y2208567D01*
X-109200Y2209500D01*
X-109000Y2210433D01*
X-108500Y2211100D01*
X-107800Y2211500D01*
X-107100D01*
X-106400Y2211233D01*
X-105800Y2210567D01*
G01X-101500Y2203500D02*
Y2211500D01*
X-99100D01*
X-98300Y2211100D01*
X-97700Y2210167D01*
X-97500Y2209100D01*
X-97700Y2208033D01*
X-98200Y2207233D01*
X-99100Y2206833D01*
X-101500D01*
G01X-94000Y2203500D02*
X-91500Y2211500D01*
X-89000Y2203500D01*
G01X-89900Y2206300D02*
X-93100D01*
G01X-81300Y2210833D02*
X-81900Y2211233D01*
X-82600Y2211500D01*
X-83400D01*
X-84300Y2211100D01*
X-85000Y2210433D01*
X-85500Y2209633D01*
X-85900Y2208300D01*
X-86000Y2207100D01*
X-85800Y2205900D01*
X-85500Y2205100D01*
X-84900Y2204300D01*
X-84200Y2203767D01*
X-83500Y2203500D01*
X-82800D01*
X-82100Y2203767D01*
X-81500Y2204167D01*
X-81000Y2204700D01*
G01X-76700Y2211500D02*
X-74300D01*
G01X-75500D02*
Y2203500D01*
G01X-76700D02*
X-74300D01*
G01X-69800D02*
Y2211500D01*
X-65200Y2203500D01*
Y2211500D01*
G01X-58900Y2207500D02*
X-56900D01*
Y2205100D01*
X-57500Y2204300D01*
X-58200Y2203767D01*
X-59200Y2203500D01*
X-60200Y2203767D01*
X-60900Y2204300D01*
X-61500Y2205100D01*
X-61900Y2206033D01*
X-62100Y2207100D01*
Y2208033D01*
X-61900Y2208833D01*
X-61500Y2209767D01*
X-60900Y2210567D01*
X-60300Y2211100D01*
X-59500Y2211500D01*
X-58800D01*
X-58000Y2211233D01*
X-57400Y2210700D01*
G01X-46000Y2203500D02*
X-43500Y2211500D01*
X-41000Y2203500D01*
G01X-41900Y2206300D02*
X-45100D01*
G01X-37800Y2203500D02*
Y2211500D01*
X-33200Y2203500D01*
Y2211500D01*
G01X-29700Y2203500D02*
Y2211500D01*
X-27700D01*
X-26900Y2211100D01*
X-26300Y2210567D01*
X-25800Y2209767D01*
X-25400Y2208833D01*
X-25300Y2207500D01*
X-25400Y2206167D01*
X-25800Y2205233D01*
X-26300Y2204433D01*
X-26900Y2203900D01*
X-27700Y2203500D01*
X-29700D01*
G01X-14100D02*
Y2211500D01*
X-11500Y2204833D01*
X-8900Y2211500D01*
Y2203500D01*
G01X-6000D02*
X-3500Y2211500D01*
X-1000Y2203500D01*
G01X-1900Y2206300D02*
X-5100D01*
G01X4500Y2211500D02*
Y2203500D01*
G01X2200Y2211500D02*
X6800D01*
G01X14500Y2203500D02*
X10500D01*
Y2211500D01*
X14500D01*
G01X12900Y2207633D02*
X10500D01*
G01X18500Y2203500D02*
Y2211500D01*
X21000D01*
X21800Y2211100D01*
X22300Y2210567D01*
X22500Y2209500D01*
X22300Y2208433D01*
X21700Y2207767D01*
X21000Y2207367D01*
X18500D01*
G01X21000D02*
X22500Y2203500D01*
G01X27300Y2211500D02*
X29700D01*
G01X28500D02*
Y2203500D01*
G01X27300D02*
X29700D01*
G01X34000D02*
X36500Y2211500D01*
X39000Y2203500D01*
G01X38100Y2206300D02*
X34900D01*
G01X42500Y2211500D02*
Y2203500D01*
X46500D01*
G01X58300D02*
Y2211500D01*
X60300D01*
X61100Y2211100D01*
X61700Y2210567D01*
X62200Y2209767D01*
X62600Y2208833D01*
X62700Y2207500D01*
X62600Y2206167D01*
X62200Y2205233D01*
X61700Y2204433D01*
X61100Y2203900D01*
X60300Y2203500D01*
X58300D01*
G01X67300Y2211500D02*
X69700D01*
G01X68500D02*
Y2203500D01*
G01X67300D02*
X69700D01*
G01X78500D02*
X74500D01*
Y2211500D01*
X78500D01*
G01X76900Y2207633D02*
X74500D01*
G01X82500Y2211500D02*
Y2203500D01*
X86500D01*
G01X94500D02*
X90500D01*
Y2211500D01*
X94500D01*
G01X92900Y2207633D02*
X90500D01*
G01X102700Y2210833D02*
X102100Y2211233D01*
X101400Y2211500D01*
X100600D01*
X99700Y2211100D01*
X99000Y2210433D01*
X98500Y2209633D01*
X98100Y2208300D01*
X98000Y2207100D01*
X98200Y2205900D01*
X98500Y2205100D01*
X99100Y2204300D01*
X99800Y2203767D01*
X100500Y2203500D01*
X101200D01*
X101900Y2203767D01*
X102500Y2204167D01*
X103000Y2204700D01*
G01X108500Y2211500D02*
Y2203500D01*
G01X106200Y2211500D02*
X110800D01*
G01X114500Y2203500D02*
Y2211500D01*
X117000D01*
X117800Y2211100D01*
X118300Y2210567D01*
X118500Y2209500D01*
X118300Y2208433D01*
X117700Y2207767D01*
X117000Y2207367D01*
X114500D01*
G01X117000D02*
X118500Y2203500D01*
G01X123300Y2211500D02*
X125700D01*
G01X124500D02*
Y2203500D01*
G01X123300D02*
X125700D01*
G01X134700Y2210833D02*
X134100Y2211233D01*
X133400Y2211500D01*
X132600D01*
X131700Y2211100D01*
X131000Y2210433D01*
X130500Y2209633D01*
X130100Y2208300D01*
X130000Y2207100D01*
X130200Y2205900D01*
X130500Y2205100D01*
X131100Y2204300D01*
X131800Y2203767D01*
X132500Y2203500D01*
X133200D01*
X133900Y2203767D01*
X134500Y2204167D01*
X135000Y2204700D01*
G01X150700Y2210833D02*
X150100Y2211233D01*
X149400Y2211500D01*
X148600D01*
X147700Y2211100D01*
X147000Y2210433D01*
X146500Y2209633D01*
X146100Y2208300D01*
X146000Y2207100D01*
X146200Y2205900D01*
X146500Y2205100D01*
X147100Y2204300D01*
X147800Y2203767D01*
X148500Y2203500D01*
X149200D01*
X149900Y2203767D01*
X150500Y2204167D01*
X151000Y2204700D01*
G01X156500Y2203500D02*
X155700Y2203633D01*
X155000Y2204167D01*
X154400Y2204967D01*
X154000Y2205900D01*
X153800Y2206967D01*
Y2208033D01*
X154000Y2209100D01*
X154400Y2210033D01*
X155000Y2210833D01*
X155700Y2211367D01*
X156500Y2211500D01*
X157300Y2211367D01*
X158000Y2210833D01*
X158600Y2210033D01*
X159000Y2209100D01*
X159200Y2208033D01*
Y2206967D01*
X159000Y2205900D01*
X158600Y2204967D01*
X158000Y2204167D01*
X157300Y2203633D01*
X156500Y2203500D01*
G01X162200D02*
Y2211500D01*
X166800Y2203500D01*
Y2211500D01*
G01X170400Y2204566D02*
X171200Y2203900D01*
X172100Y2203500D01*
X172900D01*
X173700Y2203900D01*
X174300Y2204566D01*
X174600Y2205500D01*
X174400Y2206433D01*
X173900Y2207233D01*
X173000Y2207767D01*
X171800Y2208033D01*
X171100Y2208567D01*
X170800Y2209500D01*
X171000Y2210433D01*
X171500Y2211100D01*
X172200Y2211500D01*
X172900D01*
X173600Y2211233D01*
X174200Y2210567D01*
G01X180500Y2211500D02*
Y2203500D01*
G01X178200Y2211500D02*
X182800D01*
G01X186000Y2203500D02*
X188500Y2211500D01*
X191000Y2203500D01*
G01X190100Y2206300D02*
X186900D01*
G01X194200Y2203500D02*
Y2211500D01*
X198800Y2203500D01*
Y2211500D01*
G01X204500D02*
Y2203500D01*
G01X202200Y2211500D02*
X206800D01*
G01X220500D02*
Y2203500D01*
G01X218200Y2211500D02*
X222800D01*
G01X228500Y2203500D02*
X227700Y2203633D01*
X227000Y2204167D01*
X226400Y2204967D01*
X226000Y2205900D01*
X225800Y2206967D01*
Y2208033D01*
X226000Y2209100D01*
X226400Y2210033D01*
X227000Y2210833D01*
X227700Y2211367D01*
X228500Y2211500D01*
X229300Y2211367D01*
X230000Y2210833D01*
X230600Y2210033D01*
X231000Y2209100D01*
X231200Y2208033D01*
Y2206967D01*
X231000Y2205900D01*
X230600Y2204967D01*
X230000Y2204167D01*
X229300Y2203633D01*
X228500Y2203500D01*
G01X242000D02*
X244500Y2211500D01*
X247000Y2203500D01*
G01X246100Y2206300D02*
X242900D01*
G01X254700Y2210833D02*
X254100Y2211233D01*
X253400Y2211500D01*
X252600D01*
X251700Y2211100D01*
X251000Y2210433D01*
X250500Y2209633D01*
X250100Y2208300D01*
X250000Y2207100D01*
X250200Y2205900D01*
X250500Y2205100D01*
X251100Y2204300D01*
X251800Y2203767D01*
X252500Y2203500D01*
X253200D01*
X253900Y2203767D01*
X254500Y2204167D01*
X255000Y2204700D01*
G01X258400Y2203500D02*
Y2211500D01*
G01X262600D02*
Y2203500D01*
G01Y2207500D02*
X258400D01*
G01X267300Y2211500D02*
X269700D01*
G01X268500D02*
Y2203500D01*
G01X267300D02*
X269700D01*
G01X278500D02*
X274500D01*
Y2211500D01*
X278500D01*
G01X276900Y2207633D02*
X274500D01*
G01X282000Y2211500D02*
X284500Y2203500D01*
X287000Y2211500D01*
G01X294500Y2203500D02*
X290500D01*
Y2211500D01*
X294500D01*
G01X292900Y2207633D02*
X290500D01*
G01X306500Y2203500D02*
Y2211500D01*
X309000D01*
X309800Y2211100D01*
X310300Y2210567D01*
X310500Y2209500D01*
X310300Y2208433D01*
X309700Y2207767D01*
X309000Y2207367D01*
X306500D01*
G01X309000D02*
X310500Y2203500D01*
G01X318500D02*
X314500D01*
Y2211500D01*
X318500D01*
G01X316900Y2207633D02*
X314500D01*
G01X324500Y2203500D02*
X323700Y2203633D01*
X323000Y2204167D01*
X322400Y2204967D01*
X322000Y2205900D01*
X321800Y2206967D01*
Y2208033D01*
X322000Y2209100D01*
X322400Y2210033D01*
X323000Y2210833D01*
X323700Y2211367D01*
X324500Y2211500D01*
X325300Y2211367D01*
X326000Y2210833D01*
X326600Y2210033D01*
X327000Y2209100D01*
X327200Y2208033D01*
Y2206967D01*
X327000Y2205900D01*
X326600Y2204967D01*
X326000Y2204167D01*
X325300Y2203633D01*
X324500Y2203500D01*
G01X325300Y2205633D02*
X326500Y2203500D01*
G01X330300Y2211500D02*
Y2205767D01*
X330700Y2204566D01*
X331500Y2203767D01*
X332500Y2203500D01*
X333500Y2203767D01*
X334300Y2204566D01*
X334700Y2205767D01*
Y2211500D01*
G01X339300D02*
X341700D01*
G01X340500D02*
Y2203500D01*
G01X339300D02*
X341700D01*
G01X346500D02*
Y2211500D01*
X349000D01*
X349800Y2211100D01*
X350300Y2210567D01*
X350500Y2209500D01*
X350300Y2208433D01*
X349700Y2207767D01*
X349000Y2207367D01*
X346500D01*
G01X349000D02*
X350500Y2203500D01*
G01X358500D02*
X354500D01*
Y2211500D01*
X358500D01*
G01X356900Y2207633D02*
X354500D01*
G01X362300Y2203500D02*
Y2211500D01*
X364300D01*
X365100Y2211100D01*
X365700Y2210567D01*
X366200Y2209767D01*
X366600Y2208833D01*
X366700Y2207500D01*
X366600Y2206167D01*
X366200Y2205233D01*
X365700Y2204433D01*
X365100Y2203900D01*
X364300Y2203500D01*
X362300D01*
G01X-105300Y2225833D02*
X-105900Y2226233D01*
X-106600Y2226500D01*
X-107400D01*
X-108300Y2226100D01*
X-109000Y2225433D01*
X-109500Y2224633D01*
X-109900Y2223300D01*
X-110000Y2222100D01*
X-109800Y2220900D01*
X-109500Y2220100D01*
X-108900Y2219300D01*
X-108200Y2218767D01*
X-107500Y2218500D01*
X-106800D01*
X-106100Y2218767D01*
X-105500Y2219167D01*
X-105000Y2219700D01*
G01X-101600Y2218500D02*
Y2226500D01*
G01X-97400D02*
Y2218500D01*
G01Y2222500D02*
X-101600D01*
G01X-94000Y2218500D02*
X-91500Y2226500D01*
X-89000Y2218500D01*
G01X-89900Y2221300D02*
X-93100D01*
G01X-85500Y2218500D02*
Y2226500D01*
X-83000D01*
X-82200Y2226100D01*
X-81700Y2225567D01*
X-81500Y2224500D01*
X-81700Y2223433D01*
X-82300Y2222767D01*
X-83000Y2222367D01*
X-85500D01*
G01X-83000D02*
X-81500Y2218500D01*
G01X-75500Y2226500D02*
Y2218500D01*
G01X-77800Y2226500D02*
X-73200D01*
G01X-67500Y2218233D02*
X-67700Y2218367D01*
Y2218633D01*
X-67500Y2218767D01*
X-67300Y2218633D01*
Y2218367D01*
X-67500Y2218233D01*
G01X-54100Y2218500D02*
Y2226500D01*
X-51500Y2219833D01*
X-48900Y2226500D01*
Y2218500D01*
G01X-46000D02*
X-43500Y2226500D01*
X-41000Y2218500D01*
G01X-41900Y2221300D02*
X-45100D01*
G01X-37800Y2218500D02*
Y2226500D01*
X-33200Y2218500D01*
Y2226500D01*
G01X-29700D02*
Y2220767D01*
X-29300Y2219566D01*
X-28500Y2218767D01*
X-27500Y2218500D01*
X-26500Y2218767D01*
X-25700Y2219566D01*
X-25300Y2220767D01*
Y2226500D01*
G01X-21400Y2218500D02*
Y2226500D01*
X-17600D01*
G01X-19000Y2222633D02*
X-21400D01*
G01X-14000Y2218500D02*
X-11500Y2226500D01*
X-9000Y2218500D01*
G01X-9900Y2221300D02*
X-13100D01*
G01X-1300Y2225833D02*
X-1900Y2226233D01*
X-2600Y2226500D01*
X-3400D01*
X-4300Y2226100D01*
X-5000Y2225433D01*
X-5500Y2224633D01*
X-5900Y2223300D01*
X-6000Y2222100D01*
X-5800Y2220900D01*
X-5500Y2220100D01*
X-4900Y2219300D01*
X-4200Y2218767D01*
X-3500Y2218500D01*
X-2800D01*
X-2100Y2218767D01*
X-1500Y2219167D01*
X-1000Y2219700D01*
G01X4500Y2226500D02*
Y2218500D01*
G01X2200Y2226500D02*
X6800D01*
G01X10300D02*
Y2220767D01*
X10700Y2219566D01*
X11500Y2218767D01*
X12500Y2218500D01*
X13500Y2218767D01*
X14300Y2219566D01*
X14700Y2220767D01*
Y2226500D01*
G01X18500Y2218500D02*
Y2226500D01*
X21000D01*
X21800Y2226100D01*
X22300Y2225567D01*
X22500Y2224500D01*
X22300Y2223433D01*
X21700Y2222767D01*
X21000Y2222367D01*
X18500D01*
G01X21000D02*
X22500Y2218500D01*
G01X30500D02*
X26500D01*
Y2226500D01*
X30500D01*
G01X28900Y2222633D02*
X26500D01*
G01X34500Y2218500D02*
Y2226500D01*
X37000D01*
X37800Y2226100D01*
X38300Y2225567D01*
X38500Y2224500D01*
X38300Y2223433D01*
X37700Y2222767D01*
X37000Y2222367D01*
X34500D01*
G01X37000D02*
X38500Y2218500D01*
G01X51300Y2226500D02*
X53700D01*
G01X52500D02*
Y2218500D01*
G01X51300D02*
X53700D01*
G01X58400Y2219566D02*
X59200Y2218900D01*
X60100Y2218500D01*
X60900D01*
X61700Y2218900D01*
X62300Y2219566D01*
X62600Y2220500D01*
X62400Y2221433D01*
X61900Y2222233D01*
X61000Y2222767D01*
X59800Y2223033D01*
X59100Y2223567D01*
X58800Y2224500D01*
X59000Y2225433D01*
X59500Y2226100D01*
X60200Y2226500D01*
X60900D01*
X61600Y2226233D01*
X62200Y2225567D01*
G01X74600Y2218500D02*
Y2226500D01*
X78400D01*
G01X77000Y2222633D02*
X74600D01*
G01X82500Y2218500D02*
Y2226500D01*
X85000D01*
X85800Y2226100D01*
X86300Y2225567D01*
X86500Y2224500D01*
X86300Y2223433D01*
X85700Y2222767D01*
X85000Y2222367D01*
X82500D01*
G01X85000D02*
X86500Y2218500D01*
G01X94500D02*
X90500D01*
Y2226500D01*
X94500D01*
G01X92900Y2222633D02*
X90500D01*
G01X102500Y2218500D02*
X98500D01*
Y2226500D01*
X102500D01*
G01X100900Y2222633D02*
X98500D01*
G01X116500Y2226500D02*
Y2218500D01*
G01X114200Y2226500D02*
X118800D01*
G01X124500Y2218500D02*
X123700Y2218633D01*
X123000Y2219167D01*
X122400Y2219967D01*
X122000Y2220900D01*
X121800Y2221967D01*
Y2223033D01*
X122000Y2224100D01*
X122400Y2225033D01*
X123000Y2225833D01*
X123700Y2226367D01*
X124500Y2226500D01*
X125300Y2226367D01*
X126000Y2225833D01*
X126600Y2225033D01*
X127000Y2224100D01*
X127200Y2223033D01*
Y2221967D01*
X127000Y2220900D01*
X126600Y2219967D01*
X126000Y2219167D01*
X125300Y2218633D01*
X124500Y2218500D01*
G01X138000D02*
X140500Y2226500D01*
X143000Y2218500D01*
G01X142100Y2221300D02*
X138900D01*
G01X146300Y2218500D02*
Y2226500D01*
X148300D01*
X149100Y2226100D01*
X149700Y2225567D01*
X150200Y2224767D01*
X150600Y2223833D01*
X150700Y2222500D01*
X150600Y2221167D01*
X150200Y2220233D01*
X149700Y2219433D01*
X149100Y2218900D01*
X148300Y2218500D01*
X146300D01*
G01X154500Y2220100D02*
X155000Y2219300D01*
X155600Y2218767D01*
X156300Y2218500D01*
X157100Y2218767D01*
X157700Y2219300D01*
X158300Y2220100D01*
X158500Y2221167D01*
Y2226500D01*
G01X162300D02*
Y2220767D01*
X162700Y2219566D01*
X163500Y2218767D01*
X164500Y2218500D01*
X165500Y2218767D01*
X166300Y2219566D01*
X166700Y2220767D01*
Y2226500D01*
G01X170400Y2219566D02*
X171200Y2218900D01*
X172100Y2218500D01*
X172900D01*
X173700Y2218900D01*
X174300Y2219566D01*
X174600Y2220500D01*
X174400Y2221433D01*
X173900Y2222233D01*
X173000Y2222767D01*
X171800Y2223033D01*
X171100Y2223567D01*
X170800Y2224500D01*
X171000Y2225433D01*
X171500Y2226100D01*
X172200Y2226500D01*
X172900D01*
X173600Y2226233D01*
X174200Y2225567D01*
G01X180500Y2226500D02*
Y2218500D01*
G01X178200Y2226500D02*
X182800D01*
G01X196500D02*
Y2218500D01*
G01X194200Y2226500D02*
X198800D01*
G01X202500Y2218500D02*
Y2226500D01*
X205000D01*
X205800Y2226100D01*
X206300Y2225567D01*
X206500Y2224500D01*
X206300Y2223433D01*
X205700Y2222767D01*
X205000Y2222367D01*
X202500D01*
G01X205000D02*
X206500Y2218500D01*
G01X210000D02*
X212500Y2226500D01*
X215000Y2218500D01*
G01X214100Y2221300D02*
X210900D01*
G01X222700Y2225833D02*
X222100Y2226233D01*
X221400Y2226500D01*
X220600D01*
X219700Y2226100D01*
X219000Y2225433D01*
X218500Y2224633D01*
X218100Y2223300D01*
X218000Y2222100D01*
X218200Y2220900D01*
X218500Y2220100D01*
X219100Y2219300D01*
X219800Y2218767D01*
X220500Y2218500D01*
X221200D01*
X221900Y2218767D01*
X222500Y2219167D01*
X223000Y2219700D01*
G01X230500Y2218500D02*
X226500D01*
Y2226500D01*
X230500D01*
G01X228900Y2222633D02*
X226500D01*
G01X241500Y2226500D02*
X242900Y2218500D01*
X244500Y2226500D01*
X246100Y2218500D01*
X247500Y2226500D01*
G01X251300D02*
X253700D01*
G01X252500D02*
Y2218500D01*
G01X251300D02*
X253700D01*
G01X258300D02*
Y2226500D01*
X260300D01*
X261100Y2226100D01*
X261700Y2225567D01*
X262200Y2224767D01*
X262600Y2223833D01*
X262700Y2222500D01*
X262600Y2221167D01*
X262200Y2220233D01*
X261700Y2219433D01*
X261100Y2218900D01*
X260300Y2218500D01*
X258300D01*
G01X268500Y2226500D02*
Y2218500D01*
G01X266200Y2226500D02*
X270800D01*
G01X274400Y2218500D02*
Y2226500D01*
G01X278600D02*
Y2218500D01*
G01Y2222500D02*
X274400D01*
G01X282400Y2219566D02*
X283200Y2218900D01*
X284100Y2218500D01*
X284900D01*
X285700Y2218900D01*
X286300Y2219566D01*
X286600Y2220500D01*
X286400Y2221433D01*
X285900Y2222233D01*
X285000Y2222767D01*
X283800Y2223033D01*
X283100Y2223567D01*
X282800Y2224500D01*
X283000Y2225433D01*
X283500Y2226100D01*
X284200Y2226500D01*
X284900D01*
X285600Y2226233D01*
X286200Y2225567D01*
G01X292300Y2217033D02*
X292700Y2218767D01*
G01X314300Y2218500D02*
Y2226500D01*
X316300D01*
X317100Y2226100D01*
X317700Y2225567D01*
X318200Y2224767D01*
X318600Y2223833D01*
X318700Y2222500D01*
X318600Y2221167D01*
X318200Y2220233D01*
X317700Y2219433D01*
X317100Y2218900D01*
X316300Y2218500D01*
X314300D01*
G01X323300Y2226500D02*
X325700D01*
G01X324500D02*
Y2218500D01*
G01X323300D02*
X325700D01*
G01X334500D02*
X330500D01*
Y2226500D01*
X334500D01*
G01X332900Y2222633D02*
X330500D01*
G01X338500Y2226500D02*
Y2218500D01*
X342500D01*
G01X350500D02*
X346500D01*
Y2226500D01*
X350500D01*
G01X348900Y2222633D02*
X346500D01*
G01X358700Y2225833D02*
X358100Y2226233D01*
X357400Y2226500D01*
X356600D01*
X355700Y2226100D01*
X355000Y2225433D01*
X354500Y2224633D01*
X354100Y2223300D01*
X354000Y2222100D01*
X354200Y2220900D01*
X354500Y2220100D01*
X355100Y2219300D01*
X355800Y2218767D01*
X356500Y2218500D01*
X357200D01*
X357900Y2218767D01*
X358500Y2219167D01*
X359000Y2219700D01*
G01X364500Y2226500D02*
Y2218500D01*
G01X362200Y2226500D02*
X366800D01*
G01X370500Y2218500D02*
Y2226500D01*
X373000D01*
X373800Y2226100D01*
X374300Y2225567D01*
X374500Y2224500D01*
X374300Y2223433D01*
X373700Y2222767D01*
X373000Y2222367D01*
X370500D01*
G01X373000D02*
X374500Y2218500D01*
G01X379300Y2226500D02*
X381700D01*
G01X380500D02*
Y2218500D01*
G01X379300D02*
X381700D01*
G01X390700Y2225833D02*
X390100Y2226233D01*
X389400Y2226500D01*
X388600D01*
X387700Y2226100D01*
X387000Y2225433D01*
X386500Y2224633D01*
X386100Y2223300D01*
X386000Y2222100D01*
X386200Y2220900D01*
X386500Y2220100D01*
X387100Y2219300D01*
X387800Y2218767D01*
X388500Y2218500D01*
X389200D01*
X389900Y2218767D01*
X390500Y2219167D01*
X391000Y2219700D01*
G01X-121300Y2233500D02*
Y2241500D01*
X-125000Y2235767D01*
X-120000D01*
G01X-114500Y2233233D02*
X-114700Y2233367D01*
Y2233633D01*
X-114500Y2233767D01*
X-114300Y2233633D01*
Y2233367D01*
X-114500Y2233233D01*
G01X-104300Y2240833D02*
X-104900Y2241233D01*
X-105600Y2241500D01*
X-106400D01*
X-107300Y2241100D01*
X-108000Y2240433D01*
X-108500Y2239633D01*
X-108900Y2238300D01*
X-109000Y2237100D01*
X-108800Y2235900D01*
X-108500Y2235100D01*
X-107900Y2234300D01*
X-107200Y2233767D01*
X-106500Y2233500D01*
X-105800D01*
X-105100Y2233767D01*
X-104500Y2234167D01*
X-104000Y2234700D01*
G01X-98500Y2233500D02*
X-99300Y2233633D01*
X-100000Y2234167D01*
X-100600Y2234967D01*
X-101000Y2235900D01*
X-101200Y2236967D01*
Y2238033D01*
X-101000Y2239100D01*
X-100600Y2240033D01*
X-100000Y2240833D01*
X-99300Y2241367D01*
X-98500Y2241500D01*
X-97700Y2241367D01*
X-97000Y2240833D01*
X-96400Y2240033D01*
X-96000Y2239100D01*
X-95800Y2238033D01*
Y2236967D01*
X-96000Y2235900D01*
X-96400Y2234967D01*
X-97000Y2234167D01*
X-97700Y2233633D01*
X-98500Y2233500D01*
G01X-92800D02*
Y2241500D01*
X-88200Y2233500D01*
Y2241500D01*
G01X-82500D02*
Y2233500D01*
G01X-84800Y2241500D02*
X-80200D01*
G01X-76500Y2233500D02*
Y2241500D01*
X-74000D01*
X-73200Y2241100D01*
X-72700Y2240567D01*
X-72500Y2239500D01*
X-72700Y2238433D01*
X-73300Y2237767D01*
X-74000Y2237367D01*
X-76500D01*
G01X-74000D02*
X-72500Y2233500D01*
G01X-66500D02*
X-67300Y2233633D01*
X-68000Y2234167D01*
X-68600Y2234967D01*
X-69000Y2235900D01*
X-69200Y2236967D01*
Y2238033D01*
X-69000Y2239100D01*
X-68600Y2240033D01*
X-68000Y2240833D01*
X-67300Y2241367D01*
X-66500Y2241500D01*
X-65700Y2241367D01*
X-65000Y2240833D01*
X-64400Y2240033D01*
X-64000Y2239100D01*
X-63800Y2238033D01*
Y2236967D01*
X-64000Y2235900D01*
X-64400Y2234967D01*
X-65000Y2234167D01*
X-65700Y2233633D01*
X-66500Y2233500D01*
G01X-60500Y2241500D02*
Y2233500D01*
X-56500D01*
G01X-52500Y2241500D02*
Y2233500D01*
X-48500D01*
G01X-40500D02*
X-44500D01*
Y2241500D01*
X-40500D01*
G01X-42100Y2237633D02*
X-44500D01*
G01X-36700Y2233500D02*
Y2241500D01*
X-34700D01*
X-33900Y2241100D01*
X-33300Y2240567D01*
X-32800Y2239767D01*
X-32400Y2238833D01*
X-32300Y2237500D01*
X-32400Y2236167D01*
X-32800Y2235233D01*
X-33300Y2234433D01*
X-33900Y2233900D01*
X-34700Y2233500D01*
X-36700D01*
G01X-19700Y2241500D02*
X-17300D01*
G01X-18500D02*
Y2233500D01*
G01X-19700D02*
X-17300D01*
G01X-13100D02*
Y2241500D01*
X-10500Y2234833D01*
X-7900Y2241500D01*
Y2233500D01*
G01X-4500D02*
Y2241500D01*
X-2100D01*
X-1300Y2241100D01*
X-700Y2240167D01*
X-500Y2239100D01*
X-700Y2238033D01*
X-1200Y2237233D01*
X-2100Y2236833D01*
X-4500D01*
G01X7500Y2233500D02*
X3500D01*
Y2241500D01*
X7500D01*
G01X5900Y2237633D02*
X3500D01*
G01X11300Y2233500D02*
Y2241500D01*
X13300D01*
X14100Y2241100D01*
X14700Y2240567D01*
X15200Y2239767D01*
X15600Y2238833D01*
X15700Y2237500D01*
X15600Y2236167D01*
X15200Y2235233D01*
X14700Y2234433D01*
X14100Y2233900D01*
X13300Y2233500D01*
X11300D01*
G01X19000D02*
X21500Y2241500D01*
X24000Y2233500D01*
G01X23100Y2236300D02*
X19900D01*
G01X27200Y2233500D02*
Y2241500D01*
X31800Y2233500D01*
Y2241500D01*
G01X39700Y2240833D02*
X39100Y2241233D01*
X38400Y2241500D01*
X37600D01*
X36700Y2241100D01*
X36000Y2240433D01*
X35500Y2239633D01*
X35100Y2238300D01*
X35000Y2237100D01*
X35200Y2235900D01*
X35500Y2235100D01*
X36100Y2234300D01*
X36800Y2233767D01*
X37500Y2233500D01*
X38200D01*
X38900Y2233767D01*
X39500Y2234167D01*
X40000Y2234700D01*
G01X47500Y2233500D02*
X43500D01*
Y2241500D01*
X47500D01*
G01X45900Y2237633D02*
X43500D01*
G01X62300Y2237767D02*
X62700Y2238167D01*
X63000Y2238833D01*
X63200Y2239767D01*
X63000Y2240567D01*
X62600Y2241100D01*
X61900Y2241500D01*
X59200D01*
Y2233500D01*
X62500D01*
X63200Y2234033D01*
X63600Y2234833D01*
X63800Y2235767D01*
X63600Y2236700D01*
X63000Y2237500D01*
X62300Y2237767D01*
X59200D01*
G01X69500Y2233500D02*
X68700Y2233633D01*
X68000Y2234167D01*
X67400Y2234967D01*
X67000Y2235900D01*
X66800Y2236967D01*
Y2238033D01*
X67000Y2239100D01*
X67400Y2240033D01*
X68000Y2240833D01*
X68700Y2241367D01*
X69500Y2241500D01*
X70300Y2241367D01*
X71000Y2240833D01*
X71600Y2240033D01*
X72000Y2239100D01*
X72200Y2238033D01*
Y2236967D01*
X72000Y2235900D01*
X71600Y2234967D01*
X71000Y2234167D01*
X70300Y2233633D01*
X69500Y2233500D01*
G01X75000D02*
X77500Y2241500D01*
X80000Y2233500D01*
G01X79100Y2236300D02*
X75900D01*
G01X83500Y2233500D02*
Y2241500D01*
X86000D01*
X86800Y2241100D01*
X87300Y2240567D01*
X87500Y2239500D01*
X87300Y2238433D01*
X86700Y2237767D01*
X86000Y2237367D01*
X83500D01*
G01X86000D02*
X87500Y2233500D01*
G01X91300D02*
Y2241500D01*
X93300D01*
X94100Y2241100D01*
X94700Y2240567D01*
X95200Y2239767D01*
X95600Y2238833D01*
X95700Y2237500D01*
X95600Y2236167D01*
X95200Y2235233D01*
X94700Y2234433D01*
X94100Y2233900D01*
X93300Y2233500D01*
X91300D01*
G01X101500Y2233233D02*
X101300Y2233367D01*
Y2233633D01*
X101500Y2233767D01*
X101700Y2233633D01*
Y2233367D01*
X101500Y2233233D01*
G01X115400Y2234566D02*
X116200Y2233900D01*
X117100Y2233500D01*
X117900D01*
X118700Y2233900D01*
X119300Y2234566D01*
X119600Y2235500D01*
X119400Y2236433D01*
X118900Y2237233D01*
X118000Y2237767D01*
X116800Y2238033D01*
X116100Y2238567D01*
X115800Y2239500D01*
X116000Y2240433D01*
X116500Y2241100D01*
X117200Y2241500D01*
X117900D01*
X118600Y2241233D01*
X119200Y2240567D01*
G01X127500Y2233500D02*
X123500D01*
Y2241500D01*
X127500D01*
G01X125900Y2237633D02*
X123500D01*
G01X135500Y2233500D02*
X131500D01*
Y2241500D01*
X135500D01*
G01X133900Y2237633D02*
X131500D01*
G01X147500Y2241500D02*
Y2233500D01*
X151500D01*
G01X155000D02*
X157500Y2241500D01*
X160000Y2233500D01*
G01X159100Y2236300D02*
X155900D01*
G01X165500Y2233500D02*
Y2237100D01*
X163500Y2241500D01*
G01X167500D02*
X165500Y2237100D01*
G01X175500Y2233500D02*
X171500D01*
Y2241500D01*
X175500D01*
G01X173900Y2237633D02*
X171500D01*
G01X179500Y2233500D02*
Y2241500D01*
X182000D01*
X182800Y2241100D01*
X183300Y2240567D01*
X183500Y2239500D01*
X183300Y2238433D01*
X182700Y2237767D01*
X182000Y2237367D01*
X179500D01*
G01X182000D02*
X183500Y2233500D01*
G01X195400Y2234566D02*
X196200Y2233900D01*
X197100Y2233500D01*
X197900D01*
X198700Y2233900D01*
X199300Y2234566D01*
X199600Y2235500D01*
X199400Y2236433D01*
X198900Y2237233D01*
X198000Y2237767D01*
X196800Y2238033D01*
X196100Y2238567D01*
X195800Y2239500D01*
X196000Y2240433D01*
X196500Y2241100D01*
X197200Y2241500D01*
X197900D01*
X198600Y2241233D01*
X199200Y2240567D01*
G01X205500Y2241500D02*
Y2233500D01*
G01X203200Y2241500D02*
X207800D01*
G01X211000Y2233500D02*
X213500Y2241500D01*
X216000Y2233500D01*
G01X215100Y2236300D02*
X211900D01*
G01X223700Y2240833D02*
X223100Y2241233D01*
X222400Y2241500D01*
X221600D01*
X220700Y2241100D01*
X220000Y2240433D01*
X219500Y2239633D01*
X219100Y2238300D01*
X219000Y2237100D01*
X219200Y2235900D01*
X219500Y2235100D01*
X220100Y2234300D01*
X220800Y2233767D01*
X221500Y2233500D01*
X222200D01*
X222900Y2233767D01*
X223500Y2234167D01*
X224000Y2234700D01*
G01X227300Y2233500D02*
Y2241500D01*
G01X231100D02*
X227300Y2236566D01*
G01X231700Y2233500D02*
X229000Y2238833D01*
G01X235300Y2241500D02*
Y2235767D01*
X235700Y2234566D01*
X236500Y2233767D01*
X237500Y2233500D01*
X238500Y2233767D01*
X239300Y2234566D01*
X239700Y2235767D01*
Y2241500D01*
G01X243500Y2233500D02*
Y2241500D01*
X245900D01*
X246700Y2241100D01*
X247300Y2240167D01*
X247500Y2239100D01*
X247300Y2238033D01*
X246800Y2237233D01*
X245900Y2236833D01*
X243500D01*
G01X259000Y2233500D02*
X261500Y2241500D01*
X264000Y2233500D01*
G01X263100Y2236300D02*
X259900D01*
G01X267200Y2233500D02*
Y2241500D01*
X271800Y2233500D01*
Y2241500D01*
G01X275300Y2233500D02*
Y2241500D01*
X277300D01*
X278100Y2241100D01*
X278700Y2240567D01*
X279200Y2239767D01*
X279600Y2238833D01*
X279700Y2237500D01*
X279600Y2236167D01*
X279200Y2235233D01*
X278700Y2234433D01*
X278100Y2233900D01*
X277300Y2233500D01*
X275300D01*
G01X292300Y2241500D02*
X294700D01*
G01X293500D02*
Y2233500D01*
G01X292300D02*
X294700D01*
G01X298900D02*
Y2241500D01*
X301500Y2234833D01*
X304100Y2241500D01*
Y2233500D01*
G01X307500D02*
Y2241500D01*
X309900D01*
X310700Y2241100D01*
X311300Y2240167D01*
X311500Y2239100D01*
X311300Y2238033D01*
X310800Y2237233D01*
X309900Y2236833D01*
X307500D01*
G01X319500Y2233500D02*
X315500D01*
Y2241500D01*
X319500D01*
G01X317900Y2237633D02*
X315500D01*
G01X323300Y2233500D02*
Y2241500D01*
X325300D01*
X326100Y2241100D01*
X326700Y2240567D01*
X327200Y2239767D01*
X327600Y2238833D01*
X327700Y2237500D01*
X327600Y2236167D01*
X327200Y2235233D01*
X326700Y2234433D01*
X326100Y2233900D01*
X325300Y2233500D01*
X323300D01*
G01X331000D02*
X333500Y2241500D01*
X336000Y2233500D01*
G01X335100Y2236300D02*
X331900D01*
G01X339200Y2233500D02*
Y2241500D01*
X343800Y2233500D01*
Y2241500D01*
G01X351700Y2240833D02*
X351100Y2241233D01*
X350400Y2241500D01*
X349600D01*
X348700Y2241100D01*
X348000Y2240433D01*
X347500Y2239633D01*
X347100Y2238300D01*
X347000Y2237100D01*
X347200Y2235900D01*
X347500Y2235100D01*
X348100Y2234300D01*
X348800Y2233767D01*
X349500Y2233500D01*
X350200D01*
X350900Y2233767D01*
X351500Y2234167D01*
X352000Y2234700D01*
G01X359500Y2233500D02*
X355500D01*
Y2241500D01*
X359500D01*
G01X357900Y2237633D02*
X355500D01*
G01X-103900Y2252500D02*
X-101900D01*
Y2250100D01*
X-102500Y2249300D01*
X-103200Y2248767D01*
X-104200Y2248500D01*
X-105200Y2248767D01*
X-105900Y2249300D01*
X-106500Y2250100D01*
X-106900Y2251033D01*
X-107100Y2252100D01*
Y2253033D01*
X-106900Y2253833D01*
X-106500Y2254767D01*
X-105900Y2255567D01*
X-105300Y2256100D01*
X-104500Y2256500D01*
X-103800D01*
X-103000Y2256233D01*
X-102400Y2255700D01*
G01X-96500Y2248233D02*
X-96700Y2248367D01*
Y2248633D01*
X-96500Y2248767D01*
X-96300Y2248633D01*
Y2248367D01*
X-96500Y2248233D01*
G01X-90800Y2248500D02*
Y2256500D01*
X-86200Y2248500D01*
Y2256500D01*
G01X-78500Y2248500D02*
X-82500D01*
Y2256500D01*
X-78500D01*
G01X-80100Y2252633D02*
X-82500D01*
G01X-70500Y2248500D02*
X-74500D01*
Y2256500D01*
X-70500D01*
G01X-72100Y2252633D02*
X-74500D01*
G01X-66700Y2248500D02*
Y2256500D01*
X-64700D01*
X-63900Y2256100D01*
X-63300Y2255567D01*
X-62800Y2254767D01*
X-62400Y2253833D01*
X-62300Y2252500D01*
X-62400Y2251167D01*
X-62800Y2250233D01*
X-63300Y2249433D01*
X-63900Y2248900D01*
X-64700Y2248500D01*
X-66700D01*
G01X-50700Y2256500D02*
Y2250767D01*
X-50300Y2249566D01*
X-49500Y2248767D01*
X-48500Y2248500D01*
X-47500Y2248767D01*
X-46700Y2249566D01*
X-46300Y2250767D01*
Y2256500D01*
G01X-42500D02*
Y2248500D01*
X-38500D01*
G01X-27100D02*
Y2256500D01*
X-24500Y2249833D01*
X-21900Y2256500D01*
Y2248500D01*
G01X-19000D02*
X-16500Y2256500D01*
X-14000Y2248500D01*
G01X-14900Y2251300D02*
X-18100D01*
G01X-10500Y2248500D02*
Y2256500D01*
X-8000D01*
X-7200Y2256100D01*
X-6700Y2255567D01*
X-6500Y2254500D01*
X-6700Y2253433D01*
X-7300Y2252767D01*
X-8000Y2252367D01*
X-10500D01*
G01X-8000D02*
X-6500Y2248500D01*
G01X-2700D02*
Y2256500D01*
G01X1100D02*
X-2700Y2251566D01*
G01X1700Y2248500D02*
X-1000Y2253833D01*
G01X13000Y2248500D02*
X15500Y2256500D01*
X18000Y2248500D01*
G01X17100Y2251300D02*
X13900D01*
G01X21200Y2248500D02*
Y2256500D01*
X25800Y2248500D01*
Y2256500D01*
G01X29300Y2248500D02*
Y2256500D01*
X31300D01*
X32100Y2256100D01*
X32700Y2255567D01*
X33200Y2254767D01*
X33600Y2253833D01*
X33700Y2252500D01*
X33600Y2251167D01*
X33200Y2250233D01*
X32700Y2249433D01*
X32100Y2248900D01*
X31300Y2248500D01*
X29300D01*
G01X45300Y2256500D02*
Y2250767D01*
X45700Y2249566D01*
X46500Y2248767D01*
X47500Y2248500D01*
X48500Y2248767D01*
X49300Y2249566D01*
X49700Y2250767D01*
Y2256500D01*
G01X53500D02*
Y2248500D01*
X57500D01*
G01X69600D02*
Y2256500D01*
X73400D01*
G01X72000Y2252633D02*
X69600D01*
G01X78300Y2256500D02*
X80700D01*
G01X79500D02*
Y2248500D01*
G01X78300D02*
X80700D01*
G01X85500Y2256500D02*
Y2248500D01*
X89500D01*
G01X97500D02*
X93500D01*
Y2256500D01*
X97500D01*
G01X95900Y2252633D02*
X93500D01*
G01X109200Y2248500D02*
Y2256500D01*
X113800Y2248500D01*
Y2256500D01*
G01X117300D02*
Y2250767D01*
X117700Y2249566D01*
X118500Y2248767D01*
X119500Y2248500D01*
X120500Y2248767D01*
X121300Y2249566D01*
X121700Y2250767D01*
Y2256500D01*
G01X124900Y2248500D02*
Y2256500D01*
X127500Y2249833D01*
X130100Y2256500D01*
Y2248500D01*
G01X136300Y2252767D02*
X136700Y2253167D01*
X137000Y2253833D01*
X137200Y2254767D01*
X137000Y2255567D01*
X136600Y2256100D01*
X135900Y2256500D01*
X133200D01*
Y2248500D01*
X136500D01*
X137200Y2249033D01*
X137600Y2249833D01*
X137800Y2250767D01*
X137600Y2251700D01*
X137000Y2252500D01*
X136300Y2252767D01*
X133200D01*
G01X145500Y2248500D02*
X141500D01*
Y2256500D01*
X145500D01*
G01X143900Y2252633D02*
X141500D01*
G01X149500Y2248500D02*
Y2256500D01*
X152000D01*
X152800Y2256100D01*
X153300Y2255567D01*
X153500Y2254500D01*
X153300Y2253433D01*
X152700Y2252767D01*
X152000Y2252367D01*
X149500D01*
G01X152000D02*
X153500Y2248500D01*
G01X167500D02*
X166900Y2248633D01*
X166300Y2249167D01*
X165900Y2250100D01*
X165700Y2251167D01*
X165900Y2252233D01*
X166300Y2253167D01*
X166900Y2253700D01*
X167500Y2253833D01*
X168100Y2253700D01*
X168700Y2253167D01*
X169100Y2252233D01*
X169200Y2251167D01*
X169100Y2250100D01*
X168700Y2249167D01*
X168100Y2248633D01*
X167500Y2248500D01*
G01X173800D02*
Y2253833D01*
G01Y2252500D02*
X174200Y2253167D01*
X174800Y2253700D01*
X175600Y2253833D01*
X176300Y2253700D01*
X176900Y2253167D01*
X177200Y2252233D01*
Y2248500D01*
G01X189400Y2249566D02*
X190200Y2248900D01*
X191100Y2248500D01*
X191900D01*
X192700Y2248900D01*
X193300Y2249566D01*
X193600Y2250500D01*
X193400Y2251433D01*
X192900Y2252233D01*
X192000Y2252767D01*
X190800Y2253033D01*
X190100Y2253567D01*
X189800Y2254500D01*
X190000Y2255433D01*
X190500Y2256100D01*
X191200Y2256500D01*
X191900D01*
X192600Y2256233D01*
X193200Y2255567D01*
G01X198300Y2256500D02*
X200700D01*
G01X199500D02*
Y2248500D01*
G01X198300D02*
X200700D01*
G01X205500Y2256500D02*
Y2248500D01*
X209500D01*
G01X213300D02*
Y2256500D01*
G01X217100D02*
X213300Y2251566D01*
G01X217700Y2248500D02*
X215000Y2253833D01*
G01X221400Y2249566D02*
X222200Y2248900D01*
X223100Y2248500D01*
X223900D01*
X224700Y2248900D01*
X225300Y2249566D01*
X225600Y2250500D01*
X225400Y2251433D01*
X224900Y2252233D01*
X224000Y2252767D01*
X222800Y2253033D01*
X222100Y2253567D01*
X221800Y2254500D01*
X222000Y2255433D01*
X222500Y2256100D01*
X223200Y2256500D01*
X223900D01*
X224600Y2256233D01*
X225200Y2255567D01*
G01X233700Y2255833D02*
X233100Y2256233D01*
X232400Y2256500D01*
X231600D01*
X230700Y2256100D01*
X230000Y2255433D01*
X229500Y2254633D01*
X229100Y2253300D01*
X229000Y2252100D01*
X229200Y2250900D01*
X229500Y2250100D01*
X230100Y2249300D01*
X230800Y2248767D01*
X231500Y2248500D01*
X232200D01*
X232900Y2248767D01*
X233500Y2249167D01*
X234000Y2249700D01*
G01X237500Y2248500D02*
Y2256500D01*
X240000D01*
X240800Y2256100D01*
X241300Y2255567D01*
X241500Y2254500D01*
X241300Y2253433D01*
X240700Y2252767D01*
X240000Y2252367D01*
X237500D01*
G01X240000D02*
X241500Y2248500D01*
G01X249500D02*
X245500D01*
Y2256500D01*
X249500D01*
G01X247900Y2252633D02*
X245500D01*
G01X257500Y2248500D02*
X253500D01*
Y2256500D01*
X257500D01*
G01X255900Y2252633D02*
X253500D01*
G01X261200Y2248500D02*
Y2256500D01*
X265800Y2248500D01*
Y2256500D01*
G01X279500D02*
Y2248500D01*
G01X277200Y2256500D02*
X281800D01*
G01X287500Y2248500D02*
X286700Y2248633D01*
X286000Y2249167D01*
X285400Y2249967D01*
X285000Y2250900D01*
X284800Y2251967D01*
Y2253033D01*
X285000Y2254100D01*
X285400Y2255033D01*
X286000Y2255833D01*
X286700Y2256367D01*
X287500Y2256500D01*
X288300Y2256367D01*
X289000Y2255833D01*
X289600Y2255033D01*
X290000Y2254100D01*
X290200Y2253033D01*
Y2251967D01*
X290000Y2250900D01*
X289600Y2249967D01*
X289000Y2249167D01*
X288300Y2248633D01*
X287500Y2248500D01*
G01X293500D02*
Y2256500D01*
X295900D01*
X296700Y2256100D01*
X297300Y2255167D01*
X297500Y2254100D01*
X297300Y2253033D01*
X296800Y2252233D01*
X295900Y2251833D01*
X293500D01*
G01X309400Y2249566D02*
X310200Y2248900D01*
X311100Y2248500D01*
X311900D01*
X312700Y2248900D01*
X313300Y2249566D01*
X313600Y2250500D01*
X313400Y2251433D01*
X312900Y2252233D01*
X312000Y2252767D01*
X310800Y2253033D01*
X310100Y2253567D01*
X309800Y2254500D01*
X310000Y2255433D01*
X310500Y2256100D01*
X311200Y2256500D01*
X311900D01*
X312600Y2256233D01*
X313200Y2255567D01*
G01X318300Y2256500D02*
X320700D01*
G01X319500D02*
Y2248500D01*
G01X318300D02*
X320700D01*
G01X325300D02*
Y2256500D01*
X327300D01*
X328100Y2256100D01*
X328700Y2255567D01*
X329200Y2254767D01*
X329600Y2253833D01*
X329700Y2252500D01*
X329600Y2251167D01*
X329200Y2250233D01*
X328700Y2249433D01*
X328100Y2248900D01*
X327300Y2248500D01*
X325300D01*
G01X337500D02*
X333500D01*
Y2256500D01*
X337500D01*
G01X335900Y2252633D02*
X333500D01*
G01X-102500Y2278500D02*
X-106500D01*
Y2286500D01*
X-102500D01*
G01X-104100Y2282633D02*
X-106500D01*
G01X-96500Y2278233D02*
X-96700Y2278367D01*
Y2278633D01*
X-96500Y2278767D01*
X-96300Y2278633D01*
Y2278367D01*
X-96500Y2278233D01*
G01X-90500Y2278500D02*
Y2286500D01*
X-88100D01*
X-87300Y2286100D01*
X-86700Y2285167D01*
X-86500Y2284100D01*
X-86700Y2283033D01*
X-87200Y2282233D01*
X-88100Y2281833D01*
X-90500D01*
G01X-82500Y2278500D02*
Y2286500D01*
X-80000D01*
X-79200Y2286100D01*
X-78700Y2285567D01*
X-78500Y2284500D01*
X-78700Y2283433D01*
X-79300Y2282767D01*
X-80000Y2282367D01*
X-82500D01*
G01X-80000D02*
X-78500Y2278500D01*
G01X-72500D02*
X-73300Y2278633D01*
X-74000Y2279167D01*
X-74600Y2279967D01*
X-75000Y2280900D01*
X-75200Y2281967D01*
Y2283033D01*
X-75000Y2284100D01*
X-74600Y2285033D01*
X-74000Y2285833D01*
X-73300Y2286367D01*
X-72500Y2286500D01*
X-71700Y2286367D01*
X-71000Y2285833D01*
X-70400Y2285033D01*
X-70000Y2284100D01*
X-69800Y2283033D01*
Y2281967D01*
X-70000Y2280900D01*
X-70400Y2279967D01*
X-71000Y2279167D01*
X-71700Y2278633D01*
X-72500Y2278500D01*
G01X-67000Y2286500D02*
X-64500Y2278500D01*
X-62000Y2286500D01*
G01X-57700D02*
X-55300D01*
G01X-56500D02*
Y2278500D01*
G01X-57700D02*
X-55300D01*
G01X-50700D02*
Y2286500D01*
X-48700D01*
X-47900Y2286100D01*
X-47300Y2285567D01*
X-46800Y2284767D01*
X-46400Y2283833D01*
X-46300Y2282500D01*
X-46400Y2281167D01*
X-46800Y2280233D01*
X-47300Y2279433D01*
X-47900Y2278900D01*
X-48700Y2278500D01*
X-50700D01*
G01X-38500D02*
X-42500D01*
Y2286500D01*
X-38500D01*
G01X-40100Y2282633D02*
X-42500D01*
G01X-26500Y2278500D02*
Y2286500D01*
X-24100D01*
X-23300Y2286100D01*
X-22700Y2285167D01*
X-22500Y2284100D01*
X-22700Y2283033D01*
X-23200Y2282233D01*
X-24100Y2281833D01*
X-26500D01*
G01X-14300Y2285833D02*
X-14900Y2286233D01*
X-15600Y2286500D01*
X-16400D01*
X-17300Y2286100D01*
X-18000Y2285433D01*
X-18500Y2284633D01*
X-18900Y2283300D01*
X-19000Y2282100D01*
X-18800Y2280900D01*
X-18500Y2280100D01*
X-17900Y2279300D01*
X-17200Y2278767D01*
X-16500Y2278500D01*
X-15800D01*
X-15100Y2278767D01*
X-14500Y2279167D01*
X-14000Y2279700D01*
G01X-7700Y2282767D02*
X-7300Y2283167D01*
X-7000Y2283833D01*
X-6800Y2284767D01*
X-7000Y2285567D01*
X-7400Y2286100D01*
X-8100Y2286500D01*
X-10800D01*
Y2278500D01*
X-7500D01*
X-6800Y2279033D01*
X-6400Y2279833D01*
X-6200Y2280767D01*
X-6400Y2281700D01*
X-7000Y2282500D01*
X-7700Y2282767D01*
X-10800D01*
G01X5600Y2278500D02*
Y2286500D01*
X9400D01*
G01X8000Y2282633D02*
X5600D01*
G01X14300Y2286500D02*
X16700D01*
G01X15500D02*
Y2278500D01*
G01X14300D02*
X16700D01*
G01X21500Y2286500D02*
Y2278500D01*
X25500D01*
G01X28900D02*
Y2286500D01*
X31500Y2279833D01*
X34100Y2286500D01*
Y2278500D01*
G01X-106400Y2263500D02*
Y2271500D01*
X-102600D01*
G01X-104000Y2267633D02*
X-106400D01*
G01X-96500Y2263233D02*
X-96700Y2263367D01*
Y2263633D01*
X-96500Y2263767D01*
X-96300Y2263633D01*
Y2263367D01*
X-96500Y2263233D01*
G01X-90800Y2263500D02*
Y2271500D01*
X-86200Y2263500D01*
Y2271500D01*
G01X-78500Y2263500D02*
X-82500D01*
Y2271500D01*
X-78500D01*
G01X-80100Y2267633D02*
X-82500D01*
G01X-70500Y2263500D02*
X-74500D01*
Y2271500D01*
X-70500D01*
G01X-72100Y2267633D02*
X-74500D01*
G01X-66700Y2263500D02*
Y2271500D01*
X-64700D01*
X-63900Y2271100D01*
X-63300Y2270567D01*
X-62800Y2269767D01*
X-62400Y2268833D01*
X-62300Y2267500D01*
X-62400Y2266167D01*
X-62800Y2265233D01*
X-63300Y2264433D01*
X-63900Y2263900D01*
X-64700Y2263500D01*
X-66700D01*
G01X-50500D02*
Y2271500D01*
X-48100D01*
X-47300Y2271100D01*
X-46700Y2270167D01*
X-46500Y2269100D01*
X-46700Y2268033D01*
X-47200Y2267233D01*
X-48100Y2266833D01*
X-50500D01*
G01X-38300Y2270833D02*
X-38900Y2271233D01*
X-39600Y2271500D01*
X-40400D01*
X-41300Y2271100D01*
X-42000Y2270433D01*
X-42500Y2269633D01*
X-42900Y2268300D01*
X-43000Y2267100D01*
X-42800Y2265900D01*
X-42500Y2265100D01*
X-41900Y2264300D01*
X-41200Y2263767D01*
X-40500Y2263500D01*
X-39800D01*
X-39100Y2263767D01*
X-38500Y2264167D01*
X-38000Y2264700D01*
G01X-31700Y2267767D02*
X-31300Y2268167D01*
X-31000Y2268833D01*
X-30800Y2269767D01*
X-31000Y2270567D01*
X-31400Y2271100D01*
X-32100Y2271500D01*
X-34800D01*
Y2263500D01*
X-31500D01*
X-30800Y2264033D01*
X-30400Y2264833D01*
X-30200Y2265767D01*
X-30400Y2266700D01*
X-31000Y2267500D01*
X-31700Y2267767D01*
X-34800D01*
G01X-19100Y2263500D02*
Y2271500D01*
X-16500Y2264833D01*
X-13900Y2271500D01*
Y2263500D01*
G01X-11000D02*
X-8500Y2271500D01*
X-6000Y2263500D01*
G01X-6900Y2266300D02*
X-10100D01*
G01X-2700Y2263500D02*
Y2271500D01*
G01X1100D02*
X-2700Y2266566D01*
G01X1700Y2263500D02*
X-1000Y2268833D01*
G01X9500Y2263500D02*
X5500D01*
Y2271500D01*
X9500D01*
G01X7900Y2267633D02*
X5500D01*
G01X13500Y2263500D02*
Y2271500D01*
X16000D01*
X16800Y2271100D01*
X17300Y2270567D01*
X17500Y2269500D01*
X17300Y2268433D01*
X16700Y2267767D01*
X16000Y2267367D01*
X13500D01*
G01X16000D02*
X17500Y2263500D01*
G01X29500Y2271500D02*
Y2263500D01*
X33500D01*
G01X39500D02*
X38700Y2263633D01*
X38000Y2264167D01*
X37400Y2264967D01*
X37000Y2265900D01*
X36800Y2266967D01*
Y2268033D01*
X37000Y2269100D01*
X37400Y2270033D01*
X38000Y2270833D01*
X38700Y2271367D01*
X39500Y2271500D01*
X40300Y2271367D01*
X41000Y2270833D01*
X41600Y2270033D01*
X42000Y2269100D01*
X42200Y2268033D01*
Y2266967D01*
X42000Y2265900D01*
X41600Y2264967D01*
X41000Y2264167D01*
X40300Y2263633D01*
X39500Y2263500D01*
G01X48100Y2267500D02*
X50100D01*
Y2265100D01*
X49500Y2264300D01*
X48800Y2263767D01*
X47800Y2263500D01*
X46800Y2263767D01*
X46100Y2264300D01*
X45500Y2265100D01*
X45100Y2266033D01*
X44900Y2267100D01*
Y2268033D01*
X45100Y2268833D01*
X45500Y2269767D01*
X46100Y2270567D01*
X46700Y2271100D01*
X47500Y2271500D01*
X48200D01*
X49000Y2271233D01*
X49600Y2270700D01*
G01X55500Y2263500D02*
X54700Y2263633D01*
X54000Y2264167D01*
X53400Y2264967D01*
X53000Y2265900D01*
X52800Y2266967D01*
Y2268033D01*
X53000Y2269100D01*
X53400Y2270033D01*
X54000Y2270833D01*
X54700Y2271367D01*
X55500Y2271500D01*
X56300Y2271367D01*
X57000Y2270833D01*
X57600Y2270033D01*
X58000Y2269100D01*
X58200Y2268033D01*
Y2266967D01*
X58000Y2265900D01*
X57600Y2264967D01*
X57000Y2264167D01*
X56300Y2263633D01*
X55500Y2263500D01*
G01X69000D02*
X71500Y2271500D01*
X74000Y2263500D01*
G01X73100Y2266300D02*
X69900D01*
G01X77200Y2263500D02*
Y2271500D01*
X81800Y2263500D01*
Y2271500D01*
G01X85300Y2263500D02*
Y2271500D01*
X87300D01*
X88100Y2271100D01*
X88700Y2270567D01*
X89200Y2269767D01*
X89600Y2268833D01*
X89700Y2267500D01*
X89600Y2266167D01*
X89200Y2265233D01*
X88700Y2264433D01*
X88100Y2263900D01*
X87300Y2263500D01*
X85300D01*
G01X101300D02*
Y2271500D01*
X103300D01*
X104100Y2271100D01*
X104700Y2270567D01*
X105200Y2269767D01*
X105600Y2268833D01*
X105700Y2267500D01*
X105600Y2266167D01*
X105200Y2265233D01*
X104700Y2264433D01*
X104100Y2263900D01*
X103300Y2263500D01*
X101300D01*
G01X109000D02*
X111500Y2271500D01*
X114000Y2263500D01*
G01X113100Y2266300D02*
X109900D01*
G01X119500Y2271500D02*
Y2263500D01*
G01X117200Y2271500D02*
X121800D01*
G01X129500Y2263500D02*
X125500D01*
Y2271500D01*
X129500D01*
G01X127900Y2267633D02*
X125500D01*
G01X145700Y2270833D02*
X145100Y2271233D01*
X144400Y2271500D01*
X143600D01*
X142700Y2271100D01*
X142000Y2270433D01*
X141500Y2269633D01*
X141100Y2268300D01*
X141000Y2267100D01*
X141200Y2265900D01*
X141500Y2265100D01*
X142100Y2264300D01*
X142800Y2263767D01*
X143500Y2263500D01*
X144200D01*
X144900Y2263767D01*
X145500Y2264167D01*
X146000Y2264700D01*
G01X151500Y2263500D02*
X150700Y2263633D01*
X150000Y2264167D01*
X149400Y2264967D01*
X149000Y2265900D01*
X148800Y2266967D01*
Y2268033D01*
X149000Y2269100D01*
X149400Y2270033D01*
X150000Y2270833D01*
X150700Y2271367D01*
X151500Y2271500D01*
X152300Y2271367D01*
X153000Y2270833D01*
X153600Y2270033D01*
X154000Y2269100D01*
X154200Y2268033D01*
Y2266967D01*
X154000Y2265900D01*
X153600Y2264967D01*
X153000Y2264167D01*
X152300Y2263633D01*
X151500Y2263500D01*
G01X157300D02*
Y2271500D01*
X159300D01*
X160100Y2271100D01*
X160700Y2270567D01*
X161200Y2269767D01*
X161600Y2268833D01*
X161700Y2267500D01*
X161600Y2266167D01*
X161200Y2265233D01*
X160700Y2264433D01*
X160100Y2263900D01*
X159300Y2263500D01*
X157300D01*
G01X169500D02*
X165500D01*
Y2271500D01*
X169500D01*
G01X167900Y2267633D02*
X165500D01*
G01X183000Y2260833D02*
X182000Y2262167D01*
X181500Y2263500D01*
Y2268833D01*
X182000Y2270167D01*
X183000Y2271500D01*
G01X188500D02*
X189900Y2263500D01*
X191500Y2271500D01*
X193100Y2263500D01*
X194500Y2271500D01*
G01X196500D02*
X197900Y2263500D01*
X199500Y2271500D01*
X201100Y2263500D01*
X202500Y2271500D01*
G01X207500Y2263500D02*
Y2267100D01*
X205500Y2271500D01*
G01X209500D02*
X207500Y2267100D01*
G01X215500Y2263500D02*
Y2267100D01*
X213500Y2271500D01*
G01X217500D02*
X215500Y2267100D01*
G01X224000Y2260833D02*
X225000Y2262167D01*
X225500Y2263500D01*
Y2268833D01*
X225000Y2270167D01*
X224000Y2271500D01*
G01X239500Y2263500D02*
X238900Y2263633D01*
X238300Y2264167D01*
X237900Y2265100D01*
X237700Y2266167D01*
X237900Y2267233D01*
X238300Y2268167D01*
X238900Y2268700D01*
X239500Y2268833D01*
X240100Y2268700D01*
X240700Y2268167D01*
X241100Y2267233D01*
X241200Y2266167D01*
X241100Y2265100D01*
X240700Y2264167D01*
X240100Y2263633D01*
X239500Y2263500D01*
G01X245800D02*
Y2268833D01*
G01Y2267500D02*
X246200Y2268167D01*
X246800Y2268700D01*
X247600Y2268833D01*
X248300Y2268700D01*
X248900Y2268167D01*
X249200Y2267233D01*
Y2263500D01*
G01X261400Y2264566D02*
X262200Y2263900D01*
X263100Y2263500D01*
X263900D01*
X264700Y2263900D01*
X265300Y2264566D01*
X265600Y2265500D01*
X265400Y2266433D01*
X264900Y2267233D01*
X264000Y2267767D01*
X262800Y2268033D01*
X262100Y2268567D01*
X261800Y2269500D01*
X262000Y2270433D01*
X262500Y2271100D01*
X263200Y2271500D01*
X263900D01*
X264600Y2271233D01*
X265200Y2270567D01*
G01X270300Y2271500D02*
X272700D01*
G01X271500D02*
Y2263500D01*
G01X270300D02*
X272700D01*
G01X277500Y2271500D02*
Y2263500D01*
X281500D01*
G01X285300D02*
Y2271500D01*
G01X289100D02*
X285300Y2266566D01*
G01X289700Y2263500D02*
X287000Y2268833D01*
G01X293400Y2264566D02*
X294200Y2263900D01*
X295100Y2263500D01*
X295900D01*
X296700Y2263900D01*
X297300Y2264566D01*
X297600Y2265500D01*
X297400Y2266433D01*
X296900Y2267233D01*
X296000Y2267767D01*
X294800Y2268033D01*
X294100Y2268567D01*
X293800Y2269500D01*
X294000Y2270433D01*
X294500Y2271100D01*
X295200Y2271500D01*
X295900D01*
X296600Y2271233D01*
X297200Y2270567D01*
G01X305700Y2270833D02*
X305100Y2271233D01*
X304400Y2271500D01*
X303600D01*
X302700Y2271100D01*
X302000Y2270433D01*
X301500Y2269633D01*
X301100Y2268300D01*
X301000Y2267100D01*
X301200Y2265900D01*
X301500Y2265100D01*
X302100Y2264300D01*
X302800Y2263767D01*
X303500Y2263500D01*
X304200D01*
X304900Y2263767D01*
X305500Y2264167D01*
X306000Y2264700D01*
G01X309500Y2263500D02*
Y2271500D01*
X312000D01*
X312800Y2271100D01*
X313300Y2270567D01*
X313500Y2269500D01*
X313300Y2268433D01*
X312700Y2267767D01*
X312000Y2267367D01*
X309500D01*
G01X312000D02*
X313500Y2263500D01*
G01X321500D02*
X317500D01*
Y2271500D01*
X321500D01*
G01X319900Y2267633D02*
X317500D01*
G01X329500Y2263500D02*
X325500D01*
Y2271500D01*
X329500D01*
G01X327900Y2267633D02*
X325500D01*
G01X333200Y2263500D02*
Y2271500D01*
X337800Y2263500D01*
Y2271500D01*
G01X351500D02*
Y2263500D01*
G01X349200Y2271500D02*
X353800D01*
G01X359500Y2263500D02*
X358700Y2263633D01*
X358000Y2264167D01*
X357400Y2264967D01*
X357000Y2265900D01*
X356800Y2266967D01*
Y2268033D01*
X357000Y2269100D01*
X357400Y2270033D01*
X358000Y2270833D01*
X358700Y2271367D01*
X359500Y2271500D01*
X360300Y2271367D01*
X361000Y2270833D01*
X361600Y2270033D01*
X362000Y2269100D01*
X362200Y2268033D01*
Y2266967D01*
X362000Y2265900D01*
X361600Y2264967D01*
X361000Y2264167D01*
X360300Y2263633D01*
X359500Y2263500D01*
G01X365500D02*
Y2271500D01*
X367900D01*
X368700Y2271100D01*
X369300Y2270167D01*
X369500Y2269100D01*
X369300Y2268033D01*
X368800Y2267233D01*
X367900Y2266833D01*
X365500D01*
G01X381400Y2264566D02*
X382200Y2263900D01*
X383100Y2263500D01*
X383900D01*
X384700Y2263900D01*
X385300Y2264566D01*
X385600Y2265500D01*
X385400Y2266433D01*
X384900Y2267233D01*
X384000Y2267767D01*
X382800Y2268033D01*
X382100Y2268567D01*
X381800Y2269500D01*
X382000Y2270433D01*
X382500Y2271100D01*
X383200Y2271500D01*
X383900D01*
X384600Y2271233D01*
X385200Y2270567D01*
G01X390300Y2271500D02*
X392700D01*
G01X391500D02*
Y2263500D01*
G01X390300D02*
X392700D01*
G01X397300D02*
Y2271500D01*
X399300D01*
X400100Y2271100D01*
X400700Y2270567D01*
X401200Y2269767D01*
X401600Y2268833D01*
X401700Y2267500D01*
X401600Y2266167D01*
X401200Y2265233D01*
X400700Y2264433D01*
X400100Y2263900D01*
X399300Y2263500D01*
X397300D01*
G01X409500D02*
X405500D01*
Y2271500D01*
X409500D01*
G01X407900Y2267633D02*
X405500D01*
G01X426500Y2260833D02*
X421500Y2268833D01*
Y2270167D01*
X422500Y2271500D01*
X423500D01*
X424500Y2270167D01*
Y2268833D01*
X423500Y2267500D01*
X421500Y2266167D01*
X420500Y2264833D01*
Y2262167D01*
X421500Y2260833D01*
X424500D01*
X426500Y2263500D01*
G01X440300Y2267767D02*
X440700Y2268167D01*
X441000Y2268833D01*
X441200Y2269767D01*
X441000Y2270567D01*
X440600Y2271100D01*
X439900Y2271500D01*
X437200D01*
Y2263500D01*
X440500D01*
X441200Y2264033D01*
X441600Y2264833D01*
X441800Y2265767D01*
X441600Y2266700D01*
X441000Y2267500D01*
X440300Y2267767D01*
X437200D01*
G01X445500Y2263500D02*
Y2271500D01*
X448000D01*
X448800Y2271100D01*
X449300Y2270567D01*
X449500Y2269500D01*
X449300Y2268433D01*
X448700Y2267767D01*
X448000Y2267367D01*
X445500D01*
G01X448000D02*
X449500Y2263500D01*
G01X457500D02*
X453500D01*
Y2271500D01*
X457500D01*
G01X455900Y2267633D02*
X453500D01*
G01X461000Y2263500D02*
X463500Y2271500D01*
X466000Y2263500D01*
G01X465100Y2266300D02*
X461900D01*
G01X469300Y2263500D02*
Y2271500D01*
G01X473100D02*
X469300Y2266566D01*
G01X473700Y2263500D02*
X471000Y2268833D01*
G01X477000Y2263500D02*
X479500Y2271500D01*
X482000Y2263500D01*
G01X481100Y2266300D02*
X477900D01*
G01X484500Y2271500D02*
X485900Y2263500D01*
X487500Y2271500D01*
X489100Y2263500D01*
X490500Y2271500D01*
G01X493000Y2263500D02*
X495500Y2271500D01*
X498000Y2263500D01*
G01X497100Y2266300D02*
X493900D01*
G01X503500Y2263500D02*
Y2267100D01*
X501500Y2271500D01*
G01X505500D02*
X503500Y2267100D01*
G01X-106700Y2293500D02*
Y2301500D01*
X-104700D01*
X-103900Y2301100D01*
X-103300Y2300567D01*
X-102800Y2299767D01*
X-102400Y2298833D01*
X-102300Y2297500D01*
X-102400Y2296167D01*
X-102800Y2295233D01*
X-103300Y2294433D01*
X-103900Y2293900D01*
X-104700Y2293500D01*
X-106700D01*
G01X-96500Y2293233D02*
X-96700Y2293367D01*
Y2293633D01*
X-96500Y2293767D01*
X-96300Y2293633D01*
Y2293367D01*
X-96500Y2293233D01*
G01X-90500Y2293500D02*
Y2301500D01*
X-88100D01*
X-87300Y2301100D01*
X-86700Y2300167D01*
X-86500Y2299100D01*
X-86700Y2298033D01*
X-87200Y2297233D01*
X-88100Y2296833D01*
X-90500D01*
G01X-82500Y2293500D02*
Y2301500D01*
X-80000D01*
X-79200Y2301100D01*
X-78700Y2300567D01*
X-78500Y2299500D01*
X-78700Y2298433D01*
X-79300Y2297767D01*
X-80000Y2297367D01*
X-82500D01*
G01X-80000D02*
X-78500Y2293500D01*
G01X-72500D02*
X-73300Y2293633D01*
X-74000Y2294167D01*
X-74600Y2294967D01*
X-75000Y2295900D01*
X-75200Y2296967D01*
Y2298033D01*
X-75000Y2299100D01*
X-74600Y2300033D01*
X-74000Y2300833D01*
X-73300Y2301367D01*
X-72500Y2301500D01*
X-71700Y2301367D01*
X-71000Y2300833D01*
X-70400Y2300033D01*
X-70000Y2299100D01*
X-69800Y2298033D01*
Y2296967D01*
X-70000Y2295900D01*
X-70400Y2294967D01*
X-71000Y2294167D01*
X-71700Y2293633D01*
X-72500Y2293500D01*
G01X-67000Y2301500D02*
X-64500Y2293500D01*
X-62000Y2301500D01*
G01X-57700D02*
X-55300D01*
G01X-56500D02*
Y2293500D01*
G01X-57700D02*
X-55300D01*
G01X-50700D02*
Y2301500D01*
X-48700D01*
X-47900Y2301100D01*
X-47300Y2300567D01*
X-46800Y2299767D01*
X-46400Y2298833D01*
X-46300Y2297500D01*
X-46400Y2296167D01*
X-46800Y2295233D01*
X-47300Y2294433D01*
X-47900Y2293900D01*
X-48700Y2293500D01*
X-50700D01*
G01X-38500D02*
X-42500D01*
Y2301500D01*
X-38500D01*
G01X-40100Y2297633D02*
X-42500D01*
G01X-25700Y2301500D02*
X-23300D01*
G01X-24500D02*
Y2293500D01*
G01X-25700D02*
X-23300D01*
G01X-19100D02*
Y2301500D01*
X-16500Y2294833D01*
X-13900Y2301500D01*
Y2293500D01*
G01X-10500D02*
Y2301500D01*
X-8100D01*
X-7300Y2301100D01*
X-6700Y2300167D01*
X-6500Y2299100D01*
X-6700Y2298033D01*
X-7200Y2297233D01*
X-8100Y2296833D01*
X-10500D01*
G01X1500Y2293500D02*
X-2500D01*
Y2301500D01*
X1500D01*
G01X-100Y2297633D02*
X-2500D01*
G01X5300Y2293500D02*
Y2301500D01*
X7300D01*
X8100Y2301100D01*
X8700Y2300567D01*
X9200Y2299767D01*
X9600Y2298833D01*
X9700Y2297500D01*
X9600Y2296167D01*
X9200Y2295233D01*
X8700Y2294433D01*
X8100Y2293900D01*
X7300Y2293500D01*
X5300D01*
G01X13000D02*
X15500Y2301500D01*
X18000Y2293500D01*
G01X17100Y2296300D02*
X13900D01*
G01X21200Y2293500D02*
Y2301500D01*
X25800Y2293500D01*
Y2301500D01*
G01X33700Y2300833D02*
X33100Y2301233D01*
X32400Y2301500D01*
X31600D01*
X30700Y2301100D01*
X30000Y2300433D01*
X29500Y2299633D01*
X29100Y2298300D01*
X29000Y2297100D01*
X29200Y2295900D01*
X29500Y2295100D01*
X30100Y2294300D01*
X30800Y2293767D01*
X31500Y2293500D01*
X32200D01*
X32900Y2293767D01*
X33500Y2294167D01*
X34000Y2294700D01*
G01X41500Y2293500D02*
X37500D01*
Y2301500D01*
X41500D01*
G01X39900Y2297633D02*
X37500D01*
G01X57700Y2300833D02*
X57100Y2301233D01*
X56400Y2301500D01*
X55600D01*
X54700Y2301100D01*
X54000Y2300433D01*
X53500Y2299633D01*
X53100Y2298300D01*
X53000Y2297100D01*
X53200Y2295900D01*
X53500Y2295100D01*
X54100Y2294300D01*
X54800Y2293767D01*
X55500Y2293500D01*
X56200D01*
X56900Y2293767D01*
X57500Y2294167D01*
X58000Y2294700D01*
G01X63500Y2293500D02*
X62700Y2293633D01*
X62000Y2294167D01*
X61400Y2294967D01*
X61000Y2295900D01*
X60800Y2296967D01*
Y2298033D01*
X61000Y2299100D01*
X61400Y2300033D01*
X62000Y2300833D01*
X62700Y2301367D01*
X63500Y2301500D01*
X64300Y2301367D01*
X65000Y2300833D01*
X65600Y2300033D01*
X66000Y2299100D01*
X66200Y2298033D01*
Y2296967D01*
X66000Y2295900D01*
X65600Y2294967D01*
X65000Y2294167D01*
X64300Y2293633D01*
X63500Y2293500D01*
G01X69300Y2301500D02*
Y2295767D01*
X69700Y2294566D01*
X70500Y2293767D01*
X71500Y2293500D01*
X72500Y2293767D01*
X73300Y2294566D01*
X73700Y2295767D01*
Y2301500D01*
G01X77500Y2293500D02*
Y2301500D01*
X79900D01*
X80700Y2301100D01*
X81300Y2300167D01*
X81500Y2299100D01*
X81300Y2298033D01*
X80800Y2297233D01*
X79900Y2296833D01*
X77500D01*
G01X87500Y2293500D02*
X86700Y2293633D01*
X86000Y2294167D01*
X85400Y2294967D01*
X85000Y2295900D01*
X84800Y2296967D01*
Y2298033D01*
X85000Y2299100D01*
X85400Y2300033D01*
X86000Y2300833D01*
X86700Y2301367D01*
X87500Y2301500D01*
X88300Y2301367D01*
X89000Y2300833D01*
X89600Y2300033D01*
X90000Y2299100D01*
X90200Y2298033D01*
Y2296967D01*
X90000Y2295900D01*
X89600Y2294967D01*
X89000Y2294167D01*
X88300Y2293633D01*
X87500Y2293500D01*
G01X93200D02*
Y2301500D01*
X97800Y2293500D01*
Y2301500D01*
G01X109000Y2293500D02*
X111500Y2301500D01*
X114000Y2293500D01*
G01X113100Y2296300D02*
X109900D01*
G01X117200Y2293500D02*
Y2301500D01*
X121800Y2293500D01*
Y2301500D01*
G01X125300Y2293500D02*
Y2301500D01*
X127300D01*
X128100Y2301100D01*
X128700Y2300567D01*
X129200Y2299767D01*
X129600Y2298833D01*
X129700Y2297500D01*
X129600Y2296167D01*
X129200Y2295233D01*
X128700Y2294433D01*
X128100Y2293900D01*
X127300Y2293500D01*
X125300D01*
G01X140900D02*
Y2301500D01*
X143500Y2294833D01*
X146100Y2301500D01*
Y2293500D01*
G01X153500D02*
X149500D01*
Y2301500D01*
X153500D01*
G01X151900Y2297633D02*
X149500D01*
G01X157000Y2293500D02*
X159500Y2301500D01*
X162000Y2293500D01*
G01X161100Y2296300D02*
X157900D01*
G01X165400Y2294566D02*
X166200Y2293900D01*
X167100Y2293500D01*
X167900D01*
X168700Y2293900D01*
X169300Y2294566D01*
X169600Y2295500D01*
X169400Y2296433D01*
X168900Y2297233D01*
X168000Y2297767D01*
X166800Y2298033D01*
X166100Y2298567D01*
X165800Y2299500D01*
X166000Y2300433D01*
X166500Y2301100D01*
X167200Y2301500D01*
X167900D01*
X168600Y2301233D01*
X169200Y2300567D01*
G01X173300Y2301500D02*
Y2295767D01*
X173700Y2294566D01*
X174500Y2293767D01*
X175500Y2293500D01*
X176500Y2293767D01*
X177300Y2294566D01*
X177700Y2295767D01*
Y2301500D01*
G01X181500Y2293500D02*
Y2301500D01*
X184000D01*
X184800Y2301100D01*
X185300Y2300567D01*
X185500Y2299500D01*
X185300Y2298433D01*
X184700Y2297767D01*
X184000Y2297367D01*
X181500D01*
G01X184000D02*
X185500Y2293500D01*
G01X193500D02*
X189500D01*
Y2301500D01*
X193500D01*
G01X191900Y2297633D02*
X189500D01*
G01X196900Y2293500D02*
Y2301500D01*
X199500Y2294833D01*
X202100Y2301500D01*
Y2293500D01*
G01X209500D02*
X205500D01*
Y2301500D01*
X209500D01*
G01X207900Y2297633D02*
X205500D01*
G01X213200Y2293500D02*
Y2301500D01*
X217800Y2293500D01*
Y2301500D01*
G01X223500D02*
Y2293500D01*
G01X221200Y2301500D02*
X225800D01*
G01X237500Y2293500D02*
Y2301500D01*
X240000D01*
X240800Y2301100D01*
X241300Y2300567D01*
X241500Y2299500D01*
X241300Y2298433D01*
X240700Y2297767D01*
X240000Y2297367D01*
X237500D01*
G01X240000D02*
X241500Y2293500D01*
G01X249500D02*
X245500D01*
Y2301500D01*
X249500D01*
G01X247900Y2297633D02*
X245500D01*
G01X253500Y2293500D02*
Y2301500D01*
X255900D01*
X256700Y2301100D01*
X257300Y2300167D01*
X257500Y2299100D01*
X257300Y2298033D01*
X256800Y2297233D01*
X255900Y2296833D01*
X253500D01*
G01X263500Y2293500D02*
X262700Y2293633D01*
X262000Y2294167D01*
X261400Y2294967D01*
X261000Y2295900D01*
X260800Y2296967D01*
Y2298033D01*
X261000Y2299100D01*
X261400Y2300033D01*
X262000Y2300833D01*
X262700Y2301367D01*
X263500Y2301500D01*
X264300Y2301367D01*
X265000Y2300833D01*
X265600Y2300033D01*
X266000Y2299100D01*
X266200Y2298033D01*
Y2296967D01*
X266000Y2295900D01*
X265600Y2294967D01*
X265000Y2294167D01*
X264300Y2293633D01*
X263500Y2293500D01*
G01X269500D02*
Y2301500D01*
X272000D01*
X272800Y2301100D01*
X273300Y2300567D01*
X273500Y2299500D01*
X273300Y2298433D01*
X272700Y2297767D01*
X272000Y2297367D01*
X269500D01*
G01X272000D02*
X273500Y2293500D01*
G01X279500Y2301500D02*
Y2293500D01*
G01X277200Y2301500D02*
X281800D01*
G01X-103700Y2327767D02*
X-103300Y2328167D01*
X-103000Y2328833D01*
X-102800Y2329767D01*
X-103000Y2330567D01*
X-103400Y2331100D01*
X-104100Y2331500D01*
X-106800D01*
Y2323500D01*
X-103500D01*
X-102800Y2324033D01*
X-102400Y2324833D01*
X-102200Y2325767D01*
X-102400Y2326700D01*
X-103000Y2327500D01*
X-103700Y2327767D01*
X-106800D01*
G01X-96500Y2323233D02*
X-96700Y2323367D01*
Y2323633D01*
X-96500Y2323767D01*
X-96300Y2323633D01*
Y2323367D01*
X-96500Y2323233D01*
G01X-91000Y2323500D02*
X-88500Y2331500D01*
X-86000Y2323500D01*
G01X-86900Y2326300D02*
X-90100D01*
G01X-82500Y2331500D02*
Y2323500D01*
X-78500D01*
G01X-74500Y2331500D02*
Y2323500D01*
X-70500D01*
G01X-59000Y2331500D02*
X-56500Y2323500D01*
X-54000Y2331500D01*
G01X-49700D02*
X-47300D01*
G01X-48500D02*
Y2323500D01*
G01X-49700D02*
X-47300D01*
G01X-43000D02*
X-40500Y2331500D01*
X-38000Y2323500D01*
G01X-38900Y2326300D02*
X-42100D01*
G01X-34600Y2324566D02*
X-33800Y2323900D01*
X-32900Y2323500D01*
X-32100D01*
X-31300Y2323900D01*
X-30700Y2324566D01*
X-30400Y2325500D01*
X-30600Y2326433D01*
X-31100Y2327233D01*
X-32000Y2327767D01*
X-33200Y2328033D01*
X-33900Y2328567D01*
X-34200Y2329500D01*
X-34000Y2330433D01*
X-33500Y2331100D01*
X-32800Y2331500D01*
X-32100D01*
X-31400Y2331233D01*
X-30800Y2330567D01*
G01X-18500Y2323500D02*
Y2331500D01*
X-16100D01*
X-15300Y2331100D01*
X-14700Y2330167D01*
X-14500Y2329100D01*
X-14700Y2328033D01*
X-15200Y2327233D01*
X-16100Y2326833D01*
X-18500D01*
G01X-10500Y2331500D02*
Y2323500D01*
X-6500D01*
G01X-2700Y2331500D02*
Y2325767D01*
X-2300Y2324566D01*
X-1500Y2323767D01*
X-500Y2323500D01*
X500Y2323767D01*
X1300Y2324566D01*
X1700Y2325767D01*
Y2331500D01*
G01X8100Y2327500D02*
X10100D01*
Y2325100D01*
X9500Y2324300D01*
X8800Y2323767D01*
X7800Y2323500D01*
X6800Y2323767D01*
X6100Y2324300D01*
X5500Y2325100D01*
X5100Y2326033D01*
X4900Y2327100D01*
Y2328033D01*
X5100Y2328833D01*
X5500Y2329767D01*
X6100Y2330567D01*
X6700Y2331100D01*
X7500Y2331500D01*
X8200D01*
X9000Y2331233D01*
X9600Y2330700D01*
G01X16100Y2327500D02*
X18100D01*
Y2325100D01*
X17500Y2324300D01*
X16800Y2323767D01*
X15800Y2323500D01*
X14800Y2323767D01*
X14100Y2324300D01*
X13500Y2325100D01*
X13100Y2326033D01*
X12900Y2327100D01*
Y2328033D01*
X13100Y2328833D01*
X13500Y2329767D01*
X14100Y2330567D01*
X14700Y2331100D01*
X15500Y2331500D01*
X16200D01*
X17000Y2331233D01*
X17600Y2330700D01*
G01X25500Y2323500D02*
X21500D01*
Y2331500D01*
X25500D01*
G01X23900Y2327633D02*
X21500D01*
G01X29300Y2323500D02*
Y2331500D01*
X31300D01*
X32100Y2331100D01*
X32700Y2330567D01*
X33200Y2329767D01*
X33600Y2328833D01*
X33700Y2327500D01*
X33600Y2326167D01*
X33200Y2325233D01*
X32700Y2324433D01*
X32100Y2323900D01*
X31300Y2323500D01*
X29300D01*
G01X49500D02*
X45500D01*
Y2331500D01*
X49500D01*
G01X47900Y2327633D02*
X45500D01*
G01X53400Y2323500D02*
X57600Y2331500D01*
G01X53400D02*
X57600Y2323500D01*
G01X65700Y2330833D02*
X65100Y2331233D01*
X64400Y2331500D01*
X63600D01*
X62700Y2331100D01*
X62000Y2330433D01*
X61500Y2329633D01*
X61100Y2328300D01*
X61000Y2327100D01*
X61200Y2325900D01*
X61500Y2325100D01*
X62100Y2324300D01*
X62800Y2323767D01*
X63500Y2323500D01*
X64200D01*
X64900Y2323767D01*
X65500Y2324167D01*
X66000Y2324700D01*
G01X73500Y2323500D02*
X69500D01*
Y2331500D01*
X73500D01*
G01X71900Y2327633D02*
X69500D01*
G01X77500Y2323500D02*
Y2331500D01*
X79900D01*
X80700Y2331100D01*
X81300Y2330167D01*
X81500Y2329100D01*
X81300Y2328033D01*
X80800Y2327233D01*
X79900Y2326833D01*
X77500D01*
G01X87500Y2331500D02*
Y2323500D01*
G01X85200Y2331500D02*
X89800D01*
G01X101600Y2323500D02*
Y2331500D01*
X105400D01*
G01X104000Y2327633D02*
X101600D01*
G01X111500Y2323500D02*
X110700Y2323633D01*
X110000Y2324167D01*
X109400Y2324967D01*
X109000Y2325900D01*
X108800Y2326967D01*
Y2328033D01*
X109000Y2329100D01*
X109400Y2330033D01*
X110000Y2330833D01*
X110700Y2331367D01*
X111500Y2331500D01*
X112300Y2331367D01*
X113000Y2330833D01*
X113600Y2330033D01*
X114000Y2329100D01*
X114200Y2328033D01*
Y2326967D01*
X114000Y2325900D01*
X113600Y2324967D01*
X113000Y2324167D01*
X112300Y2323633D01*
X111500Y2323500D01*
G01X117500D02*
Y2331500D01*
X120000D01*
X120800Y2331100D01*
X121300Y2330567D01*
X121500Y2329500D01*
X121300Y2328433D01*
X120700Y2327767D01*
X120000Y2327367D01*
X117500D01*
G01X120000D02*
X121500Y2323500D01*
G01X-102300Y2315833D02*
X-102900Y2316233D01*
X-103600Y2316500D01*
X-104400D01*
X-105300Y2316100D01*
X-106000Y2315433D01*
X-106500Y2314633D01*
X-106900Y2313300D01*
X-107000Y2312100D01*
X-106800Y2310900D01*
X-106500Y2310100D01*
X-105900Y2309300D01*
X-105200Y2308767D01*
X-104500Y2308500D01*
X-103800D01*
X-103100Y2308767D01*
X-102500Y2309167D01*
X-102000Y2309700D01*
G01X-96500Y2308233D02*
X-96700Y2308367D01*
Y2308633D01*
X-96500Y2308767D01*
X-96300Y2308633D01*
Y2308367D01*
X-96500Y2308233D01*
G01X-90800Y2308500D02*
Y2316500D01*
X-86200Y2308500D01*
Y2316500D01*
G01X-80500Y2308500D02*
X-81300Y2308633D01*
X-82000Y2309167D01*
X-82600Y2309967D01*
X-83000Y2310900D01*
X-83200Y2311967D01*
Y2313033D01*
X-83000Y2314100D01*
X-82600Y2315033D01*
X-82000Y2315833D01*
X-81300Y2316367D01*
X-80500Y2316500D01*
X-79700Y2316367D01*
X-79000Y2315833D01*
X-78400Y2315033D01*
X-78000Y2314100D01*
X-77800Y2313033D01*
Y2311967D01*
X-78000Y2310900D01*
X-78400Y2309967D01*
X-79000Y2309167D01*
X-79700Y2308633D01*
X-80500Y2308500D01*
G01X-66800D02*
Y2316500D01*
X-62200Y2308500D01*
Y2316500D01*
G01X-54500Y2308500D02*
X-58500D01*
Y2316500D01*
X-54500D01*
G01X-56100Y2312633D02*
X-58500D01*
G01X-46500Y2308500D02*
X-50500D01*
Y2316500D01*
X-46500D01*
G01X-48100Y2312633D02*
X-50500D01*
G01X-42700Y2308500D02*
Y2316500D01*
X-40700D01*
X-39900Y2316100D01*
X-39300Y2315567D01*
X-38800Y2314767D01*
X-38400Y2313833D01*
X-38300Y2312500D01*
X-38400Y2311167D01*
X-38800Y2310233D01*
X-39300Y2309433D01*
X-39900Y2308900D01*
X-40700Y2308500D01*
X-42700D01*
G01X-24500Y2316500D02*
Y2308500D01*
G01X-26800Y2316500D02*
X-22200D01*
G01X-16500Y2308500D02*
X-17300Y2308633D01*
X-18000Y2309167D01*
X-18600Y2309967D01*
X-19000Y2310900D01*
X-19200Y2311967D01*
Y2313033D01*
X-19000Y2314100D01*
X-18600Y2315033D01*
X-18000Y2315833D01*
X-17300Y2316367D01*
X-16500Y2316500D01*
X-15700Y2316367D01*
X-15000Y2315833D01*
X-14400Y2315033D01*
X-14000Y2314100D01*
X-13800Y2313033D01*
Y2311967D01*
X-14000Y2310900D01*
X-14400Y2309967D01*
X-15000Y2309167D01*
X-15700Y2308633D01*
X-16500Y2308500D01*
G01X-2500D02*
Y2316500D01*
X-100D01*
X700Y2316100D01*
X1300Y2315167D01*
X1500Y2314100D01*
X1300Y2313033D01*
X800Y2312233D01*
X-100Y2311833D01*
X-2500D01*
G01X5500Y2316500D02*
Y2308500D01*
X9500D01*
G01X13300Y2316500D02*
Y2310767D01*
X13700Y2309566D01*
X14500Y2308767D01*
X15500Y2308500D01*
X16500Y2308767D01*
X17300Y2309566D01*
X17700Y2310767D01*
Y2316500D01*
G01X24100Y2312500D02*
X26100D01*
Y2310100D01*
X25500Y2309300D01*
X24800Y2308767D01*
X23800Y2308500D01*
X22800Y2308767D01*
X22100Y2309300D01*
X21500Y2310100D01*
X21100Y2311033D01*
X20900Y2312100D01*
Y2313033D01*
X21100Y2313833D01*
X21500Y2314767D01*
X22100Y2315567D01*
X22700Y2316100D01*
X23500Y2316500D01*
X24200D01*
X25000Y2316233D01*
X25600Y2315700D01*
G01X39500Y2308500D02*
X40200Y2308633D01*
X41000Y2309033D01*
X41500Y2309700D01*
X41700Y2310633D01*
X41500Y2311566D01*
X40900Y2312367D01*
X40000Y2312767D01*
X39000D01*
X38400Y2313033D01*
X37900Y2313700D01*
X37700Y2314633D01*
X38000Y2315567D01*
X38700Y2316233D01*
X39500Y2316500D01*
X40300Y2316233D01*
X41000Y2315567D01*
X41300Y2314633D01*
X41100Y2313700D01*
X40600Y2313033D01*
X40000Y2312767D01*
X39000D01*
X38100Y2312367D01*
X37500Y2311566D01*
X37300Y2310633D01*
X37500Y2309700D01*
X38000Y2309033D01*
X38800Y2308633D01*
X39500Y2308500D01*
G01X53400D02*
Y2316500D01*
G01X57600D02*
Y2308500D01*
G01Y2312500D02*
X53400D01*
G01X63500Y2308500D02*
X62700Y2308633D01*
X62000Y2309167D01*
X61400Y2309967D01*
X61000Y2310900D01*
X60800Y2311967D01*
Y2313033D01*
X61000Y2314100D01*
X61400Y2315033D01*
X62000Y2315833D01*
X62700Y2316367D01*
X63500Y2316500D01*
X64300Y2316367D01*
X65000Y2315833D01*
X65600Y2315033D01*
X66000Y2314100D01*
X66200Y2313033D01*
Y2311967D01*
X66000Y2310900D01*
X65600Y2309967D01*
X65000Y2309167D01*
X64300Y2308633D01*
X63500Y2308500D01*
G01X69500Y2316500D02*
Y2308500D01*
X73500D01*
G01X81500D02*
X77500D01*
Y2316500D01*
X81500D01*
G01X79900Y2312633D02*
X77500D01*
G01X85400Y2309566D02*
X86200Y2308900D01*
X87100Y2308500D01*
X87900D01*
X88700Y2308900D01*
X89300Y2309566D01*
X89600Y2310500D01*
X89400Y2311433D01*
X88900Y2312233D01*
X88000Y2312767D01*
X86800Y2313033D01*
X86100Y2313567D01*
X85800Y2314500D01*
X86000Y2315433D01*
X86500Y2316100D01*
X87200Y2316500D01*
X87900D01*
X88600Y2316233D01*
X89200Y2315567D01*
G01X101400Y2309566D02*
X102200Y2308900D01*
X103100Y2308500D01*
X103900D01*
X104700Y2308900D01*
X105300Y2309566D01*
X105600Y2310500D01*
X105400Y2311433D01*
X104900Y2312233D01*
X104000Y2312767D01*
X102800Y2313033D01*
X102100Y2313567D01*
X101800Y2314500D01*
X102000Y2315433D01*
X102500Y2316100D01*
X103200Y2316500D01*
X103900D01*
X104600Y2316233D01*
X105200Y2315567D01*
G01X109300Y2316500D02*
Y2310767D01*
X109700Y2309566D01*
X110500Y2308767D01*
X111500Y2308500D01*
X112500Y2308767D01*
X113300Y2309566D01*
X113700Y2310767D01*
Y2316500D01*
G01X117500Y2308500D02*
Y2316500D01*
X120000D01*
X120800Y2316100D01*
X121300Y2315567D01*
X121500Y2314500D01*
X121300Y2313433D01*
X120700Y2312767D01*
X120000Y2312367D01*
X117500D01*
G01X120000D02*
X121500Y2308500D01*
G01X125500D02*
Y2316500D01*
X128000D01*
X128800Y2316100D01*
X129300Y2315567D01*
X129500Y2314500D01*
X129300Y2313433D01*
X128700Y2312767D01*
X128000Y2312367D01*
X125500D01*
G01X128000D02*
X129500Y2308500D01*
G01X135500D02*
X134700Y2308633D01*
X134000Y2309167D01*
X133400Y2309967D01*
X133000Y2310900D01*
X132800Y2311967D01*
Y2313033D01*
X133000Y2314100D01*
X133400Y2315033D01*
X134000Y2315833D01*
X134700Y2316367D01*
X135500Y2316500D01*
X136300Y2316367D01*
X137000Y2315833D01*
X137600Y2315033D01*
X138000Y2314100D01*
X138200Y2313033D01*
Y2311967D01*
X138000Y2310900D01*
X137600Y2309967D01*
X137000Y2309167D01*
X136300Y2308633D01*
X135500Y2308500D01*
G01X141300Y2316500D02*
Y2310767D01*
X141700Y2309566D01*
X142500Y2308767D01*
X143500Y2308500D01*
X144500Y2308767D01*
X145300Y2309566D01*
X145700Y2310767D01*
Y2316500D01*
G01X149200Y2308500D02*
Y2316500D01*
X153800Y2308500D01*
Y2316500D01*
G01X157300Y2308500D02*
Y2316500D01*
X159300D01*
X160100Y2316100D01*
X160700Y2315567D01*
X161200Y2314767D01*
X161600Y2313833D01*
X161700Y2312500D01*
X161600Y2311167D01*
X161200Y2310233D01*
X160700Y2309433D01*
X160100Y2308900D01*
X159300Y2308500D01*
X157300D01*
G01X166300Y2316500D02*
X168700D01*
G01X167500D02*
Y2308500D01*
G01X166300D02*
X168700D01*
G01X173200D02*
Y2316500D01*
X177800Y2308500D01*
Y2316500D01*
G01X184100Y2312500D02*
X186100D01*
Y2310100D01*
X185500Y2309300D01*
X184800Y2308767D01*
X183800Y2308500D01*
X182800Y2308767D01*
X182100Y2309300D01*
X181500Y2310100D01*
X181100Y2311033D01*
X180900Y2312100D01*
Y2313033D01*
X181100Y2313833D01*
X181500Y2314767D01*
X182100Y2315567D01*
X182700Y2316100D01*
X183500Y2316500D01*
X184200D01*
X185000Y2316233D01*
X185600Y2315700D01*
G01X197400Y2309566D02*
X198200Y2308900D01*
X199100Y2308500D01*
X199900D01*
X200700Y2308900D01*
X201300Y2309566D01*
X201600Y2310500D01*
X201400Y2311433D01*
X200900Y2312233D01*
X200000Y2312767D01*
X198800Y2313033D01*
X198100Y2313567D01*
X197800Y2314500D01*
X198000Y2315433D01*
X198500Y2316100D01*
X199200Y2316500D01*
X199900D01*
X200600Y2316233D01*
X201200Y2315567D01*
G01X209700Y2315833D02*
X209100Y2316233D01*
X208400Y2316500D01*
X207600D01*
X206700Y2316100D01*
X206000Y2315433D01*
X205500Y2314633D01*
X205100Y2313300D01*
X205000Y2312100D01*
X205200Y2310900D01*
X205500Y2310100D01*
X206100Y2309300D01*
X206800Y2308767D01*
X207500Y2308500D01*
X208200D01*
X208900Y2308767D01*
X209500Y2309167D01*
X210000Y2309700D01*
G01X213500Y2308500D02*
Y2316500D01*
X216000D01*
X216800Y2316100D01*
X217300Y2315567D01*
X217500Y2314500D01*
X217300Y2313433D01*
X216700Y2312767D01*
X216000Y2312367D01*
X213500D01*
G01X216000D02*
X217500Y2308500D01*
G01X225500D02*
X221500D01*
Y2316500D01*
X225500D01*
G01X223900Y2312633D02*
X221500D01*
G01X228500Y2316500D02*
X229900Y2308500D01*
X231500Y2316500D01*
X233100Y2308500D01*
X234500Y2316500D01*
G01X239500Y2308233D02*
X239300Y2308367D01*
Y2308633D01*
X239500Y2308767D01*
X239700Y2308633D01*
Y2308367D01*
X239500Y2308233D01*
G01X247000Y2305833D02*
X246000Y2307167D01*
X245500Y2308500D01*
Y2313833D01*
X246000Y2315167D01*
X247000Y2316500D01*
G01X253500Y2308500D02*
Y2316500D01*
X255900D01*
X256700Y2316100D01*
X257300Y2315167D01*
X257500Y2314100D01*
X257300Y2313033D01*
X256800Y2312233D01*
X255900Y2311833D01*
X253500D01*
G01X261500Y2316500D02*
Y2308500D01*
X265500D01*
G01X273500D02*
X269500D01*
Y2316500D01*
X273500D01*
G01X271900Y2312633D02*
X269500D01*
G01X277000Y2308500D02*
X279500Y2316500D01*
X282000Y2308500D01*
G01X281100Y2311300D02*
X277900D01*
G01X285400Y2309566D02*
X286200Y2308900D01*
X287100Y2308500D01*
X287900D01*
X288700Y2308900D01*
X289300Y2309566D01*
X289600Y2310500D01*
X289400Y2311433D01*
X288900Y2312233D01*
X288000Y2312767D01*
X286800Y2313033D01*
X286100Y2313567D01*
X285800Y2314500D01*
X286000Y2315433D01*
X286500Y2316100D01*
X287200Y2316500D01*
X287900D01*
X288600Y2316233D01*
X289200Y2315567D01*
G01X297500Y2308500D02*
X293500D01*
Y2316500D01*
X297500D01*
G01X295900Y2312633D02*
X293500D01*
G01X310300Y2316500D02*
X312700D01*
G01X311500D02*
Y2308500D01*
G01X310300D02*
X312700D01*
G01X320100Y2312500D02*
X322100D01*
Y2310100D01*
X321500Y2309300D01*
X320800Y2308767D01*
X319800Y2308500D01*
X318800Y2308767D01*
X318100Y2309300D01*
X317500Y2310100D01*
X317100Y2311033D01*
X316900Y2312100D01*
Y2313033D01*
X317100Y2313833D01*
X317500Y2314767D01*
X318100Y2315567D01*
X318700Y2316100D01*
X319500Y2316500D01*
X320200D01*
X321000Y2316233D01*
X321600Y2315700D01*
G01X325200Y2308500D02*
Y2316500D01*
X329800Y2308500D01*
Y2316500D01*
G01X335500Y2308500D02*
X334700Y2308633D01*
X334000Y2309167D01*
X333400Y2309967D01*
X333000Y2310900D01*
X332800Y2311967D01*
Y2313033D01*
X333000Y2314100D01*
X333400Y2315033D01*
X334000Y2315833D01*
X334700Y2316367D01*
X335500Y2316500D01*
X336300Y2316367D01*
X337000Y2315833D01*
X337600Y2315033D01*
X338000Y2314100D01*
X338200Y2313033D01*
Y2311967D01*
X338000Y2310900D01*
X337600Y2309967D01*
X337000Y2309167D01*
X336300Y2308633D01*
X335500Y2308500D01*
G01X341500D02*
Y2316500D01*
X344000D01*
X344800Y2316100D01*
X345300Y2315567D01*
X345500Y2314500D01*
X345300Y2313433D01*
X344700Y2312767D01*
X344000Y2312367D01*
X341500D01*
G01X344000D02*
X345500Y2308500D01*
G01X353500D02*
X349500D01*
Y2316500D01*
X353500D01*
G01X351900Y2312633D02*
X349500D01*
G01X367500Y2316500D02*
Y2308500D01*
G01X365200Y2316500D02*
X369800D01*
G01X373400Y2308500D02*
Y2316500D01*
G01X377600D02*
Y2308500D01*
G01Y2312500D02*
X373400D01*
G01X382300Y2316500D02*
X384700D01*
G01X383500D02*
Y2308500D01*
G01X382300D02*
X384700D01*
G01X389400Y2309566D02*
X390200Y2308900D01*
X391100Y2308500D01*
X391900D01*
X392700Y2308900D01*
X393300Y2309566D01*
X393600Y2310500D01*
X393400Y2311433D01*
X392900Y2312233D01*
X392000Y2312767D01*
X390800Y2313033D01*
X390100Y2313567D01*
X389800Y2314500D01*
X390000Y2315433D01*
X390500Y2316100D01*
X391200Y2316500D01*
X391900D01*
X392600Y2316233D01*
X393200Y2315567D01*
G01X406300Y2316500D02*
X408700D01*
G01X407500D02*
Y2308500D01*
G01X406300D02*
X408700D01*
G01X413600D02*
Y2316500D01*
X417400D01*
G01X416000Y2312633D02*
X413600D01*
G01X429200Y2308500D02*
Y2316500D01*
X433800Y2308500D01*
Y2316500D01*
G01X439500Y2308500D02*
X438700Y2308633D01*
X438000Y2309167D01*
X437400Y2309967D01*
X437000Y2310900D01*
X436800Y2311967D01*
Y2313033D01*
X437000Y2314100D01*
X437400Y2315033D01*
X438000Y2315833D01*
X438700Y2316367D01*
X439500Y2316500D01*
X440300Y2316367D01*
X441000Y2315833D01*
X441600Y2315033D01*
X442000Y2314100D01*
X442200Y2313033D01*
Y2311967D01*
X442000Y2310900D01*
X441600Y2309967D01*
X441000Y2309167D01*
X440300Y2308633D01*
X439500Y2308500D01*
G01X455500Y2316500D02*
Y2308500D01*
G01X453200Y2316500D02*
X457800D01*
G01X461400Y2308500D02*
Y2316500D01*
G01X465600D02*
Y2308500D01*
G01Y2312500D02*
X461400D01*
G01X470300Y2316500D02*
X472700D01*
G01X471500D02*
Y2308500D01*
G01X470300D02*
X472700D01*
G01X477400Y2309566D02*
X478200Y2308900D01*
X479100Y2308500D01*
X479900D01*
X480700Y2308900D01*
X481300Y2309566D01*
X481600Y2310500D01*
X481400Y2311433D01*
X480900Y2312233D01*
X480000Y2312767D01*
X478800Y2313033D01*
X478100Y2313567D01*
X477800Y2314500D01*
X478000Y2315433D01*
X478500Y2316100D01*
X479200Y2316500D01*
X479900D01*
X480600Y2316233D01*
X481200Y2315567D01*
G01X494300Y2316500D02*
X496700D01*
G01X495500D02*
Y2308500D01*
G01X494300D02*
X496700D01*
G01X503500Y2316500D02*
Y2308500D01*
G01X501200Y2316500D02*
X505800D01*
G01X513500Y2308500D02*
X509500D01*
Y2316500D01*
X513500D01*
G01X511900Y2312633D02*
X509500D01*
G01X516900Y2308500D02*
Y2316500D01*
X519500Y2309833D01*
X522100Y2316500D01*
Y2308500D01*
G01X534300Y2316500D02*
X536700D01*
G01X535500D02*
Y2308500D01*
G01X534300D02*
X536700D01*
G01X541200D02*
Y2316500D01*
X545800Y2308500D01*
Y2316500D01*
G01X560300Y2312767D02*
X560700Y2313167D01*
X561000Y2313833D01*
X561200Y2314767D01*
X561000Y2315567D01*
X560600Y2316100D01*
X559900Y2316500D01*
X557200D01*
Y2308500D01*
X560500D01*
X561200Y2309033D01*
X561600Y2309833D01*
X561800Y2310767D01*
X561600Y2311700D01*
X561000Y2312500D01*
X560300Y2312767D01*
X557200D01*
G01X567500Y2308500D02*
X566700Y2308633D01*
X566000Y2309167D01*
X565400Y2309967D01*
X565000Y2310900D01*
X564800Y2311967D01*
Y2313033D01*
X565000Y2314100D01*
X565400Y2315033D01*
X566000Y2315833D01*
X566700Y2316367D01*
X567500Y2316500D01*
X568300Y2316367D01*
X569000Y2315833D01*
X569600Y2315033D01*
X570000Y2314100D01*
X570200Y2313033D01*
Y2311967D01*
X570000Y2310900D01*
X569600Y2309967D01*
X569000Y2309167D01*
X568300Y2308633D01*
X567500Y2308500D01*
G01X573000D02*
X575500Y2316500D01*
X578000Y2308500D01*
G01X577100Y2311300D02*
X573900D01*
G01X581500Y2308500D02*
Y2316500D01*
X584000D01*
X584800Y2316100D01*
X585300Y2315567D01*
X585500Y2314500D01*
X585300Y2313433D01*
X584700Y2312767D01*
X584000Y2312367D01*
X581500D01*
G01X584000D02*
X585500Y2308500D01*
G01X589300D02*
Y2316500D01*
X591300D01*
X592100Y2316100D01*
X592700Y2315567D01*
X593200Y2314767D01*
X593600Y2313833D01*
X593700Y2312500D01*
X593600Y2311167D01*
X593200Y2310233D01*
X592700Y2309433D01*
X592100Y2308900D01*
X591300Y2308500D01*
X589300D01*
G01X605600D02*
Y2316500D01*
X609400D01*
G01X608000Y2312633D02*
X605600D01*
G01X614300Y2316500D02*
X616700D01*
G01X615500D02*
Y2308500D01*
G01X614300D02*
X616700D01*
G01X621500Y2316500D02*
Y2308500D01*
X625500D01*
G01X633500D02*
X629500D01*
Y2316500D01*
X633500D01*
G01X631900Y2312633D02*
X629500D01*
G01X640000Y2305833D02*
X641000Y2307167D01*
X641500Y2308500D01*
Y2313833D01*
X641000Y2315167D01*
X640000Y2316500D01*
G01X-107000Y2338500D02*
X-104500Y2346500D01*
X-102000Y2338500D01*
G01X-102900Y2341300D02*
X-106100D01*
G01X-96500Y2338233D02*
X-96700Y2338367D01*
Y2338633D01*
X-96500Y2338767D01*
X-96300Y2338633D01*
Y2338367D01*
X-96500Y2338233D01*
G01X-91000Y2346500D02*
X-88500Y2338500D01*
X-86000Y2346500D01*
G01X-81700D02*
X-79300D01*
G01X-80500D02*
Y2338500D01*
G01X-81700D02*
X-79300D01*
G01X-75000D02*
X-72500Y2346500D01*
X-70000Y2338500D01*
G01X-70900Y2341300D02*
X-74100D01*
G01X-56500Y2346500D02*
Y2338500D01*
G01X-58800Y2346500D02*
X-54200D01*
G01X-46500Y2338500D02*
X-50500D01*
Y2346500D01*
X-46500D01*
G01X-48100Y2342633D02*
X-50500D01*
G01X-43000Y2338500D02*
X-40500Y2346500D01*
X-38000Y2338500D01*
G01X-38900Y2341300D02*
X-42100D01*
G01X-34500Y2338500D02*
Y2346500D01*
X-32000D01*
X-31200Y2346100D01*
X-30700Y2345567D01*
X-30500Y2344500D01*
X-30700Y2343433D01*
X-31300Y2342767D01*
X-32000Y2342367D01*
X-34500D01*
G01X-32000D02*
X-30500Y2338500D01*
G01X-18700D02*
Y2346500D01*
X-16700D01*
X-15900Y2346100D01*
X-15300Y2345567D01*
X-14800Y2344767D01*
X-14400Y2343833D01*
X-14300Y2342500D01*
X-14400Y2341167D01*
X-14800Y2340233D01*
X-15300Y2339433D01*
X-15900Y2338900D01*
X-16700Y2338500D01*
X-18700D01*
G01X-10500D02*
Y2346500D01*
X-8000D01*
X-7200Y2346100D01*
X-6700Y2345567D01*
X-6500Y2344500D01*
X-6700Y2343433D01*
X-7300Y2342767D01*
X-8000Y2342367D01*
X-10500D01*
G01X-8000D02*
X-6500Y2338500D01*
G01X-500D02*
X-1300Y2338633D01*
X-2000Y2339167D01*
X-2600Y2339967D01*
X-3000Y2340900D01*
X-3200Y2341967D01*
Y2343033D01*
X-3000Y2344100D01*
X-2600Y2345033D01*
X-2000Y2345833D01*
X-1300Y2346367D01*
X-500Y2346500D01*
X300Y2346367D01*
X1000Y2345833D01*
X1600Y2345033D01*
X2000Y2344100D01*
X2200Y2343033D01*
Y2341967D01*
X2000Y2340900D01*
X1600Y2339967D01*
X1000Y2339167D01*
X300Y2338633D01*
X-500Y2338500D01*
G01X5500D02*
Y2346500D01*
X7900D01*
X8700Y2346100D01*
X9300Y2345167D01*
X9500Y2344100D01*
X9300Y2343033D01*
X8800Y2342233D01*
X7900Y2341833D01*
X5500D01*
G01X23000Y2335833D02*
X22000Y2337167D01*
X21500Y2338500D01*
Y2343833D01*
X22000Y2345167D01*
X23000Y2346500D01*
G01X29600Y2338500D02*
Y2346500D01*
X33400D01*
G01X32000Y2342633D02*
X29600D01*
G01X39500Y2338500D02*
X38700Y2338633D01*
X38000Y2339167D01*
X37400Y2339967D01*
X37000Y2340900D01*
X36800Y2341967D01*
Y2343033D01*
X37000Y2344100D01*
X37400Y2345033D01*
X38000Y2345833D01*
X38700Y2346367D01*
X39500Y2346500D01*
X40300Y2346367D01*
X41000Y2345833D01*
X41600Y2345033D01*
X42000Y2344100D01*
X42200Y2343033D01*
Y2341967D01*
X42000Y2340900D01*
X41600Y2339967D01*
X41000Y2339167D01*
X40300Y2338633D01*
X39500Y2338500D01*
G01X45500D02*
Y2346500D01*
X48000D01*
X48800Y2346100D01*
X49300Y2345567D01*
X49500Y2344500D01*
X49300Y2343433D01*
X48700Y2342767D01*
X48000Y2342367D01*
X45500D01*
G01X48000D02*
X49500Y2338500D01*
G01X61000D02*
X63500Y2346500D01*
X66000Y2338500D01*
G01X65100Y2341300D02*
X61900D01*
G01X69500Y2346500D02*
Y2338500D01*
X73500D01*
G01X77500Y2346500D02*
Y2338500D01*
X81500D01*
G01X93000Y2346500D02*
X95500Y2338500D01*
X98000Y2346500D01*
G01X102300D02*
X104700D01*
G01X103500D02*
Y2338500D01*
G01X102300D02*
X104700D01*
G01X109000D02*
X111500Y2346500D01*
X114000Y2338500D01*
G01X113100Y2341300D02*
X109900D01*
G01X117400Y2339566D02*
X118200Y2338900D01*
X119100Y2338500D01*
X119900D01*
X120700Y2338900D01*
X121300Y2339566D01*
X121600Y2340500D01*
X121400Y2341433D01*
X120900Y2342233D01*
X120000Y2342767D01*
X118800Y2343033D01*
X118100Y2343567D01*
X117800Y2344500D01*
X118000Y2345433D01*
X118500Y2346100D01*
X119200Y2346500D01*
X119900D01*
X120600Y2346233D01*
X121200Y2345567D01*
G01X133000Y2338500D02*
X135500Y2346500D01*
X138000Y2338500D01*
G01X137100Y2341300D02*
X133900D01*
G01X141200Y2338500D02*
Y2346500D01*
X145800Y2338500D01*
Y2346500D01*
G01X149300Y2338500D02*
Y2346500D01*
X151300D01*
X152100Y2346100D01*
X152700Y2345567D01*
X153200Y2344767D01*
X153600Y2343833D01*
X153700Y2342500D01*
X153600Y2341167D01*
X153200Y2340233D01*
X152700Y2339433D01*
X152100Y2338900D01*
X151300Y2338500D01*
X149300D01*
G01X165500D02*
Y2346500D01*
X167900D01*
X168700Y2346100D01*
X169300Y2345167D01*
X169500Y2344100D01*
X169300Y2343033D01*
X168800Y2342233D01*
X167900Y2341833D01*
X165500D01*
G01X174300Y2346500D02*
X176700D01*
G01X175500D02*
Y2338500D01*
G01X174300D02*
X176700D01*
G01X181200D02*
Y2346500D01*
X185800Y2338500D01*
Y2346500D01*
G01X189400Y2339566D02*
X190200Y2338900D01*
X191100Y2338500D01*
X191900D01*
X192700Y2338900D01*
X193300Y2339566D01*
X193600Y2340500D01*
X193400Y2341433D01*
X192900Y2342233D01*
X192000Y2342767D01*
X190800Y2343033D01*
X190100Y2343567D01*
X189800Y2344500D01*
X190000Y2345433D01*
X190500Y2346100D01*
X191200Y2346500D01*
X191900D01*
X192600Y2346233D01*
X193200Y2345567D01*
G01X200000Y2335833D02*
X201000Y2337167D01*
X201500Y2338500D01*
Y2343833D01*
X201000Y2345167D01*
X200000Y2346500D01*
G01X207500Y2338233D02*
X207300Y2338367D01*
Y2338633D01*
X207500Y2338767D01*
X207700Y2338633D01*
Y2338367D01*
X207500Y2338233D01*
G01X-124400Y2375167D02*
X-123800Y2375967D01*
X-123100Y2376367D01*
X-122300Y2376500D01*
X-121300Y2376233D01*
X-120600Y2375567D01*
X-120400Y2374767D01*
X-120500Y2373966D01*
X-120900Y2373300D01*
X-122900Y2371967D01*
X-123800Y2371033D01*
X-124400Y2369700D01*
X-124600Y2368500D01*
X-120400D01*
G01X-114500Y2368233D02*
X-114700Y2368367D01*
Y2368633D01*
X-114500Y2368767D01*
X-114300Y2368633D01*
Y2368367D01*
X-114500Y2368233D01*
G01X-108400Y2368500D02*
Y2376500D01*
X-104600D01*
G01X-106000Y2372633D02*
X-108400D01*
G01X-101000Y2368500D02*
X-98500Y2376500D01*
X-96000Y2368500D01*
G01X-96900Y2371300D02*
X-100100D01*
G01X-89700Y2372767D02*
X-89300Y2373167D01*
X-89000Y2373833D01*
X-88800Y2374767D01*
X-89000Y2375567D01*
X-89400Y2376100D01*
X-90100Y2376500D01*
X-92800D01*
Y2368500D01*
X-89500D01*
X-88800Y2369033D01*
X-88400Y2369833D01*
X-88200Y2370767D01*
X-88400Y2371700D01*
X-89000Y2372500D01*
X-89700Y2372767D01*
X-92800D01*
G01X-84500Y2368500D02*
Y2376500D01*
X-82000D01*
X-81200Y2376100D01*
X-80700Y2375567D01*
X-80500Y2374500D01*
X-80700Y2373433D01*
X-81300Y2372767D01*
X-82000Y2372367D01*
X-84500D01*
G01X-82000D02*
X-80500Y2368500D01*
G01X-75700Y2376500D02*
X-73300D01*
G01X-74500D02*
Y2368500D01*
G01X-75700D02*
X-73300D01*
G01X-64300Y2375833D02*
X-64900Y2376233D01*
X-65600Y2376500D01*
X-66400D01*
X-67300Y2376100D01*
X-68000Y2375433D01*
X-68500Y2374633D01*
X-68900Y2373300D01*
X-69000Y2372100D01*
X-68800Y2370900D01*
X-68500Y2370100D01*
X-67900Y2369300D01*
X-67200Y2368767D01*
X-66500Y2368500D01*
X-65800D01*
X-65100Y2368767D01*
X-64500Y2369167D01*
X-64000Y2369700D01*
G01X-61000Y2368500D02*
X-58500Y2376500D01*
X-56000Y2368500D01*
G01X-56900Y2371300D02*
X-60100D01*
G01X-50500Y2376500D02*
Y2368500D01*
G01X-52800Y2376500D02*
X-48200D01*
G01X-40500Y2368500D02*
X-44500D01*
Y2376500D01*
X-40500D01*
G01X-42100Y2372633D02*
X-44500D01*
G01X-28500Y2368500D02*
Y2376500D01*
X-26100D01*
X-25300Y2376100D01*
X-24700Y2375167D01*
X-24500Y2374100D01*
X-24700Y2373033D01*
X-25200Y2372233D01*
X-26100Y2371833D01*
X-28500D01*
G01X-16500Y2368500D02*
X-20500D01*
Y2376500D01*
X-16500D01*
G01X-18100Y2372633D02*
X-20500D01*
G01X-12500Y2368500D02*
Y2376500D01*
X-10000D01*
X-9200Y2376100D01*
X-8700Y2375567D01*
X-8500Y2374500D01*
X-8700Y2373433D01*
X-9300Y2372767D01*
X-10000Y2372367D01*
X-12500D01*
G01X-10000D02*
X-8500Y2368500D01*
G01X5500D02*
X4700Y2368633D01*
X4000Y2369167D01*
X3400Y2369967D01*
X3000Y2370900D01*
X2800Y2371967D01*
Y2373033D01*
X3000Y2374100D01*
X3400Y2375033D01*
X4000Y2375833D01*
X4700Y2376367D01*
X5500Y2376500D01*
X6300Y2376367D01*
X7000Y2375833D01*
X7600Y2375033D01*
X8000Y2374100D01*
X8200Y2373033D01*
Y2371967D01*
X8000Y2370900D01*
X7600Y2369967D01*
X7000Y2369167D01*
X6300Y2368633D01*
X5500Y2368500D01*
G01X6300Y2370633D02*
X7500Y2368500D01*
G01X11300Y2376500D02*
Y2370767D01*
X11700Y2369566D01*
X12500Y2368767D01*
X13500Y2368500D01*
X14500Y2368767D01*
X15300Y2369566D01*
X15700Y2370767D01*
Y2376500D01*
G01X19000Y2368500D02*
X21500Y2376500D01*
X24000Y2368500D01*
G01X23100Y2371300D02*
X19900D01*
G01X27200Y2368500D02*
Y2376500D01*
X31800Y2368500D01*
Y2376500D01*
G01X37500D02*
Y2368500D01*
G01X35200Y2376500D02*
X39800D01*
G01X43000Y2368500D02*
X45500Y2376500D01*
X48000Y2368500D01*
G01X47100Y2371300D02*
X43900D01*
G01X59500Y2368500D02*
Y2376500D01*
X61900D01*
X62700Y2376100D01*
X63300Y2375167D01*
X63500Y2374100D01*
X63300Y2373033D01*
X62800Y2372233D01*
X61900Y2371833D01*
X59500D01*
G01X71700Y2375833D02*
X71100Y2376233D01*
X70400Y2376500D01*
X69600D01*
X68700Y2376100D01*
X68000Y2375433D01*
X67500Y2374633D01*
X67100Y2373300D01*
X67000Y2372100D01*
X67200Y2370900D01*
X67500Y2370100D01*
X68100Y2369300D01*
X68800Y2368767D01*
X69500Y2368500D01*
X70200D01*
X70900Y2368767D01*
X71500Y2369167D01*
X72000Y2369700D01*
G01X78300Y2372767D02*
X78700Y2373167D01*
X79000Y2373833D01*
X79200Y2374767D01*
X79000Y2375567D01*
X78600Y2376100D01*
X77900Y2376500D01*
X75200D01*
Y2368500D01*
X78500D01*
X79200Y2369033D01*
X79600Y2369833D01*
X79800Y2370767D01*
X79600Y2371700D01*
X79000Y2372500D01*
X78300Y2372767D01*
X75200D01*
G01X91400Y2369566D02*
X92200Y2368900D01*
X93100Y2368500D01*
X93900D01*
X94700Y2368900D01*
X95300Y2369566D01*
X95600Y2370500D01*
X95400Y2371433D01*
X94900Y2372233D01*
X94000Y2372767D01*
X92800Y2373033D01*
X92100Y2373567D01*
X91800Y2374500D01*
X92000Y2375433D01*
X92500Y2376100D01*
X93200Y2376500D01*
X93900D01*
X94600Y2376233D01*
X95200Y2375567D01*
G01X99500Y2368500D02*
Y2376500D01*
X101900D01*
X102700Y2376100D01*
X103300Y2375167D01*
X103500Y2374100D01*
X103300Y2373033D01*
X102800Y2372233D01*
X101900Y2371833D01*
X99500D01*
G01X111500Y2368500D02*
X107500D01*
Y2376500D01*
X111500D01*
G01X109900Y2372633D02*
X107500D01*
G01X119700Y2375833D02*
X119100Y2376233D01*
X118400Y2376500D01*
X117600D01*
X116700Y2376100D01*
X116000Y2375433D01*
X115500Y2374633D01*
X115100Y2373300D01*
X115000Y2372100D01*
X115200Y2370900D01*
X115500Y2370100D01*
X116100Y2369300D01*
X116800Y2368767D01*
X117500Y2368500D01*
X118200D01*
X118900Y2368767D01*
X119500Y2369167D01*
X120000Y2369700D01*
G01X124300Y2376500D02*
X126700D01*
G01X125500D02*
Y2368500D01*
G01X124300D02*
X126700D01*
G01X131600D02*
Y2376500D01*
X135400D01*
G01X134000Y2372633D02*
X131600D01*
G01X140300Y2376500D02*
X142700D01*
G01X141500D02*
Y2368500D01*
G01X140300D02*
X142700D01*
G01X151700Y2375833D02*
X151100Y2376233D01*
X150400Y2376500D01*
X149600D01*
X148700Y2376100D01*
X148000Y2375433D01*
X147500Y2374633D01*
X147100Y2373300D01*
X147000Y2372100D01*
X147200Y2370900D01*
X147500Y2370100D01*
X148100Y2369300D01*
X148800Y2368767D01*
X149500Y2368500D01*
X150200D01*
X150900Y2368767D01*
X151500Y2369167D01*
X152000Y2369700D01*
G01X155000Y2368500D02*
X157500Y2376500D01*
X160000Y2368500D01*
G01X159100Y2371300D02*
X155900D01*
G01X165500Y2376500D02*
Y2368500D01*
G01X163200Y2376500D02*
X167800D01*
G01X172300D02*
X174700D01*
G01X173500D02*
Y2368500D01*
G01X172300D02*
X174700D01*
G01X181500D02*
X180700Y2368633D01*
X180000Y2369167D01*
X179400Y2369967D01*
X179000Y2370900D01*
X178800Y2371967D01*
Y2373033D01*
X179000Y2374100D01*
X179400Y2375033D01*
X180000Y2375833D01*
X180700Y2376367D01*
X181500Y2376500D01*
X182300Y2376367D01*
X183000Y2375833D01*
X183600Y2375033D01*
X184000Y2374100D01*
X184200Y2373033D01*
Y2371967D01*
X184000Y2370900D01*
X183600Y2369967D01*
X183000Y2369167D01*
X182300Y2368633D01*
X181500Y2368500D01*
G01X187200D02*
Y2376500D01*
X191800Y2368500D01*
Y2376500D01*
G01X208500Y2365833D02*
X203500Y2373833D01*
Y2375167D01*
X204500Y2376500D01*
X205500D01*
X206500Y2375167D01*
Y2373833D01*
X205500Y2372500D01*
X203500Y2371167D01*
X202500Y2369833D01*
Y2367167D01*
X203500Y2365833D01*
X206500D01*
X208500Y2368500D01*
G01X221500D02*
X220700Y2368633D01*
X220000Y2369167D01*
X219400Y2369967D01*
X219000Y2370900D01*
X218800Y2371967D01*
Y2373033D01*
X219000Y2374100D01*
X219400Y2375033D01*
X220000Y2375833D01*
X220700Y2376367D01*
X221500Y2376500D01*
X222300Y2376367D01*
X223000Y2375833D01*
X223600Y2375033D01*
X224000Y2374100D01*
X224200Y2373033D01*
Y2371967D01*
X224000Y2370900D01*
X223600Y2369967D01*
X223000Y2369167D01*
X222300Y2368633D01*
X221500Y2368500D01*
G01X222300Y2370633D02*
X223500Y2368500D01*
G01X231700Y2375833D02*
X231100Y2376233D01*
X230400Y2376500D01*
X229600D01*
X228700Y2376100D01*
X228000Y2375433D01*
X227500Y2374633D01*
X227100Y2373300D01*
X227000Y2372100D01*
X227200Y2370900D01*
X227500Y2370100D01*
X228100Y2369300D01*
X228800Y2368767D01*
X229500Y2368500D01*
X230200D01*
X230900Y2368767D01*
X231500Y2369167D01*
X232000Y2369700D01*
G01X237500Y2376500D02*
Y2368500D01*
G01X235200Y2376500D02*
X239800D01*
G01X255500Y2368500D02*
X251500D01*
Y2376500D01*
X255500D01*
G01X253900Y2372633D02*
X251500D01*
G01X261500Y2368500D02*
X260700Y2368633D01*
X260000Y2369167D01*
X259400Y2369967D01*
X259000Y2370900D01*
X258800Y2371967D01*
Y2373033D01*
X259000Y2374100D01*
X259400Y2375033D01*
X260000Y2375833D01*
X260700Y2376367D01*
X261500Y2376500D01*
X262300Y2376367D01*
X263000Y2375833D01*
X263600Y2375033D01*
X264000Y2374100D01*
X264200Y2373033D01*
Y2371967D01*
X264000Y2370900D01*
X263600Y2369967D01*
X263000Y2369167D01*
X262300Y2368633D01*
X261500Y2368500D01*
G01X262300Y2370633D02*
X263500Y2368500D01*
G01X275600D02*
Y2376500D01*
X279400D01*
G01X278000Y2372633D02*
X275600D01*
G01X283000Y2368500D02*
X285500Y2376500D01*
X288000Y2368500D01*
G01X287100Y2371300D02*
X283900D01*
G01X293500Y2368500D02*
X292700Y2368633D01*
X292000Y2369167D01*
X291400Y2369967D01*
X291000Y2370900D01*
X290800Y2371967D01*
Y2373033D01*
X291000Y2374100D01*
X291400Y2375033D01*
X292000Y2375833D01*
X292700Y2376367D01*
X293500Y2376500D01*
X294300Y2376367D01*
X295000Y2375833D01*
X295600Y2375033D01*
X296000Y2374100D01*
X296200Y2373033D01*
Y2371967D01*
X296000Y2370900D01*
X295600Y2369967D01*
X295000Y2369167D01*
X294300Y2368633D01*
X293500Y2368500D01*
G01X294300Y2370633D02*
X295500Y2368500D01*
G01X301500Y2368233D02*
X301300Y2368367D01*
Y2368633D01*
X301500Y2368767D01*
X301700Y2368633D01*
Y2368367D01*
X301500Y2368233D01*
G01X-124700Y2355100D02*
X-124100Y2354167D01*
X-123300Y2353633D01*
X-122400Y2353500D01*
X-121600Y2353633D01*
X-120800Y2354300D01*
X-120300Y2355100D01*
X-120200Y2355900D01*
X-120400Y2356833D01*
X-121100Y2357500D01*
X-121800Y2357767D01*
X-122700D01*
G01X-121800D02*
X-121200Y2358167D01*
X-120700Y2358833D01*
X-120500Y2359633D01*
X-120700Y2360433D01*
X-121200Y2361100D01*
X-122100Y2361500D01*
X-123000Y2361367D01*
X-123900Y2360833D01*
G01X-114500Y2353233D02*
X-114700Y2353367D01*
Y2353633D01*
X-114500Y2353767D01*
X-114300Y2353633D01*
Y2353367D01*
X-114500Y2353233D01*
G01X-108500Y2353500D02*
Y2361500D01*
X-106100D01*
X-105300Y2361100D01*
X-104700Y2360167D01*
X-104500Y2359100D01*
X-104700Y2358033D01*
X-105200Y2357233D01*
X-106100Y2356833D01*
X-108500D01*
G01X-96300Y2360833D02*
X-96900Y2361233D01*
X-97600Y2361500D01*
X-98400D01*
X-99300Y2361100D01*
X-100000Y2360433D01*
X-100500Y2359633D01*
X-100900Y2358300D01*
X-101000Y2357100D01*
X-100800Y2355900D01*
X-100500Y2355100D01*
X-99900Y2354300D01*
X-99200Y2353767D01*
X-98500Y2353500D01*
X-97800D01*
X-97100Y2353767D01*
X-96500Y2354167D01*
X-96000Y2354700D01*
G01X-89700Y2357767D02*
X-89300Y2358167D01*
X-89000Y2358833D01*
X-88800Y2359767D01*
X-89000Y2360567D01*
X-89400Y2361100D01*
X-90100Y2361500D01*
X-92800D01*
Y2353500D01*
X-89500D01*
X-88800Y2354033D01*
X-88400Y2354833D01*
X-88200Y2355767D01*
X-88400Y2356700D01*
X-89000Y2357500D01*
X-89700Y2357767D01*
X-92800D01*
G01X-76500Y2353500D02*
Y2361500D01*
X-74100D01*
X-73300Y2361100D01*
X-72700Y2360167D01*
X-72500Y2359100D01*
X-72700Y2358033D01*
X-73200Y2357233D01*
X-74100Y2356833D01*
X-76500D01*
G01X-68500Y2353500D02*
Y2361500D01*
X-66000D01*
X-65200Y2361100D01*
X-64700Y2360567D01*
X-64500Y2359500D01*
X-64700Y2358433D01*
X-65300Y2357767D01*
X-66000Y2357367D01*
X-68500D01*
G01X-66000D02*
X-64500Y2353500D01*
G01X-58500D02*
X-59300Y2353633D01*
X-60000Y2354167D01*
X-60600Y2354967D01*
X-61000Y2355900D01*
X-61200Y2356967D01*
Y2358033D01*
X-61000Y2359100D01*
X-60600Y2360033D01*
X-60000Y2360833D01*
X-59300Y2361367D01*
X-58500Y2361500D01*
X-57700Y2361367D01*
X-57000Y2360833D01*
X-56400Y2360033D01*
X-56000Y2359100D01*
X-55800Y2358033D01*
Y2356967D01*
X-56000Y2355900D01*
X-56400Y2354967D01*
X-57000Y2354167D01*
X-57700Y2353633D01*
X-58500Y2353500D01*
G01X-48300Y2360833D02*
X-48900Y2361233D01*
X-49600Y2361500D01*
X-50400D01*
X-51300Y2361100D01*
X-52000Y2360433D01*
X-52500Y2359633D01*
X-52900Y2358300D01*
X-53000Y2357100D01*
X-52800Y2355900D01*
X-52500Y2355100D01*
X-51900Y2354300D01*
X-51200Y2353767D01*
X-50500Y2353500D01*
X-49800D01*
X-49100Y2353767D01*
X-48500Y2354167D01*
X-48000Y2354700D01*
G01X-40500Y2353500D02*
X-44500D01*
Y2361500D01*
X-40500D01*
G01X-42100Y2357633D02*
X-44500D01*
G01X-36600Y2354566D02*
X-35800Y2353900D01*
X-34900Y2353500D01*
X-34100D01*
X-33300Y2353900D01*
X-32700Y2354566D01*
X-32400Y2355500D01*
X-32600Y2356433D01*
X-33100Y2357233D01*
X-34000Y2357767D01*
X-35200Y2358033D01*
X-35900Y2358567D01*
X-36200Y2359500D01*
X-36000Y2360433D01*
X-35500Y2361100D01*
X-34800Y2361500D01*
X-34100D01*
X-33400Y2361233D01*
X-32800Y2360567D01*
G01X-28600Y2354566D02*
X-27800Y2353900D01*
X-26900Y2353500D01*
X-26100D01*
X-25300Y2353900D01*
X-24700Y2354566D01*
X-24400Y2355500D01*
X-24600Y2356433D01*
X-25100Y2357233D01*
X-26000Y2357767D01*
X-27200Y2358033D01*
X-27900Y2358567D01*
X-28200Y2359500D01*
X-28000Y2360433D01*
X-27500Y2361100D01*
X-26800Y2361500D01*
X-26100D01*
X-25400Y2361233D01*
X-24800Y2360567D01*
G01X-18500Y2353233D02*
X-18700Y2353367D01*
Y2353633D01*
X-18500Y2353767D01*
X-18300Y2353633D01*
Y2353367D01*
X-18500Y2353233D01*
G01Y2356833D02*
X-18700Y2356967D01*
Y2357233D01*
X-18500Y2357367D01*
X-18300Y2357233D01*
Y2356967D01*
X-18500Y2356833D01*
G01X-124800Y2398500D02*
Y2406500D01*
X-120200Y2398500D01*
Y2406500D01*
G01X-114500Y2398500D02*
X-115300Y2398633D01*
X-116000Y2399167D01*
X-116600Y2399967D01*
X-117000Y2400900D01*
X-117200Y2401967D01*
Y2403033D01*
X-117000Y2404100D01*
X-116600Y2405033D01*
X-116000Y2405833D01*
X-115300Y2406367D01*
X-114500Y2406500D01*
X-113700Y2406367D01*
X-113000Y2405833D01*
X-112400Y2405033D01*
X-112000Y2404100D01*
X-111800Y2403033D01*
Y2401967D01*
X-112000Y2400900D01*
X-112400Y2399967D01*
X-113000Y2399167D01*
X-113700Y2398633D01*
X-114500Y2398500D01*
G01X-106500Y2406500D02*
Y2398500D01*
G01X-108800Y2406500D02*
X-104200D01*
G01X-96500Y2398500D02*
X-100500D01*
Y2406500D01*
X-96500D01*
G01X-98100Y2402633D02*
X-100500D01*
G01X-92600Y2399566D02*
X-91800Y2398900D01*
X-90900Y2398500D01*
X-90100D01*
X-89300Y2398900D01*
X-88700Y2399566D01*
X-88400Y2400500D01*
X-88600Y2401433D01*
X-89100Y2402233D01*
X-90000Y2402767D01*
X-91200Y2403033D01*
X-91900Y2403567D01*
X-92200Y2404500D01*
X-92000Y2405433D01*
X-91500Y2406100D01*
X-90800Y2406500D01*
X-90100D01*
X-89400Y2406233D01*
X-88800Y2405567D01*
G01X-82500Y2398233D02*
X-82700Y2398367D01*
Y2398633D01*
X-82500Y2398767D01*
X-82300Y2398633D01*
Y2398367D01*
X-82500Y2398233D01*
G01Y2401833D02*
X-82700Y2401967D01*
Y2402233D01*
X-82500Y2402367D01*
X-82300Y2402233D01*
Y2401967D01*
X-82500Y2401833D01*
G01X-67000Y2395833D02*
X-68000Y2397167D01*
X-68500Y2398500D01*
Y2403833D01*
X-68000Y2405167D01*
X-67000Y2406500D01*
G01X-60700D02*
Y2400767D01*
X-60300Y2399566D01*
X-59500Y2398767D01*
X-58500Y2398500D01*
X-57500Y2398767D01*
X-56700Y2399566D01*
X-56300Y2400767D01*
Y2406500D01*
G01X-52800Y2398500D02*
Y2406500D01*
X-48200Y2398500D01*
Y2406500D01*
G01X-44500D02*
Y2398500D01*
X-40500D01*
G01X-32500D02*
X-36500D01*
Y2406500D01*
X-32500D01*
G01X-34100Y2402633D02*
X-36500D01*
G01X-28600Y2399566D02*
X-27800Y2398900D01*
X-26900Y2398500D01*
X-26100D01*
X-25300Y2398900D01*
X-24700Y2399566D01*
X-24400Y2400500D01*
X-24600Y2401433D01*
X-25100Y2402233D01*
X-26000Y2402767D01*
X-27200Y2403033D01*
X-27900Y2403567D01*
X-28200Y2404500D01*
X-28000Y2405433D01*
X-27500Y2406100D01*
X-26800Y2406500D01*
X-26100D01*
X-25400Y2406233D01*
X-24800Y2405567D01*
G01X-20600Y2399566D02*
X-19800Y2398900D01*
X-18900Y2398500D01*
X-18100D01*
X-17300Y2398900D01*
X-16700Y2399566D01*
X-16400Y2400500D01*
X-16600Y2401433D01*
X-17100Y2402233D01*
X-18000Y2402767D01*
X-19200Y2403033D01*
X-19900Y2403567D01*
X-20200Y2404500D01*
X-20000Y2405433D01*
X-19500Y2406100D01*
X-18800Y2406500D01*
X-18100D01*
X-17400Y2406233D01*
X-16800Y2405567D01*
G01X-2500Y2398500D02*
X-3300Y2398633D01*
X-4000Y2399167D01*
X-4600Y2399967D01*
X-5000Y2400900D01*
X-5200Y2401967D01*
Y2403033D01*
X-5000Y2404100D01*
X-4600Y2405033D01*
X-4000Y2405833D01*
X-3300Y2406367D01*
X-2500Y2406500D01*
X-1700Y2406367D01*
X-1000Y2405833D01*
X-400Y2405033D01*
X0Y2404100D01*
X200Y2403033D01*
Y2401967D01*
X0Y2400900D01*
X-400Y2399967D01*
X-1000Y2399167D01*
X-1700Y2398633D01*
X-2500Y2398500D01*
G01X5500Y2406500D02*
Y2398500D01*
G01X3200Y2406500D02*
X7800D01*
G01X11400Y2398500D02*
Y2406500D01*
G01X15600D02*
Y2398500D01*
G01Y2402500D02*
X11400D01*
G01X23500Y2398500D02*
X19500D01*
Y2406500D01*
X23500D01*
G01X21900Y2402633D02*
X19500D01*
G01X27500Y2398500D02*
Y2406500D01*
X30000D01*
X30800Y2406100D01*
X31300Y2405567D01*
X31500Y2404500D01*
X31300Y2403433D01*
X30700Y2402767D01*
X30000Y2402367D01*
X27500D01*
G01X30000D02*
X31500Y2398500D01*
G01X34500Y2406500D02*
X35900Y2398500D01*
X37500Y2406500D01*
X39100Y2398500D01*
X40500Y2406500D01*
G01X44300D02*
X46700D01*
G01X45500D02*
Y2398500D01*
G01X44300D02*
X46700D01*
G01X51400Y2399566D02*
X52200Y2398900D01*
X53100Y2398500D01*
X53900D01*
X54700Y2398900D01*
X55300Y2399566D01*
X55600Y2400500D01*
X55400Y2401433D01*
X54900Y2402233D01*
X54000Y2402767D01*
X52800Y2403033D01*
X52100Y2403567D01*
X51800Y2404500D01*
X52000Y2405433D01*
X52500Y2406100D01*
X53200Y2406500D01*
X53900D01*
X54600Y2406233D01*
X55200Y2405567D01*
G01X63500Y2398500D02*
X59500D01*
Y2406500D01*
X63500D01*
G01X61900Y2402633D02*
X59500D01*
G01X75400Y2399566D02*
X76200Y2398900D01*
X77100Y2398500D01*
X77900D01*
X78700Y2398900D01*
X79300Y2399566D01*
X79600Y2400500D01*
X79400Y2401433D01*
X78900Y2402233D01*
X78000Y2402767D01*
X76800Y2403033D01*
X76100Y2403567D01*
X75800Y2404500D01*
X76000Y2405433D01*
X76500Y2406100D01*
X77200Y2406500D01*
X77900D01*
X78600Y2406233D01*
X79200Y2405567D01*
G01X83500Y2398500D02*
Y2406500D01*
X85900D01*
X86700Y2406100D01*
X87300Y2405167D01*
X87500Y2404100D01*
X87300Y2403033D01*
X86800Y2402233D01*
X85900Y2401833D01*
X83500D01*
G01X95500Y2398500D02*
X91500D01*
Y2406500D01*
X95500D01*
G01X93900Y2402633D02*
X91500D01*
G01X103700Y2405833D02*
X103100Y2406233D01*
X102400Y2406500D01*
X101600D01*
X100700Y2406100D01*
X100000Y2405433D01*
X99500Y2404633D01*
X99100Y2403300D01*
X99000Y2402100D01*
X99200Y2400900D01*
X99500Y2400100D01*
X100100Y2399300D01*
X100800Y2398767D01*
X101500Y2398500D01*
X102200D01*
X102900Y2398767D01*
X103500Y2399167D01*
X104000Y2399700D01*
G01X108300Y2406500D02*
X110700D01*
G01X109500D02*
Y2398500D01*
G01X108300D02*
X110700D01*
G01X115600D02*
Y2406500D01*
X119400D01*
G01X118000Y2402633D02*
X115600D01*
G01X124300Y2406500D02*
X126700D01*
G01X125500D02*
Y2398500D01*
G01X124300D02*
X126700D01*
G01X135500D02*
X131500D01*
Y2406500D01*
X135500D01*
G01X133900Y2402633D02*
X131500D01*
G01X139300Y2398500D02*
Y2406500D01*
X141300D01*
X142100Y2406100D01*
X142700Y2405567D01*
X143200Y2404767D01*
X143600Y2403833D01*
X143700Y2402500D01*
X143600Y2401167D01*
X143200Y2400233D01*
X142700Y2399433D01*
X142100Y2398900D01*
X141300Y2398500D01*
X139300D01*
G01X156300Y2406500D02*
X158700D01*
G01X157500D02*
Y2398500D01*
G01X156300D02*
X158700D01*
G01X163200D02*
Y2406500D01*
X167800Y2398500D01*
Y2406500D01*
G01X179500Y2398500D02*
Y2406500D01*
X181900D01*
X182700Y2406100D01*
X183300Y2405167D01*
X183500Y2404100D01*
X183300Y2403033D01*
X182800Y2402233D01*
X181900Y2401833D01*
X179500D01*
G01X191700Y2405833D02*
X191100Y2406233D01*
X190400Y2406500D01*
X189600D01*
X188700Y2406100D01*
X188000Y2405433D01*
X187500Y2404633D01*
X187100Y2403300D01*
X187000Y2402100D01*
X187200Y2400900D01*
X187500Y2400100D01*
X188100Y2399300D01*
X188800Y2398767D01*
X189500Y2398500D01*
X190200D01*
X190900Y2398767D01*
X191500Y2399167D01*
X192000Y2399700D01*
G01X198300Y2402767D02*
X198700Y2403167D01*
X199000Y2403833D01*
X199200Y2404767D01*
X199000Y2405567D01*
X198600Y2406100D01*
X197900Y2406500D01*
X195200D01*
Y2398500D01*
X198500D01*
X199200Y2399033D01*
X199600Y2399833D01*
X199800Y2400767D01*
X199600Y2401700D01*
X199000Y2402500D01*
X198300Y2402767D01*
X195200D01*
G01X211400Y2399566D02*
X212200Y2398900D01*
X213100Y2398500D01*
X213900D01*
X214700Y2398900D01*
X215300Y2399566D01*
X215600Y2400500D01*
X215400Y2401433D01*
X214900Y2402233D01*
X214000Y2402767D01*
X212800Y2403033D01*
X212100Y2403567D01*
X211800Y2404500D01*
X212000Y2405433D01*
X212500Y2406100D01*
X213200Y2406500D01*
X213900D01*
X214600Y2406233D01*
X215200Y2405567D01*
G01X219500Y2398500D02*
Y2406500D01*
X221900D01*
X222700Y2406100D01*
X223300Y2405167D01*
X223500Y2404100D01*
X223300Y2403033D01*
X222800Y2402233D01*
X221900Y2401833D01*
X219500D01*
G01X231500Y2398500D02*
X227500D01*
Y2406500D01*
X231500D01*
G01X229900Y2402633D02*
X227500D01*
G01X239700Y2405833D02*
X239100Y2406233D01*
X238400Y2406500D01*
X237600D01*
X236700Y2406100D01*
X236000Y2405433D01*
X235500Y2404633D01*
X235100Y2403300D01*
X235000Y2402100D01*
X235200Y2400900D01*
X235500Y2400100D01*
X236100Y2399300D01*
X236800Y2398767D01*
X237500Y2398500D01*
X238200D01*
X238900Y2398767D01*
X239500Y2399167D01*
X240000Y2399700D01*
G01X246000Y2395833D02*
X247000Y2397167D01*
X247500Y2398500D01*
Y2403833D01*
X247000Y2405167D01*
X246000Y2406500D01*
G01X-122500Y2383500D02*
Y2391500D01*
X-123700Y2389900D01*
G01Y2383500D02*
X-121300D01*
G01X-114500Y2383233D02*
X-114700Y2383367D01*
Y2383633D01*
X-114500Y2383767D01*
X-114300Y2383633D01*
Y2383367D01*
X-114500Y2383233D01*
G01X-108500Y2383500D02*
Y2391500D01*
X-106100D01*
X-105300Y2391100D01*
X-104700Y2390167D01*
X-104500Y2389100D01*
X-104700Y2388033D01*
X-105200Y2387233D01*
X-106100Y2386833D01*
X-108500D01*
G01X-96300Y2390833D02*
X-96900Y2391233D01*
X-97600Y2391500D01*
X-98400D01*
X-99300Y2391100D01*
X-100000Y2390433D01*
X-100500Y2389633D01*
X-100900Y2388300D01*
X-101000Y2387100D01*
X-100800Y2385900D01*
X-100500Y2385100D01*
X-99900Y2384300D01*
X-99200Y2383767D01*
X-98500Y2383500D01*
X-97800D01*
X-97100Y2383767D01*
X-96500Y2384167D01*
X-96000Y2384700D01*
G01X-89700Y2387767D02*
X-89300Y2388167D01*
X-89000Y2388833D01*
X-88800Y2389767D01*
X-89000Y2390567D01*
X-89400Y2391100D01*
X-90100Y2391500D01*
X-92800D01*
Y2383500D01*
X-89500D01*
X-88800Y2384033D01*
X-88400Y2384833D01*
X-88200Y2385767D01*
X-88400Y2386700D01*
X-89000Y2387500D01*
X-89700Y2387767D01*
X-92800D01*
G01X-76600Y2384566D02*
X-75800Y2383900D01*
X-74900Y2383500D01*
X-74100D01*
X-73300Y2383900D01*
X-72700Y2384566D01*
X-72400Y2385500D01*
X-72600Y2386433D01*
X-73100Y2387233D01*
X-74000Y2387767D01*
X-75200Y2388033D01*
X-75900Y2388567D01*
X-76200Y2389500D01*
X-76000Y2390433D01*
X-75500Y2391100D01*
X-74800Y2391500D01*
X-74100D01*
X-73400Y2391233D01*
X-72800Y2390567D01*
G01X-67700Y2391500D02*
X-65300D01*
G01X-66500D02*
Y2383500D01*
G01X-67700D02*
X-65300D01*
G01X-60400Y2391500D02*
X-56600D01*
X-60400Y2383500D01*
X-56600D01*
G01X-48500D02*
X-52500D01*
Y2391500D01*
X-48500D01*
G01X-50100Y2387633D02*
X-52500D01*
G01X-18500Y2383233D02*
X-18700Y2383367D01*
Y2383633D01*
X-18500Y2383767D01*
X-18300Y2383633D01*
Y2383367D01*
X-18500Y2383233D01*
G01Y2386833D02*
X-18700Y2386967D01*
Y2387233D01*
X-18500Y2387367D01*
X-18300Y2387233D01*
Y2386967D01*
X-18500Y2386833D01*
G01X-4400Y2383500D02*
Y2391500D01*
X-600D01*
G01X-2000Y2387633D02*
X-4400D01*
G01X5500Y2383500D02*
X4700Y2383633D01*
X4000Y2384167D01*
X3400Y2384967D01*
X3000Y2385900D01*
X2800Y2386967D01*
Y2388033D01*
X3000Y2389100D01*
X3400Y2390033D01*
X4000Y2390833D01*
X4700Y2391367D01*
X5500Y2391500D01*
X6300Y2391367D01*
X7000Y2390833D01*
X7600Y2390033D01*
X8000Y2389100D01*
X8200Y2388033D01*
Y2386967D01*
X8000Y2385900D01*
X7600Y2384967D01*
X7000Y2384167D01*
X6300Y2383633D01*
X5500Y2383500D01*
G01X11500Y2391500D02*
Y2383500D01*
X15500D01*
G01X19500Y2391500D02*
Y2383500D01*
X23500D01*
G01X29500D02*
X28700Y2383633D01*
X28000Y2384167D01*
X27400Y2384967D01*
X27000Y2385900D01*
X26800Y2386967D01*
Y2388033D01*
X27000Y2389100D01*
X27400Y2390033D01*
X28000Y2390833D01*
X28700Y2391367D01*
X29500Y2391500D01*
X30300Y2391367D01*
X31000Y2390833D01*
X31600Y2390033D01*
X32000Y2389100D01*
X32200Y2388033D01*
Y2386967D01*
X32000Y2385900D01*
X31600Y2384967D01*
X31000Y2384167D01*
X30300Y2383633D01*
X29500Y2383500D01*
G01X34500Y2391500D02*
X35900Y2383500D01*
X37500Y2391500D01*
X39100Y2383500D01*
X40500Y2391500D01*
G01X54100Y2387500D02*
X56100D01*
Y2385100D01*
X55500Y2384300D01*
X54800Y2383767D01*
X53800Y2383500D01*
X52800Y2383767D01*
X52100Y2384300D01*
X51500Y2385100D01*
X51100Y2386033D01*
X50900Y2387100D01*
Y2388033D01*
X51100Y2388833D01*
X51500Y2389767D01*
X52100Y2390567D01*
X52700Y2391100D01*
X53500Y2391500D01*
X54200D01*
X55000Y2391233D01*
X55600Y2390700D01*
G01X63500Y2383500D02*
X59500D01*
Y2391500D01*
X63500D01*
G01X61900Y2387633D02*
X59500D01*
G01X67500Y2383500D02*
Y2391500D01*
X70000D01*
X70800Y2391100D01*
X71300Y2390567D01*
X71500Y2389500D01*
X71300Y2388433D01*
X70700Y2387767D01*
X70000Y2387367D01*
X67500D01*
G01X70000D02*
X71500Y2383500D01*
G01X78300Y2387767D02*
X78700Y2388167D01*
X79000Y2388833D01*
X79200Y2389767D01*
X79000Y2390567D01*
X78600Y2391100D01*
X77900Y2391500D01*
X75200D01*
Y2383500D01*
X78500D01*
X79200Y2384033D01*
X79600Y2384833D01*
X79800Y2385767D01*
X79600Y2386700D01*
X79000Y2387500D01*
X78300Y2387767D01*
X75200D01*
G01X87500Y2383500D02*
X83500D01*
Y2391500D01*
X87500D01*
G01X85900Y2387633D02*
X83500D01*
G01X91500Y2383500D02*
Y2391500D01*
X94000D01*
X94800Y2391100D01*
X95300Y2390567D01*
X95500Y2389500D01*
X95300Y2388433D01*
X94700Y2387767D01*
X94000Y2387367D01*
X91500D01*
G01X94000D02*
X95500Y2383500D01*
G01X107600D02*
Y2391500D01*
X111400D01*
G01X110000Y2387633D02*
X107600D01*
G01X116300Y2391500D02*
X118700D01*
G01X117500D02*
Y2383500D01*
G01X116300D02*
X118700D01*
G01X123500Y2391500D02*
Y2383500D01*
X127500D01*
G01X135500D02*
X131500D01*
Y2391500D01*
X135500D01*
G01X133900Y2387633D02*
X131500D01*
G01X140800Y2381100D02*
X142200Y2382967D01*
Y2384833D01*
X140800D01*
Y2382967D01*
X142200D01*
G01Y2386167D02*
Y2388033D01*
X140800D01*
Y2386167D01*
X142200D01*
G01X154500Y2391500D02*
X155900Y2383500D01*
X157500Y2391500D01*
X159100Y2383500D01*
X160500Y2391500D01*
G01X164300D02*
X166700D01*
G01X165500D02*
Y2383500D01*
G01X164300D02*
X166700D01*
G01X173500Y2391500D02*
Y2383500D01*
G01X171200Y2391500D02*
X175800D01*
G01X179400Y2383500D02*
Y2391500D01*
G01X183600D02*
Y2383500D01*
G01Y2387500D02*
X179400D01*
G01X197500Y2391500D02*
Y2383500D01*
G01X195200Y2391500D02*
X199800D01*
G01X205500Y2383500D02*
X204700Y2383633D01*
X204000Y2384167D01*
X203400Y2384967D01*
X203000Y2385900D01*
X202800Y2386967D01*
Y2388033D01*
X203000Y2389100D01*
X203400Y2390033D01*
X204000Y2390833D01*
X204700Y2391367D01*
X205500Y2391500D01*
X206300Y2391367D01*
X207000Y2390833D01*
X207600Y2390033D01*
X208000Y2389100D01*
X208200Y2388033D01*
Y2386967D01*
X208000Y2385900D01*
X207600Y2384967D01*
X207000Y2384167D01*
X206300Y2383633D01*
X205500Y2383500D01*
G01X211500Y2391500D02*
Y2383500D01*
X215500D01*
G01X223500D02*
X219500D01*
Y2391500D01*
X223500D01*
G01X221900Y2387633D02*
X219500D01*
G01X227500Y2383500D02*
Y2391500D01*
X230000D01*
X230800Y2391100D01*
X231300Y2390567D01*
X231500Y2389500D01*
X231300Y2388433D01*
X230700Y2387767D01*
X230000Y2387367D01*
X227500D01*
G01X230000D02*
X231500Y2383500D01*
G01X235000D02*
X237500Y2391500D01*
X240000Y2383500D01*
G01X239100Y2386300D02*
X235900D01*
G01X243200Y2383500D02*
Y2391500D01*
X247800Y2383500D01*
Y2391500D01*
G01X255700Y2390833D02*
X255100Y2391233D01*
X254400Y2391500D01*
X253600D01*
X252700Y2391100D01*
X252000Y2390433D01*
X251500Y2389633D01*
X251100Y2388300D01*
X251000Y2387100D01*
X251200Y2385900D01*
X251500Y2385100D01*
X252100Y2384300D01*
X252800Y2383767D01*
X253500Y2383500D01*
X254200D01*
X254900Y2383767D01*
X255500Y2384167D01*
X256000Y2384700D01*
G01X263500Y2383500D02*
X259500D01*
Y2391500D01*
X263500D01*
G01X261900Y2387633D02*
X259500D01*
G01X276200Y2384967D02*
X278800D01*
G01Y2387367D02*
X276200D01*
G01X284400Y2386167D02*
X286800D01*
G01X285500Y2387900D02*
Y2384433D01*
G01X291700Y2383233D02*
X295300Y2391500D01*
G01X300200Y2386167D02*
X302800D01*
G01X309500Y2391500D02*
X308700Y2391233D01*
X308100Y2390567D01*
X307700Y2389767D01*
X307400Y2388700D01*
X307300Y2387500D01*
X307400Y2386300D01*
X307700Y2385233D01*
X308100Y2384433D01*
X308700Y2383767D01*
X309500Y2383500D01*
X310300Y2383767D01*
X310900Y2384433D01*
X311300Y2385233D01*
X311600Y2386300D01*
X311700Y2387500D01*
X311600Y2388700D01*
X311300Y2389767D01*
X310900Y2390567D01*
X310300Y2391233D01*
X309500Y2391500D01*
G01X317500Y2383233D02*
X317300Y2383367D01*
Y2383633D01*
X317500Y2383767D01*
X317700Y2383633D01*
Y2383367D01*
X317500Y2383233D01*
G01X325500Y2383500D02*
Y2391500D01*
X324300Y2389900D01*
G01Y2383500D02*
X326700D01*
G01X331300Y2384700D02*
X331900Y2384033D01*
X332600Y2383633D01*
X333500Y2383500D01*
X334400Y2383767D01*
X335100Y2384300D01*
X335600Y2385233D01*
X335700Y2386300D01*
X335500Y2387367D01*
X335000Y2388033D01*
X334300Y2388567D01*
X333600Y2388700D01*
X332900Y2388567D01*
X332000Y2388033D01*
X332300Y2391500D01*
X335000D01*
G01X338900Y2383500D02*
Y2391500D01*
X341500Y2384833D01*
X344100Y2391500D01*
Y2383500D01*
G01X346900D02*
Y2391500D01*
X349500Y2384833D01*
X352100Y2391500D01*
Y2383500D01*
G01X-122500Y2413500D02*
X-123300Y2413633D01*
X-124000Y2414167D01*
X-124600Y2414967D01*
X-125000Y2415900D01*
X-125200Y2416967D01*
Y2418033D01*
X-125000Y2419100D01*
X-124600Y2420033D01*
X-124000Y2420833D01*
X-123300Y2421367D01*
X-122500Y2421500D01*
X-121700Y2421367D01*
X-121000Y2420833D01*
X-120400Y2420033D01*
X-120000Y2419100D01*
X-119800Y2418033D01*
Y2416967D01*
X-120000Y2415900D01*
X-120400Y2414967D01*
X-121000Y2414167D01*
X-121700Y2413633D01*
X-122500Y2413500D01*
G01X-121700Y2415633D02*
X-120500Y2413500D01*
G01X-116200Y2418833D02*
Y2415100D01*
X-115800Y2414167D01*
X-115200Y2413633D01*
X-114500Y2413500D01*
X-113800Y2413633D01*
X-113200Y2414167D01*
X-112800Y2415100D01*
G01Y2413500D02*
Y2418833D01*
G01X-104700Y2413500D02*
Y2418833D01*
G01Y2417900D02*
X-105100Y2418433D01*
X-105700Y2418700D01*
X-106400Y2418833D01*
X-107100Y2418567D01*
X-107700Y2418033D01*
X-108100Y2417233D01*
X-108300Y2416167D01*
X-108100Y2415100D01*
X-107700Y2414300D01*
X-107100Y2413767D01*
X-106400Y2413500D01*
X-105700Y2413633D01*
X-105100Y2414033D01*
X-104700Y2414566D01*
G01X-100200Y2413500D02*
Y2418833D01*
G01Y2417500D02*
X-99800Y2418167D01*
X-99200Y2418700D01*
X-98400Y2418833D01*
X-97700Y2418700D01*
X-97100Y2418167D01*
X-96800Y2417233D01*
Y2413500D01*
G01X-90500Y2421500D02*
Y2413500D01*
G01X-91900Y2418833D02*
X-89100D01*
G01X-80700Y2413500D02*
Y2418833D01*
G01Y2417900D02*
X-81100Y2418433D01*
X-81700Y2418700D01*
X-82400Y2418833D01*
X-83100Y2418567D01*
X-83700Y2418033D01*
X-84100Y2417233D01*
X-84300Y2416167D01*
X-84100Y2415100D01*
X-83700Y2414300D01*
X-83100Y2413767D01*
X-82400Y2413500D01*
X-81700Y2413633D01*
X-81100Y2414033D01*
X-80700Y2414566D01*
G01X-68400Y2413500D02*
Y2421500D01*
X-64600D01*
G01X-66000Y2417633D02*
X-68400D01*
G01X-61000Y2413500D02*
X-58500Y2421500D01*
X-56000Y2413500D01*
G01X-56900Y2416300D02*
X-60100D01*
G01X-49700Y2417767D02*
X-49300Y2418167D01*
X-49000Y2418833D01*
X-48800Y2419767D01*
X-49000Y2420567D01*
X-49400Y2421100D01*
X-50100Y2421500D01*
X-52800D01*
Y2413500D01*
X-49500D01*
X-48800Y2414033D01*
X-48400Y2414833D01*
X-48200Y2415767D01*
X-48400Y2416700D01*
X-49000Y2417500D01*
X-49700Y2417767D01*
X-52800D01*
G01X-36800Y2413500D02*
Y2421500D01*
X-32200Y2413500D01*
Y2421500D01*
G01X-26500Y2413500D02*
X-27300Y2413633D01*
X-28000Y2414167D01*
X-28600Y2414967D01*
X-29000Y2415900D01*
X-29200Y2416967D01*
Y2418033D01*
X-29000Y2419100D01*
X-28600Y2420033D01*
X-28000Y2420833D01*
X-27300Y2421367D01*
X-26500Y2421500D01*
X-25700Y2421367D01*
X-25000Y2420833D01*
X-24400Y2420033D01*
X-24000Y2419100D01*
X-23800Y2418033D01*
Y2416967D01*
X-24000Y2415900D01*
X-24400Y2414967D01*
X-25000Y2414167D01*
X-25700Y2413633D01*
X-26500Y2413500D01*
G01X-18500Y2421500D02*
Y2413500D01*
G01X-20800Y2421500D02*
X-16200D01*
G01X-8500Y2413500D02*
X-12500D01*
Y2421500D01*
X-8500D01*
G01X-10100Y2417633D02*
X-12500D01*
G01X3500Y2413500D02*
Y2421500D01*
X6000D01*
X6800Y2421100D01*
X7300Y2420567D01*
X7500Y2419500D01*
X7300Y2418433D01*
X6700Y2417767D01*
X6000Y2417367D01*
X3500D01*
G01X6000D02*
X7500Y2413500D01*
G01X15500D02*
X11500D01*
Y2421500D01*
X15500D01*
G01X13900Y2417633D02*
X11500D01*
G01X19000Y2421500D02*
X21500Y2413500D01*
X24000Y2421500D01*
G01X29500Y2413233D02*
X29300Y2413367D01*
Y2413633D01*
X29500Y2413767D01*
X29700Y2413633D01*
Y2413367D01*
X29500Y2413233D01*
G01Y2416833D02*
X29300Y2416967D01*
Y2417233D01*
X29500Y2417367D01*
X29700Y2417233D01*
Y2416967D01*
X29500Y2416833D01*
G01X35600Y2413500D02*
Y2421500D01*
X39400D01*
G01X38000Y2417633D02*
X35600D01*
G01X-104113Y-18750D02*
X-99463D01*
Y-6250D01*
X-104113D01*
G01X-1000Y0D02*
X-90088D01*
G01X-48878Y1832007D02*
X-92185D01*
G01X-84311D02*
Y1885157D01*
G01X-87200Y1859560D02*
X-99700D01*
X-90742Y1853825D01*
Y1861575D01*
G01X-87200Y1866070D02*
X-99700D01*
X-89283Y1870100D01*
X-99700Y1874130D01*
X-87200D01*
G01Y1878470D02*
X-99700D01*
X-89283Y1882500D01*
X-99700Y1886530D01*
X-87200D01*
G01X-48878Y1847756D02*
X-92185D01*
G01X-96700Y1997767D02*
X-96300Y1998167D01*
X-96000Y1998833D01*
X-95800Y1999767D01*
X-96000Y2000567D01*
X-96400Y2001100D01*
X-97100Y2001500D01*
X-99800D01*
Y1993500D01*
X-96500D01*
X-95800Y1994033D01*
X-95400Y1994833D01*
X-95200Y1995767D01*
X-95400Y1996700D01*
X-96000Y1997500D01*
X-96700Y1997767D01*
X-99800D01*
G01X-89500Y1993233D02*
X-89700Y1993367D01*
Y1993633D01*
X-89500Y1993767D01*
X-89300Y1993633D01*
Y1993367D01*
X-89500Y1993233D01*
G01X-82700Y2001500D02*
X-80300D01*
G01X-81500D02*
Y1993500D01*
G01X-82700D02*
X-80300D01*
G01X-75400D02*
Y2001500D01*
X-71600D01*
G01X-73000Y1997633D02*
X-75400D01*
G01X-57500Y2001500D02*
Y1993500D01*
G01X-59800Y2001500D02*
X-55200D01*
G01X-51600Y1993500D02*
Y2001500D01*
G01X-47400D02*
Y1993500D01*
G01Y1997500D02*
X-51600D01*
G01X-39500Y1993500D02*
X-43500D01*
Y2001500D01*
X-39500D01*
G01X-41100Y1997633D02*
X-43500D01*
G01X-27500Y1993500D02*
Y2001500D01*
X-25100D01*
X-24300Y2001100D01*
X-23700Y2000167D01*
X-23500Y1999100D01*
X-23700Y1998033D01*
X-24200Y1997233D01*
X-25100Y1996833D01*
X-27500D01*
G01X-17500Y2001500D02*
Y1993500D01*
G01X-19800Y2001500D02*
X-15200D01*
G01X-11600Y1993500D02*
Y2001500D01*
G01X-7400D02*
Y1993500D01*
G01Y1997500D02*
X-11600D01*
G01X6500Y2001500D02*
Y1993500D01*
G01X4200Y2001500D02*
X8800D01*
G01X14500Y1993500D02*
X13700Y1993633D01*
X13000Y1994167D01*
X12400Y1994967D01*
X12000Y1995900D01*
X11800Y1996967D01*
Y1998033D01*
X12000Y1999100D01*
X12400Y2000033D01*
X13000Y2000833D01*
X13700Y2001367D01*
X14500Y2001500D01*
X15300Y2001367D01*
X16000Y2000833D01*
X16600Y2000033D01*
X17000Y1999100D01*
X17200Y1998033D01*
Y1996967D01*
X17000Y1995900D01*
X16600Y1994967D01*
X16000Y1994167D01*
X15300Y1993633D01*
X14500Y1993500D01*
G01X22500D02*
X21700Y1993633D01*
X21000Y1994167D01*
X20400Y1994967D01*
X20000Y1995900D01*
X19800Y1996967D01*
Y1998033D01*
X20000Y1999100D01*
X20400Y2000033D01*
X21000Y2000833D01*
X21700Y2001367D01*
X22500Y2001500D01*
X23300Y2001367D01*
X24000Y2000833D01*
X24600Y2000033D01*
X25000Y1999100D01*
X25200Y1998033D01*
Y1996967D01*
X25000Y1995900D01*
X24600Y1994967D01*
X24000Y1994167D01*
X23300Y1993633D01*
X22500Y1993500D01*
G01X28500Y2001500D02*
Y1993500D01*
X32500D01*
G01X37300Y2001500D02*
X39700D01*
G01X38500D02*
Y1993500D01*
G01X37300D02*
X39700D01*
G01X44200D02*
Y2001500D01*
X48800Y1993500D01*
Y2001500D01*
G01X55100Y1997500D02*
X57100D01*
Y1995100D01*
X56500Y1994300D01*
X55800Y1993767D01*
X54800Y1993500D01*
X53800Y1993767D01*
X53100Y1994300D01*
X52500Y1995100D01*
X52100Y1996033D01*
X51900Y1997100D01*
Y1998033D01*
X52100Y1998833D01*
X52500Y1999767D01*
X53100Y2000567D01*
X53700Y2001100D01*
X54500Y2001500D01*
X55200D01*
X56000Y2001233D01*
X56600Y2000700D01*
G01X68400Y1993500D02*
Y2001500D01*
G01X72600D02*
Y1993500D01*
G01Y1997500D02*
X68400D01*
G01X78500Y1993500D02*
X77700Y1993633D01*
X77000Y1994167D01*
X76400Y1994967D01*
X76000Y1995900D01*
X75800Y1996967D01*
Y1998033D01*
X76000Y1999100D01*
X76400Y2000033D01*
X77000Y2000833D01*
X77700Y2001367D01*
X78500Y2001500D01*
X79300Y2001367D01*
X80000Y2000833D01*
X80600Y2000033D01*
X81000Y1999100D01*
X81200Y1998033D01*
Y1996967D01*
X81000Y1995900D01*
X80600Y1994967D01*
X80000Y1994167D01*
X79300Y1993633D01*
X78500Y1993500D01*
G01X84500Y2001500D02*
Y1993500D01*
X88500D01*
G01X96500D02*
X92500D01*
Y2001500D01*
X96500D01*
G01X94900Y1997633D02*
X92500D01*
G01X109300Y2001500D02*
X111700D01*
G01X110500D02*
Y1993500D01*
G01X109300D02*
X111700D01*
G01X116400Y1994566D02*
X117200Y1993900D01*
X118100Y1993500D01*
X118900D01*
X119700Y1993900D01*
X120300Y1994566D01*
X120600Y1995500D01*
X120400Y1996433D01*
X119900Y1997233D01*
X119000Y1997767D01*
X117800Y1998033D01*
X117100Y1998567D01*
X116800Y1999500D01*
X117000Y2000433D01*
X117500Y2001100D01*
X118200Y2001500D01*
X118900D01*
X119600Y2001233D01*
X120200Y2000567D01*
G01X131900Y1993500D02*
Y2001500D01*
X134500Y1994833D01*
X137100Y2001500D01*
Y1993500D01*
G01X140000D02*
X142500Y2001500D01*
X145000Y1993500D01*
G01X144100Y1996300D02*
X140900D01*
G01X148300Y1993500D02*
Y2001500D01*
X150300D01*
X151100Y2001100D01*
X151700Y2000567D01*
X152200Y1999767D01*
X152600Y1998833D01*
X152700Y1997500D01*
X152600Y1996167D01*
X152200Y1995233D01*
X151700Y1994433D01*
X151100Y1993900D01*
X150300Y1993500D01*
X148300D01*
G01X160500D02*
X156500D01*
Y2001500D01*
X160500D01*
G01X158900Y1997633D02*
X156500D01*
G01X175300Y1997767D02*
X175700Y1998167D01*
X176000Y1998833D01*
X176200Y1999767D01*
X176000Y2000567D01*
X175600Y2001100D01*
X174900Y2001500D01*
X172200D01*
Y1993500D01*
X175500D01*
X176200Y1994033D01*
X176600Y1994833D01*
X176800Y1995767D01*
X176600Y1996700D01*
X176000Y1997500D01*
X175300Y1997767D01*
X172200D01*
G01X182500Y1993500D02*
Y1997100D01*
X180500Y2001500D01*
G01X184500D02*
X182500Y1997100D01*
G01X196500Y1993500D02*
Y2001500D01*
X199000D01*
X199800Y2001100D01*
X200300Y2000567D01*
X200500Y1999500D01*
X200300Y1998433D01*
X199700Y1997767D01*
X199000Y1997367D01*
X196500D01*
G01X199000D02*
X200500Y1993500D01*
G01X206500D02*
X205700Y1993633D01*
X205000Y1994167D01*
X204400Y1994967D01*
X204000Y1995900D01*
X203800Y1996967D01*
Y1998033D01*
X204000Y1999100D01*
X204400Y2000033D01*
X205000Y2000833D01*
X205700Y2001367D01*
X206500Y2001500D01*
X207300Y2001367D01*
X208000Y2000833D01*
X208600Y2000033D01*
X209000Y1999100D01*
X209200Y1998033D01*
Y1996967D01*
X209000Y1995900D01*
X208600Y1994967D01*
X208000Y1994167D01*
X207300Y1993633D01*
X206500Y1993500D01*
G01X212300Y2001500D02*
Y1995767D01*
X212700Y1994566D01*
X213500Y1993767D01*
X214500Y1993500D01*
X215500Y1993767D01*
X216300Y1994566D01*
X216700Y1995767D01*
Y2001500D01*
G01X222500D02*
Y1993500D01*
G01X220200Y2001500D02*
X224800D01*
G01X229300D02*
X231700D01*
G01X230500D02*
Y1993500D01*
G01X229300D02*
X231700D01*
G01X236200D02*
Y2001500D01*
X240800Y1993500D01*
Y2001500D01*
G01X247100Y1997500D02*
X249100D01*
Y1995100D01*
X248500Y1994300D01*
X247800Y1993767D01*
X246800Y1993500D01*
X245800Y1993767D01*
X245100Y1994300D01*
X244500Y1995100D01*
X244100Y1996033D01*
X243900Y1997100D01*
Y1998033D01*
X244100Y1998833D01*
X244500Y1999767D01*
X245100Y2000567D01*
X245700Y2001100D01*
X246500Y2001500D01*
X247200D01*
X248000Y2001233D01*
X248600Y2000700D01*
G01X254300Y1992033D02*
X254700Y1993767D01*
G01X268200Y1993500D02*
Y2001500D01*
X272800Y1993500D01*
Y2001500D01*
G01X278500Y1993500D02*
X277700Y1993633D01*
X277000Y1994167D01*
X276400Y1994967D01*
X276000Y1995900D01*
X275800Y1996967D01*
Y1998033D01*
X276000Y1999100D01*
X276400Y2000033D01*
X277000Y2000833D01*
X277700Y2001367D01*
X278500Y2001500D01*
X279300Y2001367D01*
X280000Y2000833D01*
X280600Y2000033D01*
X281000Y1999100D01*
X281200Y1998033D01*
Y1996967D01*
X281000Y1995900D01*
X280600Y1994967D01*
X280000Y1994167D01*
X279300Y1993633D01*
X278500Y1993500D01*
G01X284200D02*
Y2001500D01*
X288800Y1993500D01*
Y2001500D01*
G01X293200Y1996167D02*
X295800D01*
G01X300600Y1993500D02*
Y2001500D01*
X304400D01*
G01X303000Y1997633D02*
X300600D01*
G01X308300Y2001500D02*
Y1995767D01*
X308700Y1994566D01*
X309500Y1993767D01*
X310500Y1993500D01*
X311500Y1993767D01*
X312300Y1994566D01*
X312700Y1995767D01*
Y2001500D01*
G01X316200Y1993500D02*
Y2001500D01*
X320800Y1993500D01*
Y2001500D01*
G01X328700Y2000833D02*
X328100Y2001233D01*
X327400Y2001500D01*
X326600D01*
X325700Y2001100D01*
X325000Y2000433D01*
X324500Y1999633D01*
X324100Y1998300D01*
X324000Y1997100D01*
X324200Y1995900D01*
X324500Y1995100D01*
X325100Y1994300D01*
X325800Y1993767D01*
X326500Y1993500D01*
X327200D01*
X327900Y1993767D01*
X328500Y1994167D01*
X329000Y1994700D01*
G01X334500Y2001500D02*
Y1993500D01*
G01X332200Y2001500D02*
X336800D01*
G01X341300D02*
X343700D01*
G01X342500D02*
Y1993500D01*
G01X341300D02*
X343700D01*
G01X350500D02*
X349700Y1993633D01*
X349000Y1994167D01*
X348400Y1994967D01*
X348000Y1995900D01*
X347800Y1996967D01*
Y1998033D01*
X348000Y1999100D01*
X348400Y2000033D01*
X349000Y2000833D01*
X349700Y2001367D01*
X350500Y2001500D01*
X351300Y2001367D01*
X352000Y2000833D01*
X352600Y2000033D01*
X353000Y1999100D01*
X353200Y1998033D01*
Y1996967D01*
X353000Y1995900D01*
X352600Y1994967D01*
X352000Y1994167D01*
X351300Y1993633D01*
X350500Y1993500D01*
G01X356200D02*
Y2001500D01*
X360800Y1993500D01*
Y2001500D01*
G01X364000Y1993500D02*
X366500Y2001500D01*
X369000Y1993500D01*
G01X368100Y1996300D02*
X364900D01*
G01X372500Y2001500D02*
Y1993500D01*
X376500D01*
G01X388500D02*
Y2001500D01*
X390900D01*
X391700Y2001100D01*
X392300Y2000167D01*
X392500Y1999100D01*
X392300Y1998033D01*
X391800Y1997233D01*
X390900Y1996833D01*
X388500D01*
G01X396000Y1993500D02*
X398500Y2001500D01*
X401000Y1993500D01*
G01X400100Y1996300D02*
X396900D01*
G01X404300Y1993500D02*
Y2001500D01*
X406300D01*
X407100Y2001100D01*
X407700Y2000567D01*
X408200Y1999767D01*
X408600Y1998833D01*
X408700Y1997500D01*
X408600Y1996167D01*
X408200Y1995233D01*
X407700Y1994433D01*
X407100Y1993900D01*
X406300Y1993500D01*
X404300D01*
G01X420400Y1994566D02*
X421200Y1993900D01*
X422100Y1993500D01*
X422900D01*
X423700Y1993900D01*
X424300Y1994566D01*
X424600Y1995500D01*
X424400Y1996433D01*
X423900Y1997233D01*
X423000Y1997767D01*
X421800Y1998033D01*
X421100Y1998567D01*
X420800Y1999500D01*
X421000Y2000433D01*
X421500Y2001100D01*
X422200Y2001500D01*
X422900D01*
X423600Y2001233D01*
X424200Y2000567D01*
G01X429300Y2001500D02*
X431700D01*
G01X430500D02*
Y1993500D01*
G01X429300D02*
X431700D01*
G01X436600Y2001500D02*
X440400D01*
X436600Y1993500D01*
X440400D01*
G01X448500D02*
X444500D01*
Y2001500D01*
X448500D01*
G01X446900Y1997633D02*
X444500D01*
G01X461300Y2001500D02*
X463700D01*
G01X462500D02*
Y1993500D01*
G01X461300D02*
X463700D01*
G01X468400Y1994566D02*
X469200Y1993900D01*
X470100Y1993500D01*
X470900D01*
X471700Y1993900D01*
X472300Y1994566D01*
X472600Y1995500D01*
X472400Y1996433D01*
X471900Y1997233D01*
X471000Y1997767D01*
X469800Y1998033D01*
X469100Y1998567D01*
X468800Y1999500D01*
X469000Y2000433D01*
X469500Y2001100D01*
X470200Y2001500D01*
X470900D01*
X471600Y2001233D01*
X472200Y2000567D01*
G01X486500Y2001500D02*
Y1993500D01*
G01X484200Y2001500D02*
X488800D01*
G01X492400Y1993500D02*
Y2001500D01*
G01X496600D02*
Y1993500D01*
G01Y1997500D02*
X492400D01*
G01X504500Y1993500D02*
X500500D01*
Y2001500D01*
X504500D01*
G01X502900Y1997633D02*
X500500D01*
G01X516500Y1993500D02*
Y2001500D01*
X518900D01*
X519700Y2001100D01*
X520300Y2000167D01*
X520500Y1999100D01*
X520300Y1998033D01*
X519800Y1997233D01*
X518900Y1996833D01*
X516500D01*
G01X524500Y1993500D02*
Y2001500D01*
X527000D01*
X527800Y2001100D01*
X528300Y2000567D01*
X528500Y1999500D01*
X528300Y1998433D01*
X527700Y1997767D01*
X527000Y1997367D01*
X524500D01*
G01X527000D02*
X528500Y1993500D01*
G01X534500D02*
X533700Y1993633D01*
X533000Y1994167D01*
X532400Y1994967D01*
X532000Y1995900D01*
X531800Y1996967D01*
Y1998033D01*
X532000Y1999100D01*
X532400Y2000033D01*
X533000Y2000833D01*
X533700Y2001367D01*
X534500Y2001500D01*
X535300Y2001367D01*
X536000Y2000833D01*
X536600Y2000033D01*
X537000Y1999100D01*
X537200Y1998033D01*
Y1996967D01*
X537000Y1995900D01*
X536600Y1994967D01*
X536000Y1994167D01*
X535300Y1993633D01*
X534500Y1993500D01*
G01X540600D02*
Y2001500D01*
X544400D01*
G01X543000Y1997633D02*
X540600D01*
G01X549300Y2001500D02*
X551700D01*
G01X550500D02*
Y1993500D01*
G01X549300D02*
X551700D01*
G01X556500Y2001500D02*
Y1993500D01*
X560500D01*
G01X568500D02*
X564500D01*
Y2001500D01*
X568500D01*
G01X566900Y1997633D02*
X564500D01*
G01X580400Y1994566D02*
X581200Y1993900D01*
X582100Y1993500D01*
X582900D01*
X583700Y1993900D01*
X584300Y1994566D01*
X584600Y1995500D01*
X584400Y1996433D01*
X583900Y1997233D01*
X583000Y1997767D01*
X581800Y1998033D01*
X581100Y1998567D01*
X580800Y1999500D01*
X581000Y2000433D01*
X581500Y2001100D01*
X582200Y2001500D01*
X582900D01*
X583600Y2001233D01*
X584200Y2000567D01*
G01X589300Y2001500D02*
X591700D01*
G01X590500D02*
Y1993500D01*
G01X589300D02*
X591700D01*
G01X596600Y2001500D02*
X600400D01*
X596600Y1993500D01*
X600400D01*
G01X608500D02*
X604500D01*
Y2001500D01*
X608500D01*
G01X606900Y1997633D02*
X604500D01*
G01X621400Y1996167D02*
X623800D01*
G01X622500Y1997900D02*
Y1994433D01*
G01X636600Y2000167D02*
X637200Y2000967D01*
X637900Y2001367D01*
X638700Y2001500D01*
X639700Y2001233D01*
X640400Y2000567D01*
X640600Y1999767D01*
X640500Y1998966D01*
X640100Y1998300D01*
X638100Y1996967D01*
X637200Y1996033D01*
X636600Y1994700D01*
X636400Y1993500D01*
X640600D01*
G01X646500Y2001500D02*
X645700Y2001233D01*
X645100Y2000567D01*
X644700Y1999767D01*
X644400Y1998700D01*
X644300Y1997500D01*
X644400Y1996300D01*
X644700Y1995233D01*
X645100Y1994433D01*
X645700Y1993767D01*
X646500Y1993500D01*
X647300Y1993767D01*
X647900Y1994433D01*
X648300Y1995233D01*
X648600Y1996300D01*
X648700Y1997500D01*
X648600Y1998700D01*
X648300Y1999767D01*
X647900Y2000567D01*
X647300Y2001233D01*
X646500Y2001500D01*
G01X651900Y1993500D02*
Y2001500D01*
X654500Y1994833D01*
X657100Y2001500D01*
Y1993500D01*
G01X661300Y2001500D02*
X663700D01*
G01X662500D02*
Y1993500D01*
G01X661300D02*
X663700D01*
G01X668500Y2001500D02*
Y1993500D01*
X672500D01*
G01X-100000Y2008500D02*
X-97500Y2016500D01*
X-95000Y2008500D01*
G01X-95900Y2011300D02*
X-99100D01*
G01X-89500Y2008233D02*
X-89700Y2008367D01*
Y2008633D01*
X-89500Y2008767D01*
X-89300Y2008633D01*
Y2008367D01*
X-89500Y2008233D01*
G01X-82700Y2016500D02*
X-80300D01*
G01X-81500D02*
Y2008500D01*
G01X-82700D02*
X-80300D01*
G01X-75400D02*
Y2016500D01*
X-71600D01*
G01X-73000Y2012633D02*
X-75400D01*
G01X-57500Y2016500D02*
Y2008500D01*
G01X-59800Y2016500D02*
X-55200D01*
G01X-51600Y2008500D02*
Y2016500D01*
G01X-47400D02*
Y2008500D01*
G01Y2012500D02*
X-51600D01*
G01X-39500Y2008500D02*
X-43500D01*
Y2016500D01*
X-39500D01*
G01X-41100Y2012633D02*
X-43500D01*
G01X-27500Y2008500D02*
Y2016500D01*
X-25100D01*
X-24300Y2016100D01*
X-23700Y2015167D01*
X-23500Y2014100D01*
X-23700Y2013033D01*
X-24200Y2012233D01*
X-25100Y2011833D01*
X-27500D01*
G01X-17500Y2016500D02*
Y2008500D01*
G01X-19800Y2016500D02*
X-15200D01*
G01X-11600Y2008500D02*
Y2016500D01*
G01X-7400D02*
Y2008500D01*
G01Y2012500D02*
X-11600D01*
G01X6500Y2016500D02*
Y2008500D01*
G01X4200Y2016500D02*
X8800D01*
G01X14500Y2008500D02*
X13700Y2008633D01*
X13000Y2009167D01*
X12400Y2009967D01*
X12000Y2010900D01*
X11800Y2011967D01*
Y2013033D01*
X12000Y2014100D01*
X12400Y2015033D01*
X13000Y2015833D01*
X13700Y2016367D01*
X14500Y2016500D01*
X15300Y2016367D01*
X16000Y2015833D01*
X16600Y2015033D01*
X17000Y2014100D01*
X17200Y2013033D01*
Y2011967D01*
X17000Y2010900D01*
X16600Y2009967D01*
X16000Y2009167D01*
X15300Y2008633D01*
X14500Y2008500D01*
G01X22500D02*
X21700Y2008633D01*
X21000Y2009167D01*
X20400Y2009967D01*
X20000Y2010900D01*
X19800Y2011967D01*
Y2013033D01*
X20000Y2014100D01*
X20400Y2015033D01*
X21000Y2015833D01*
X21700Y2016367D01*
X22500Y2016500D01*
X23300Y2016367D01*
X24000Y2015833D01*
X24600Y2015033D01*
X25000Y2014100D01*
X25200Y2013033D01*
Y2011967D01*
X25000Y2010900D01*
X24600Y2009967D01*
X24000Y2009167D01*
X23300Y2008633D01*
X22500Y2008500D01*
G01X28500Y2016500D02*
Y2008500D01*
X32500D01*
G01X37300Y2016500D02*
X39700D01*
G01X38500D02*
Y2008500D01*
G01X37300D02*
X39700D01*
G01X44200D02*
Y2016500D01*
X48800Y2008500D01*
Y2016500D01*
G01X55100Y2012500D02*
X57100D01*
Y2010100D01*
X56500Y2009300D01*
X55800Y2008767D01*
X54800Y2008500D01*
X53800Y2008767D01*
X53100Y2009300D01*
X52500Y2010100D01*
X52100Y2011033D01*
X51900Y2012100D01*
Y2013033D01*
X52100Y2013833D01*
X52500Y2014767D01*
X53100Y2015567D01*
X53700Y2016100D01*
X54500Y2016500D01*
X55200D01*
X56000Y2016233D01*
X56600Y2015700D01*
G01X68400Y2008500D02*
Y2016500D01*
G01X72600D02*
Y2008500D01*
G01Y2012500D02*
X68400D01*
G01X78500Y2008500D02*
X77700Y2008633D01*
X77000Y2009167D01*
X76400Y2009967D01*
X76000Y2010900D01*
X75800Y2011967D01*
Y2013033D01*
X76000Y2014100D01*
X76400Y2015033D01*
X77000Y2015833D01*
X77700Y2016367D01*
X78500Y2016500D01*
X79300Y2016367D01*
X80000Y2015833D01*
X80600Y2015033D01*
X81000Y2014100D01*
X81200Y2013033D01*
Y2011967D01*
X81000Y2010900D01*
X80600Y2009967D01*
X80000Y2009167D01*
X79300Y2008633D01*
X78500Y2008500D01*
G01X84500Y2016500D02*
Y2008500D01*
X88500D01*
G01X96500D02*
X92500D01*
Y2016500D01*
X96500D01*
G01X94900Y2012633D02*
X92500D01*
G01X109300Y2016500D02*
X111700D01*
G01X110500D02*
Y2008500D01*
G01X109300D02*
X111700D01*
G01X116400Y2009566D02*
X117200Y2008900D01*
X118100Y2008500D01*
X118900D01*
X119700Y2008900D01*
X120300Y2009566D01*
X120600Y2010500D01*
X120400Y2011433D01*
X119900Y2012233D01*
X119000Y2012767D01*
X117800Y2013033D01*
X117100Y2013567D01*
X116800Y2014500D01*
X117000Y2015433D01*
X117500Y2016100D01*
X118200Y2016500D01*
X118900D01*
X119600Y2016233D01*
X120200Y2015567D01*
G01X131900Y2008500D02*
Y2016500D01*
X134500Y2009833D01*
X137100Y2016500D01*
Y2008500D01*
G01X140000D02*
X142500Y2016500D01*
X145000Y2008500D01*
G01X144100Y2011300D02*
X140900D01*
G01X148300Y2008500D02*
Y2016500D01*
X150300D01*
X151100Y2016100D01*
X151700Y2015567D01*
X152200Y2014767D01*
X152600Y2013833D01*
X152700Y2012500D01*
X152600Y2011167D01*
X152200Y2010233D01*
X151700Y2009433D01*
X151100Y2008900D01*
X150300Y2008500D01*
X148300D01*
G01X160500D02*
X156500D01*
Y2016500D01*
X160500D01*
G01X158900Y2012633D02*
X156500D01*
G01X175300Y2012767D02*
X175700Y2013167D01*
X176000Y2013833D01*
X176200Y2014767D01*
X176000Y2015567D01*
X175600Y2016100D01*
X174900Y2016500D01*
X172200D01*
Y2008500D01*
X175500D01*
X176200Y2009033D01*
X176600Y2009833D01*
X176800Y2010767D01*
X176600Y2011700D01*
X176000Y2012500D01*
X175300Y2012767D01*
X172200D01*
G01X182500Y2008500D02*
Y2012100D01*
X180500Y2016500D01*
G01X184500D02*
X182500Y2012100D01*
G01X196300Y2008500D02*
Y2016500D01*
X198300D01*
X199100Y2016100D01*
X199700Y2015567D01*
X200200Y2014767D01*
X200600Y2013833D01*
X200700Y2012500D01*
X200600Y2011167D01*
X200200Y2010233D01*
X199700Y2009433D01*
X199100Y2008900D01*
X198300Y2008500D01*
X196300D01*
G01X204500D02*
Y2016500D01*
X207000D01*
X207800Y2016100D01*
X208300Y2015567D01*
X208500Y2014500D01*
X208300Y2013433D01*
X207700Y2012767D01*
X207000Y2012367D01*
X204500D01*
G01X207000D02*
X208500Y2008500D01*
G01X213300Y2016500D02*
X215700D01*
G01X214500D02*
Y2008500D01*
G01X213300D02*
X215700D01*
G01X220500Y2016500D02*
Y2008500D01*
X224500D01*
G01X228500Y2016500D02*
Y2008500D01*
X232500D01*
G01X237300Y2016500D02*
X239700D01*
G01X238500D02*
Y2008500D01*
G01X237300D02*
X239700D01*
G01X244200D02*
Y2016500D01*
X248800Y2008500D01*
Y2016500D01*
G01X255100Y2012500D02*
X257100D01*
Y2010100D01*
X256500Y2009300D01*
X255800Y2008767D01*
X254800Y2008500D01*
X253800Y2008767D01*
X253100Y2009300D01*
X252500Y2010100D01*
X252100Y2011033D01*
X251900Y2012100D01*
Y2013033D01*
X252100Y2013833D01*
X252500Y2014767D01*
X253100Y2015567D01*
X253700Y2016100D01*
X254500Y2016500D01*
X255200D01*
X256000Y2016233D01*
X256600Y2015700D01*
G01X262300Y2007033D02*
X262700Y2008767D01*
G01X276200Y2008500D02*
Y2016500D01*
X280800Y2008500D01*
Y2016500D01*
G01X286500Y2008500D02*
X285700Y2008633D01*
X285000Y2009167D01*
X284400Y2009967D01*
X284000Y2010900D01*
X283800Y2011967D01*
Y2013033D01*
X284000Y2014100D01*
X284400Y2015033D01*
X285000Y2015833D01*
X285700Y2016367D01*
X286500Y2016500D01*
X287300Y2016367D01*
X288000Y2015833D01*
X288600Y2015033D01*
X289000Y2014100D01*
X289200Y2013033D01*
Y2011967D01*
X289000Y2010900D01*
X288600Y2009967D01*
X288000Y2009167D01*
X287300Y2008633D01*
X286500Y2008500D01*
G01X292200D02*
Y2016500D01*
X296800Y2008500D01*
Y2016500D01*
G01X301200Y2011167D02*
X303800D01*
G01X308600Y2008500D02*
Y2016500D01*
X312400D01*
G01X311000Y2012633D02*
X308600D01*
G01X316300Y2016500D02*
Y2010767D01*
X316700Y2009566D01*
X317500Y2008767D01*
X318500Y2008500D01*
X319500Y2008767D01*
X320300Y2009566D01*
X320700Y2010767D01*
Y2016500D01*
G01X324200Y2008500D02*
Y2016500D01*
X328800Y2008500D01*
Y2016500D01*
G01X336700Y2015833D02*
X336100Y2016233D01*
X335400Y2016500D01*
X334600D01*
X333700Y2016100D01*
X333000Y2015433D01*
X332500Y2014633D01*
X332100Y2013300D01*
X332000Y2012100D01*
X332200Y2010900D01*
X332500Y2010100D01*
X333100Y2009300D01*
X333800Y2008767D01*
X334500Y2008500D01*
X335200D01*
X335900Y2008767D01*
X336500Y2009167D01*
X337000Y2009700D01*
G01X342500Y2016500D02*
Y2008500D01*
G01X340200Y2016500D02*
X344800D01*
G01X349300D02*
X351700D01*
G01X350500D02*
Y2008500D01*
G01X349300D02*
X351700D01*
G01X358500D02*
X357700Y2008633D01*
X357000Y2009167D01*
X356400Y2009967D01*
X356000Y2010900D01*
X355800Y2011967D01*
Y2013033D01*
X356000Y2014100D01*
X356400Y2015033D01*
X357000Y2015833D01*
X357700Y2016367D01*
X358500Y2016500D01*
X359300Y2016367D01*
X360000Y2015833D01*
X360600Y2015033D01*
X361000Y2014100D01*
X361200Y2013033D01*
Y2011967D01*
X361000Y2010900D01*
X360600Y2009967D01*
X360000Y2009167D01*
X359300Y2008633D01*
X358500Y2008500D01*
G01X364200D02*
Y2016500D01*
X368800Y2008500D01*
Y2016500D01*
G01X372000Y2008500D02*
X374500Y2016500D01*
X377000Y2008500D01*
G01X376100Y2011300D02*
X372900D01*
G01X380500Y2016500D02*
Y2008500D01*
X384500D01*
G01X396500D02*
Y2016500D01*
X398900D01*
X399700Y2016100D01*
X400300Y2015167D01*
X400500Y2014100D01*
X400300Y2013033D01*
X399800Y2012233D01*
X398900Y2011833D01*
X396500D01*
G01X404000Y2008500D02*
X406500Y2016500D01*
X409000Y2008500D01*
G01X408100Y2011300D02*
X404900D01*
G01X412300Y2008500D02*
Y2016500D01*
X414300D01*
X415100Y2016100D01*
X415700Y2015567D01*
X416200Y2014767D01*
X416600Y2013833D01*
X416700Y2012500D01*
X416600Y2011167D01*
X416200Y2010233D01*
X415700Y2009433D01*
X415100Y2008900D01*
X414300Y2008500D01*
X412300D01*
G01X428400Y2009566D02*
X429200Y2008900D01*
X430100Y2008500D01*
X430900D01*
X431700Y2008900D01*
X432300Y2009566D01*
X432600Y2010500D01*
X432400Y2011433D01*
X431900Y2012233D01*
X431000Y2012767D01*
X429800Y2013033D01*
X429100Y2013567D01*
X428800Y2014500D01*
X429000Y2015433D01*
X429500Y2016100D01*
X430200Y2016500D01*
X430900D01*
X431600Y2016233D01*
X432200Y2015567D01*
G01X437300Y2016500D02*
X439700D01*
G01X438500D02*
Y2008500D01*
G01X437300D02*
X439700D01*
G01X444600Y2016500D02*
X448400D01*
X444600Y2008500D01*
X448400D01*
G01X456500D02*
X452500D01*
Y2016500D01*
X456500D01*
G01X454900Y2012633D02*
X452500D01*
G01X469300Y2016500D02*
X471700D01*
G01X470500D02*
Y2008500D01*
G01X469300D02*
X471700D01*
G01X476400Y2009566D02*
X477200Y2008900D01*
X478100Y2008500D01*
X478900D01*
X479700Y2008900D01*
X480300Y2009566D01*
X480600Y2010500D01*
X480400Y2011433D01*
X479900Y2012233D01*
X479000Y2012767D01*
X477800Y2013033D01*
X477100Y2013567D01*
X476800Y2014500D01*
X477000Y2015433D01*
X477500Y2016100D01*
X478200Y2016500D01*
X478900D01*
X479600Y2016233D01*
X480200Y2015567D01*
G01X494500Y2016500D02*
Y2008500D01*
G01X492200Y2016500D02*
X496800D01*
G01X500400Y2008500D02*
Y2016500D01*
G01X504600D02*
Y2008500D01*
G01Y2012500D02*
X500400D01*
G01X512500Y2008500D02*
X508500D01*
Y2016500D01*
X512500D01*
G01X510900Y2012633D02*
X508500D01*
G01X524300Y2008500D02*
Y2016500D01*
X526300D01*
X527100Y2016100D01*
X527700Y2015567D01*
X528200Y2014767D01*
X528600Y2013833D01*
X528700Y2012500D01*
X528600Y2011167D01*
X528200Y2010233D01*
X527700Y2009433D01*
X527100Y2008900D01*
X526300Y2008500D01*
X524300D01*
G01X532500D02*
Y2016500D01*
X535000D01*
X535800Y2016100D01*
X536300Y2015567D01*
X536500Y2014500D01*
X536300Y2013433D01*
X535700Y2012767D01*
X535000Y2012367D01*
X532500D01*
G01X535000D02*
X536500Y2008500D01*
G01X541300Y2016500D02*
X543700D01*
G01X542500D02*
Y2008500D01*
G01X541300D02*
X543700D01*
G01X548500Y2016500D02*
Y2008500D01*
X552500D01*
G01X556500Y2016500D02*
Y2008500D01*
X560500D01*
G01X572400Y2009566D02*
X573200Y2008900D01*
X574100Y2008500D01*
X574900D01*
X575700Y2008900D01*
X576300Y2009566D01*
X576600Y2010500D01*
X576400Y2011433D01*
X575900Y2012233D01*
X575000Y2012767D01*
X573800Y2013033D01*
X573100Y2013567D01*
X572800Y2014500D01*
X573000Y2015433D01*
X573500Y2016100D01*
X574200Y2016500D01*
X574900D01*
X575600Y2016233D01*
X576200Y2015567D01*
G01X581300Y2016500D02*
X583700D01*
G01X582500D02*
Y2008500D01*
G01X581300D02*
X583700D01*
G01X588600Y2016500D02*
X592400D01*
X588600Y2008500D01*
X592400D01*
G01X600500D02*
X596500D01*
Y2016500D01*
X600500D01*
G01X598900Y2012633D02*
X596500D01*
G01X613400Y2011167D02*
X615800D01*
G01X614500Y2012900D02*
Y2009433D01*
G01X630500Y2008500D02*
Y2016500D01*
X629300Y2014900D01*
G01Y2008500D02*
X631700D01*
G01X638500Y2016500D02*
X637700Y2016233D01*
X637100Y2015567D01*
X636700Y2014767D01*
X636400Y2013700D01*
X636300Y2012500D01*
X636400Y2011300D01*
X636700Y2010233D01*
X637100Y2009433D01*
X637700Y2008767D01*
X638500Y2008500D01*
X639300Y2008767D01*
X639900Y2009433D01*
X640300Y2010233D01*
X640600Y2011300D01*
X640700Y2012500D01*
X640600Y2013700D01*
X640300Y2014767D01*
X639900Y2015567D01*
X639300Y2016233D01*
X638500Y2016500D01*
G01X643900Y2008500D02*
Y2016500D01*
X646500Y2009833D01*
X649100Y2016500D01*
Y2008500D01*
G01X653300Y2016500D02*
X655700D01*
G01X654500D02*
Y2008500D01*
G01X653300D02*
X655700D01*
G01X660500Y2016500D02*
Y2008500D01*
X664500D01*
G01X-7874Y54252D02*
Y0D01*
X-77874D01*
Y54252D01*
X-7874D01*
G01X-38504Y659055D02*
Y600000D01*
X-77874D01*
Y659055D01*
X-38504D01*
G01X-45054Y658217D02*
X-41954D01*
Y657297D01*
X-42109Y656990D01*
X-42471Y656760D01*
X-42884Y656683D01*
X-43297Y656760D01*
X-43607Y656952D01*
X-43762Y657297D01*
Y658217D01*
G01X-42212Y653507D02*
X-42057Y653737D01*
X-41954Y654005D01*
Y654312D01*
X-42109Y654657D01*
X-42367Y654925D01*
X-42677Y655117D01*
X-43194Y655270D01*
X-43659Y655308D01*
X-44124Y655232D01*
X-44434Y655117D01*
X-44744Y654887D01*
X-44951Y654618D01*
X-45054Y654350D01*
Y654082D01*
X-44951Y653813D01*
X-44796Y653583D01*
X-44589Y653392D01*
G01X-43401Y650943D02*
X-43246Y650790D01*
X-42987Y650675D01*
X-42626Y650598D01*
X-42316Y650675D01*
X-42109Y650828D01*
X-41954Y651097D01*
Y652132D01*
X-45054D01*
Y650867D01*
X-44847Y650598D01*
X-44537Y650445D01*
X-44176Y650368D01*
X-43814Y650445D01*
X-43504Y650675D01*
X-43401Y650943D01*
Y652132D01*
G01X-41954Y646008D02*
X-45054Y645050D01*
X-41954Y644092D01*
G01X-45054Y641183D02*
Y642717D01*
X-41954D01*
Y641183D01*
G01X-43452Y641797D02*
Y642717D01*
G01X-45054Y639732D02*
X-41954D01*
X-45054Y637968D01*
X-41954D01*
G01X-45054Y636593D02*
X-41954D01*
Y635827D01*
X-42109Y635520D01*
X-42316Y635290D01*
X-42626Y635098D01*
X-42987Y634945D01*
X-43504Y634907D01*
X-44021Y634945D01*
X-44382Y635098D01*
X-44692Y635290D01*
X-44899Y635520D01*
X-45054Y635827D01*
Y636593D01*
G01Y632650D02*
X-45002Y632957D01*
X-44796Y633225D01*
X-44486Y633455D01*
X-44124Y633608D01*
X-43711Y633685D01*
X-43297D01*
X-42884Y633608D01*
X-42522Y633455D01*
X-42212Y633225D01*
X-42006Y632957D01*
X-41954Y632650D01*
X-42006Y632343D01*
X-42212Y632075D01*
X-42522Y631845D01*
X-42884Y631692D01*
X-43297Y631615D01*
X-43711D01*
X-44124Y631692D01*
X-44486Y631845D01*
X-44796Y632075D01*
X-45002Y632343D01*
X-45054Y632650D01*
G01Y630317D02*
X-41954D01*
Y629358D01*
X-42109Y629052D01*
X-42316Y628860D01*
X-42729Y628783D01*
X-43142Y628860D01*
X-43401Y629090D01*
X-43556Y629358D01*
Y630317D01*
G01Y629358D02*
X-45054Y628783D01*
G01X-46954Y650917D02*
X-50054D01*
Y649383D01*
G01Y647050D02*
X-50002Y647357D01*
X-49796Y647625D01*
X-49486Y647855D01*
X-49124Y648008D01*
X-48711Y648085D01*
X-48297D01*
X-47884Y648008D01*
X-47522Y647855D01*
X-47212Y647625D01*
X-47006Y647357D01*
X-46954Y647050D01*
X-47006Y646743D01*
X-47212Y646475D01*
X-47522Y646245D01*
X-47884Y646092D01*
X-48297Y646015D01*
X-48711D01*
X-49124Y646092D01*
X-49486Y646245D01*
X-49796Y646475D01*
X-50002Y646743D01*
X-50054Y647050D01*
G01X-48504Y643720D02*
Y642953D01*
X-49434D01*
X-49744Y643183D01*
X-49951Y643452D01*
X-50054Y643835D01*
X-49951Y644218D01*
X-49744Y644487D01*
X-49434Y644717D01*
X-49072Y644870D01*
X-48659Y644947D01*
X-48297D01*
X-47987Y644870D01*
X-47626Y644717D01*
X-47316Y644487D01*
X-47109Y644257D01*
X-46954Y643950D01*
Y643682D01*
X-47057Y643375D01*
X-47264Y643145D01*
G01X-50054Y640850D02*
X-50002Y641157D01*
X-49796Y641425D01*
X-49486Y641655D01*
X-49124Y641808D01*
X-48711Y641885D01*
X-48297D01*
X-47884Y641808D01*
X-47522Y641655D01*
X-47212Y641425D01*
X-47006Y641157D01*
X-46954Y640850D01*
X-47006Y640543D01*
X-47212Y640275D01*
X-47522Y640045D01*
X-47884Y639892D01*
X-48297Y639815D01*
X-48711D01*
X-49124Y639892D01*
X-49486Y640045D01*
X-49796Y640275D01*
X-50002Y640543D01*
X-50054Y640850D01*
G01X-39036Y1750315D02*
G03I-2953J0D01*
G01Y1770000D02*
G03I-2953J0D01*
G01X-44941Y1812322D02*
X529862D01*
G01X-44941Y1828070D02*
Y1812322D01*
G01Y1832007D02*
X529862D01*
G01Y1828070D02*
X-44941D01*
G01Y1847756D02*
Y1832007D01*
G01X529862Y1847756D02*
X-44941D01*
G01Y1851693D02*
Y1922559D01*
G01Y1914685D02*
X250334D01*
G01X100772Y1287047D02*
X-15512D01*
G01X-32787Y1268297D02*
X-28137D01*
Y1280797D01*
X-32787D01*
G01X334Y1680433D02*
X-31162D01*
G01D02*
X10177D01*
G01X-19351Y1750315D02*
G03I-2953J0D01*
G01Y1770000D02*
G03I-2953J0D01*
G01X18750Y-50561D02*
Y-55211D01*
X6250D01*
Y-50561D01*
G01X18750Y-31961D02*
Y-27311D01*
X6250D01*
Y-31961D01*
G01X0Y-1000D02*
Y-17936D01*
G01X138740Y5906D02*
X144646Y0D01*
X187795D01*
G03X203543Y15748I0J15748D01*
G01Y1311024D01*
G03X187795Y1326772I-15748J0D01*
G01X15748D01*
G03X0Y1311024I0J-15748D01*
G01Y15748D01*
G03X15748Y0I15748J0D01*
G01X58898D01*
X64803Y5906D01*
Y43307D01*
G02X74252I4724J0D01*
G01Y7283D01*
X80157Y1378D01*
X99488D01*
X105394Y7283D01*
Y43307D01*
G02X108150I1378J0D01*
G01Y7283D01*
X114055Y1378D01*
X123386D01*
X129291Y7283D01*
Y43307D01*
G02X138740I4724J0D01*
G01Y5906D01*
G01X0Y1298209D02*
Y1522000D01*
G01X5000D02*
X0Y1521000D01*
X5000Y1520000D01*
Y1522000D01*
G01X53275Y1521000D02*
X0D01*
G01X-7310Y1661675D02*
X-6380Y1660633D01*
X-5295Y1660008D01*
X-3900Y1659800D01*
X-2505Y1660217D01*
X-1420Y1661050D01*
X-645Y1662508D01*
X-490Y1664175D01*
X-800Y1665842D01*
X-1575Y1666883D01*
X-2660Y1667717D01*
X-3745Y1667925D01*
X-4830Y1667717D01*
X-6225Y1666883D01*
X-5760Y1672300D01*
X-1575D01*
G01X4470Y1659800D02*
Y1672300D01*
X8500Y1661883D01*
X12530Y1672300D01*
Y1659800D01*
G01X16870D02*
Y1672300D01*
X20900Y1661883D01*
X24930Y1672300D01*
Y1659800D01*
G01X334Y1742813D02*
Y1672559D01*
G01Y1750315D02*
G03I-2952J0D01*
G01Y1770000D02*
G03I-2952J0D01*
G01X27362Y41378D02*
G02X33268I2953J0D01*
G02X27362I-2953J0D01*
G01Y404764D02*
G02X33268I2953J0D01*
G02X27362I-2953J0D01*
G01X32860Y621444D02*
X18483Y638513D01*
G01X31076Y625090D02*
X32860Y621444D01*
X29571Y623822D01*
X31076Y625090D01*
G01X27362Y768150D02*
G02X33268I2953J0D01*
G02X27362I-2953J0D01*
G01Y1131535D02*
G02X33268I2953J0D01*
G02X27362I-2953J0D01*
G01X51515Y1652874D02*
X20019D01*
G01D02*
X61358D01*
G01X20019Y1743163D02*
Y1672559D01*
G01Y1680433D02*
X51515D01*
G01D02*
X10177D01*
G01X25925Y1747362D02*
X20019D01*
G01X25925Y1753267D02*
Y1747362D01*
G01X20019D02*
Y1753267D01*
G01X25925Y1767047D02*
X20019D01*
G01Y1753267D02*
X25925D01*
G01Y1772952D02*
Y1767047D01*
G01X20019D02*
Y1772952D01*
G01D02*
X25925D01*
G01X61250Y-220922D02*
Y-225572D01*
X48750D01*
Y-220922D01*
G01X61250Y-152722D02*
Y-148072D01*
X48750D01*
Y-152722D01*
G01X32908Y574289D02*
X36832Y621205D01*
G02X48601I5885J-492D01*
G01X52525Y574289D01*
G02X32908I-9808J-820D01*
G01X52504Y574514D02*
G02X32930I-9787J-1045D01*
G01D02*
X36589Y608787D01*
G01X48845D02*
X52504Y574514D01*
G01X36811Y612966D02*
Y620713D01*
G01X36589Y608787D02*
G03X36811Y612966I-39154J4175D01*
G01X48623D02*
G03X48845Y608787I39376J-4D01*
G01X48623Y620713D02*
Y612966D01*
G01X36811Y620713D02*
G02X48623I5906J0D01*
G01X42717Y621713D02*
Y1339435D01*
G01X43717Y620713D02*
X236075D01*
G01X61467Y1353460D02*
Y1348810D01*
X48967D01*
Y1353460D01*
G01X61467Y1421660D02*
Y1426310D01*
X48967D01*
Y1421660D01*
G01X45690Y1630275D02*
X46620Y1629233D01*
X47705Y1628608D01*
X49100Y1628400D01*
X50495Y1628817D01*
X51580Y1629650D01*
X52355Y1631108D01*
X52510Y1632775D01*
X52200Y1634442D01*
X51425Y1635483D01*
X50340Y1636317D01*
X49255Y1636525D01*
X48170Y1636317D01*
X46775Y1635483D01*
X47240Y1640900D01*
X51425D01*
G01X57470Y1628400D02*
Y1640900D01*
X61500Y1630483D01*
X65530Y1640900D01*
Y1628400D01*
G01X69870D02*
Y1640900D01*
X73900Y1630483D01*
X77930Y1640900D01*
Y1628400D01*
G01X51515Y1743425D02*
Y1645000D01*
G01X71200Y1704575D02*
X39704D01*
G01D02*
X74153D01*
G01X51515Y1747362D02*
X45610D01*
G01X51515Y1753267D02*
Y1747362D01*
G01X45610D02*
Y1753267D01*
G01X51515Y1767047D02*
X45610D01*
G01Y1753267D02*
X51515D01*
G01Y1772952D02*
Y1767047D01*
G01X45610D02*
Y1772952D01*
G01D02*
X51515D01*
G01X87250Y-220922D02*
Y-225572D01*
X74750D01*
Y-220922D01*
G01X87250Y-152722D02*
Y-148072D01*
X74750D01*
Y-152722D01*
G01X82992Y16126D02*
Y-82622D01*
X56000D01*
Y-138622D01*
X55999Y-138697D01*
G01X77050Y1502250D02*
X72400D01*
Y1514750D01*
X77050D01*
G01X71200Y1743425D02*
Y1645000D01*
G01Y1652874D02*
X102696D01*
G01D02*
X61358D01*
G01X77106Y1742740D02*
Y1696701D01*
G01X71200Y1739241D02*
Y1696701D01*
G01X77106Y1704575D02*
X143632D01*
G01D02*
X74153D01*
G01X77106Y1747362D02*
X71200D01*
G01X77106Y1753267D02*
Y1747362D01*
G01X71200D02*
Y1753267D01*
G01X77106Y1767047D02*
X71200D01*
G01Y1753267D02*
X77106D01*
G01Y1772952D02*
Y1767047D01*
G01X71200D02*
Y1772952D01*
G01D02*
X77106D01*
G01X113022Y-222100D02*
Y-226750D01*
X100522D01*
Y-222100D01*
G01X113022Y-153900D02*
Y-149250D01*
X100522D01*
Y-153900D01*
G01X97992Y16126D02*
Y-106622D01*
X81000D01*
Y-138697D01*
G01X99402Y17126D02*
G03I-1410J0D01*
G01X84402D02*
G03I-1410J0D01*
G01X91929Y157126D02*
X95886Y204858D01*
G02X107657I5886J-488D01*
G01X111614Y157126D01*
G02X91929I-9842J0D01*
G01X111559Y158171D02*
G02X91985I-9787J-1045D01*
G01D02*
X95644Y192444D01*
G01X95866Y196623D02*
Y204370D01*
G01X95644Y192444D02*
G03X95866Y196623I-39154J4175D01*
G01Y204370D02*
G02X107678I5906J0D01*
G01X82804Y231110D02*
Y290165D01*
X114300D01*
Y231110D01*
X82804D01*
G01X91929Y905157D02*
X95886Y952889D01*
G02X107657I5886J-488D01*
G01X111614Y905157D01*
G02X91929I-9842J0D01*
G01X91985Y906202D02*
X95644Y940475D01*
G01X111559Y906202D02*
G02X91985I-9787J-1045D01*
G01X95644Y940475D02*
G03X95866Y944654I-39154J4175D01*
G01Y952401D02*
G02X107678I5906J0D01*
G01X95866Y944654D02*
Y952401D01*
G01X89173Y1287047D02*
G02X114370I12599J0D01*
G02X89173I-12599J0D01*
G01X101115Y1707528D02*
Y1720028D01*
X99255Y1717528D01*
G01Y1707528D02*
X102975D01*
G01X113515Y1707111D02*
X113205Y1707320D01*
Y1707736D01*
X113515Y1707945D01*
X113825Y1707736D01*
Y1707320D01*
X113515Y1707111D01*
G01X122505Y1709403D02*
X123435Y1708361D01*
X124520Y1707736D01*
X125915Y1707528D01*
X127310Y1707945D01*
X128395Y1708778D01*
X129170Y1710236D01*
X129325Y1711903D01*
X129015Y1713570D01*
X128240Y1714611D01*
X127155Y1715445D01*
X126070Y1715653D01*
X124985Y1715445D01*
X123590Y1714611D01*
X124055Y1720028D01*
X128240D01*
G01X134285Y1707528D02*
Y1720028D01*
X138315Y1709611D01*
X142345Y1720028D01*
Y1707528D01*
G01X146685D02*
Y1720028D01*
X150715Y1709611D01*
X154745Y1720028D01*
Y1707528D01*
G01X81043Y1767047D02*
X200773D01*
G01X81043Y1772952D02*
X200773D01*
G01X106772Y40929D02*
Y-139875D01*
G01X116772Y18685D02*
Y-106622D01*
X135000D01*
Y-138622D01*
G01X118182Y19685D02*
G03I-1410J0D01*
G01X107900Y192444D02*
X111559Y158171D01*
G01X107678Y196623D02*
G03X107900Y192444I39376J-4D01*
G01X107678Y204370D02*
Y196623D01*
G01X103195Y210101D02*
X117572Y227170D01*
G01X104979Y213747D02*
X103195Y210101D01*
X106484Y212479D01*
X104979Y213747D01*
G01X102772Y204370D02*
X220615D01*
G01X101772Y205370D02*
Y1337905D01*
G01X107900Y940475D02*
X111559Y906202D01*
G01X107678Y944654D02*
G03X107900Y940475I39376J-4D01*
G01X103195Y958132D02*
X117572Y975201D01*
G01X104979Y961778D02*
X103195Y958132D01*
X106484Y960510D01*
X104979Y961778D01*
G01X107678Y952401D02*
Y944654D01*
G01X102772Y952401D02*
X225775D01*
G01X120522Y1355480D02*
Y1350830D01*
X108022D01*
Y1355480D01*
G01X120522Y1423680D02*
Y1428330D01*
X108022D01*
Y1423680D01*
G01X140250Y-219722D02*
Y-224372D01*
X127750D01*
Y-219722D01*
G01X140250Y-151522D02*
Y-146872D01*
X127750D01*
Y-151522D01*
G01X143324Y1326772D02*
X392600D01*
G01X132850Y1502250D02*
X137500D01*
Y1514750D01*
X132850D01*
G01X130400Y2324566D02*
X131200Y2323900D01*
X132100Y2323500D01*
X132900D01*
X133700Y2323900D01*
X134300Y2324566D01*
X134600Y2325500D01*
X134400Y2326433D01*
X133900Y2327233D01*
X133000Y2327767D01*
X131800Y2328033D01*
X131100Y2328567D01*
X130800Y2329500D01*
X131000Y2330433D01*
X131500Y2331100D01*
X132200Y2331500D01*
X132900D01*
X133600Y2331233D01*
X134200Y2330567D01*
G01X140500Y2323500D02*
X139700Y2323633D01*
X139000Y2324167D01*
X138400Y2324967D01*
X138000Y2325900D01*
X137800Y2326967D01*
Y2328033D01*
X138000Y2329100D01*
X138400Y2330033D01*
X139000Y2330833D01*
X139700Y2331367D01*
X140500Y2331500D01*
X141300Y2331367D01*
X142000Y2330833D01*
X142600Y2330033D01*
X143000Y2329100D01*
X143200Y2328033D01*
Y2326967D01*
X143000Y2325900D01*
X142600Y2324967D01*
X142000Y2324167D01*
X141300Y2323633D01*
X140500Y2323500D01*
G01X146500Y2331500D02*
Y2323500D01*
X150500D01*
G01X154300D02*
Y2331500D01*
X156300D01*
X157100Y2331100D01*
X157700Y2330567D01*
X158200Y2329767D01*
X158600Y2328833D01*
X158700Y2327500D01*
X158600Y2326167D01*
X158200Y2325233D01*
X157700Y2324433D01*
X157100Y2323900D01*
X156300Y2323500D01*
X154300D01*
G01X166500D02*
X162500D01*
Y2331500D01*
X166500D01*
G01X164900Y2327633D02*
X162500D01*
G01X170500Y2323500D02*
Y2331500D01*
X173000D01*
X173800Y2331100D01*
X174300Y2330567D01*
X174500Y2329500D01*
X174300Y2328433D01*
X173700Y2327767D01*
X173000Y2327367D01*
X170500D01*
G01X173000D02*
X174500Y2323500D01*
G01X177900D02*
Y2331500D01*
X180500Y2324833D01*
X183100Y2331500D01*
Y2323500D01*
G01X186000D02*
X188500Y2331500D01*
X191000Y2323500D01*
G01X190100Y2326300D02*
X186900D01*
G01X194400Y2324566D02*
X195200Y2323900D01*
X196100Y2323500D01*
X196900D01*
X197700Y2323900D01*
X198300Y2324566D01*
X198600Y2325500D01*
X198400Y2326433D01*
X197900Y2327233D01*
X197000Y2327767D01*
X195800Y2328033D01*
X195100Y2328567D01*
X194800Y2329500D01*
X195000Y2330433D01*
X195500Y2331100D01*
X196200Y2331500D01*
X196900D01*
X197600Y2331233D01*
X198200Y2330567D01*
G01X202300Y2323500D02*
Y2331500D01*
G01X206100D02*
X202300Y2326566D01*
G01X206700Y2323500D02*
X204000Y2328833D01*
G01X220500Y2323500D02*
X219700Y2323633D01*
X219000Y2324167D01*
X218400Y2324967D01*
X218000Y2325900D01*
X217800Y2326967D01*
Y2328033D01*
X218000Y2329100D01*
X218400Y2330033D01*
X219000Y2330833D01*
X219700Y2331367D01*
X220500Y2331500D01*
X221300Y2331367D01*
X222000Y2330833D01*
X222600Y2330033D01*
X223000Y2329100D01*
X223200Y2328033D01*
Y2326967D01*
X223000Y2325900D01*
X222600Y2324967D01*
X222000Y2324167D01*
X221300Y2323633D01*
X220500Y2323500D01*
G01X226500D02*
Y2331500D01*
X228900D01*
X229700Y2331100D01*
X230300Y2330167D01*
X230500Y2329100D01*
X230300Y2328033D01*
X229800Y2327233D01*
X228900Y2326833D01*
X226500D01*
G01X238500Y2323500D02*
X234500D01*
Y2331500D01*
X238500D01*
G01X236900Y2327633D02*
X234500D01*
G01X242200Y2323500D02*
Y2331500D01*
X246800Y2323500D01*
Y2331500D01*
G01X260500Y2323500D02*
X259700Y2323633D01*
X259000Y2324167D01*
X258400Y2324967D01*
X258000Y2325900D01*
X257800Y2326967D01*
Y2328033D01*
X258000Y2329100D01*
X258400Y2330033D01*
X259000Y2330833D01*
X259700Y2331367D01*
X260500Y2331500D01*
X261300Y2331367D01*
X262000Y2330833D01*
X262600Y2330033D01*
X263000Y2329100D01*
X263200Y2328033D01*
Y2326967D01*
X263000Y2325900D01*
X262600Y2324967D01*
X262000Y2324167D01*
X261300Y2323633D01*
X260500Y2323500D01*
G01X266200D02*
Y2331500D01*
X270800Y2323500D01*
Y2331500D01*
G01X285300Y2327767D02*
X285700Y2328167D01*
X286000Y2328833D01*
X286200Y2329767D01*
X286000Y2330567D01*
X285600Y2331100D01*
X284900Y2331500D01*
X282200D01*
Y2323500D01*
X285500D01*
X286200Y2324033D01*
X286600Y2324833D01*
X286800Y2325767D01*
X286600Y2326700D01*
X286000Y2327500D01*
X285300Y2327767D01*
X282200D01*
G01X292500Y2323500D02*
X291700Y2323633D01*
X291000Y2324167D01*
X290400Y2324967D01*
X290000Y2325900D01*
X289800Y2326967D01*
Y2328033D01*
X290000Y2329100D01*
X290400Y2330033D01*
X291000Y2330833D01*
X291700Y2331367D01*
X292500Y2331500D01*
X293300Y2331367D01*
X294000Y2330833D01*
X294600Y2330033D01*
X295000Y2329100D01*
X295200Y2328033D01*
Y2326967D01*
X295000Y2325900D01*
X294600Y2324967D01*
X294000Y2324167D01*
X293300Y2323633D01*
X292500Y2323500D01*
G01X300500Y2331500D02*
Y2323500D01*
G01X298200Y2331500D02*
X302800D01*
G01X306400Y2323500D02*
Y2331500D01*
G01X310600D02*
Y2323500D01*
G01Y2327500D02*
X306400D01*
G01X322400Y2324566D02*
X323200Y2323900D01*
X324100Y2323500D01*
X324900D01*
X325700Y2323900D01*
X326300Y2324566D01*
X326600Y2325500D01*
X326400Y2326433D01*
X325900Y2327233D01*
X325000Y2327767D01*
X323800Y2328033D01*
X323100Y2328567D01*
X322800Y2329500D01*
X323000Y2330433D01*
X323500Y2331100D01*
X324200Y2331500D01*
X324900D01*
X325600Y2331233D01*
X326200Y2330567D01*
G01X331300Y2331500D02*
X333700D01*
G01X332500D02*
Y2323500D01*
G01X331300D02*
X333700D01*
G01X338300D02*
Y2331500D01*
X340300D01*
X341100Y2331100D01*
X341700Y2330567D01*
X342200Y2329767D01*
X342600Y2328833D01*
X342700Y2327500D01*
X342600Y2326167D01*
X342200Y2325233D01*
X341700Y2324433D01*
X341100Y2323900D01*
X340300Y2323500D01*
X338300D01*
G01X350500D02*
X346500D01*
Y2331500D01*
X350500D01*
G01X348900Y2327633D02*
X346500D01*
G01X356500Y2323233D02*
X356300Y2323367D01*
Y2323633D01*
X356500Y2323767D01*
X356700Y2323633D01*
Y2323367D01*
X356500Y2323233D01*
G01X165007Y0D02*
X392600D01*
G01X151019Y574289D02*
X154942Y621205D01*
G02X166712I5885J-492D01*
G01X170635Y574289D01*
G02X151019I-9808J-820D01*
G01X170614Y574514D02*
G02X151040I-9787J-1045D01*
G01D02*
X154699Y608787D01*
G01X166955D02*
X170614Y574514D01*
G01X154921Y612966D02*
Y620713D01*
G01X154699Y608787D02*
G03X154921Y612966I-39154J4175D01*
G01X166733D02*
G03X166955Y608787I39376J-4D01*
G01X166733Y620713D02*
Y612966D01*
G01X162250Y626444D02*
X176627Y643513D01*
G01X164034Y630090D02*
X162250Y626444D01*
X165539Y628822D01*
X164034Y630090D01*
G01X154921Y620713D02*
G02X166733I5906J0D01*
G01X160827Y621713D02*
Y1341655D01*
G01X179577Y1359230D02*
Y1354580D01*
X167077D01*
Y1359230D01*
G01X179577Y1427430D02*
Y1432080D01*
X167077D01*
Y1427430D01*
G01X156325Y1521000D02*
X203543D01*
G01X170276Y111457D02*
G02X176181I2953J0D01*
G02X170276I-2952J0D01*
G01Y474843D02*
G02X176181I2953J0D01*
G02X170276I-2952J0D01*
G01Y838228D02*
G02X176181I2953J0D01*
G02X170276I-2952J0D01*
G01Y1201614D02*
G02X176181I2953J0D01*
G02X170276I-2952J0D01*
G01X184041Y1658239D02*
X171541D01*
X174041Y1656379D01*
G01X184041D02*
Y1660099D01*
G01X184458Y1670639D02*
X184249Y1670329D01*
X183833D01*
X183624Y1670639D01*
X183833Y1670949D01*
X184249D01*
X184458Y1670639D01*
G01X182166Y1679629D02*
X183208Y1680559D01*
X183833Y1681644D01*
X184041Y1683039D01*
X183624Y1684434D01*
X182791Y1685519D01*
X181333Y1686294D01*
X179666Y1686449D01*
X177999Y1686139D01*
X176958Y1685364D01*
X176124Y1684279D01*
X175916Y1683194D01*
X176124Y1682109D01*
X176958Y1680714D01*
X171541Y1681179D01*
Y1685364D01*
G01X184041Y1691409D02*
X171541D01*
X181958Y1695439D01*
X171541Y1699469D01*
X184041D01*
G01Y1703809D02*
X171541D01*
X181958Y1707839D01*
X171541Y1711869D01*
X184041D01*
G01X192899Y1767047D02*
Y1671228D01*
G01D02*
Y1770000D01*
G01Y1804448D02*
Y1770000D01*
G01Y1772952D02*
Y1804448D01*
G01X203543Y1280489D02*
Y1522000D01*
G01X198543Y1520000D02*
X203543Y1521000D01*
X198543Y1522000D01*
Y1520000D01*
G01X200734Y1917637D02*
Y1930137D01*
X198874Y1927637D01*
G01Y1917637D02*
X202594D01*
G01X213134Y1930137D02*
X211894Y1929720D01*
X210964Y1928679D01*
X210344Y1927429D01*
X209879Y1925762D01*
X209724Y1923887D01*
X209879Y1922012D01*
X210344Y1920345D01*
X210964Y1919095D01*
X211894Y1918054D01*
X213134Y1917637D01*
X214374Y1918054D01*
X215304Y1919095D01*
X215924Y1920345D01*
X216389Y1922012D01*
X216544Y1923887D01*
X216389Y1925762D01*
X215924Y1927429D01*
X215304Y1928679D01*
X214374Y1929720D01*
X213134Y1930137D01*
G01X225534D02*
X224294Y1929720D01*
X223364Y1928679D01*
X222744Y1927429D01*
X222279Y1925762D01*
X222124Y1923887D01*
X222279Y1922012D01*
X222744Y1920345D01*
X223364Y1919095D01*
X224294Y1918054D01*
X225534Y1917637D01*
X226774Y1918054D01*
X227704Y1919095D01*
X228324Y1920345D01*
X228789Y1922012D01*
X228944Y1923887D01*
X228789Y1925762D01*
X228324Y1927429D01*
X227704Y1928679D01*
X226774Y1929720D01*
X225534Y1930137D01*
G01X235919Y1921804D02*
X239949D01*
G01X250334Y1917637D02*
Y1930137D01*
X248474Y1927637D01*
G01Y1917637D02*
X252194D01*
G01X259324Y1919512D02*
X260254Y1918470D01*
X261339Y1917845D01*
X262734Y1917637D01*
X264129Y1918054D01*
X265214Y1918887D01*
X265989Y1920345D01*
X266144Y1922012D01*
X265834Y1923679D01*
X265059Y1924720D01*
X263974Y1925554D01*
X262889Y1925762D01*
X261804Y1925554D01*
X260409Y1924720D01*
X260874Y1930137D01*
X265059D01*
G01X275134D02*
X273894Y1929720D01*
X272964Y1928679D01*
X272344Y1927429D01*
X271879Y1925762D01*
X271724Y1923887D01*
X271879Y1922012D01*
X272344Y1920345D01*
X272964Y1919095D01*
X273894Y1918054D01*
X275134Y1917637D01*
X276374Y1918054D01*
X277304Y1919095D01*
X277924Y1920345D01*
X278389Y1922012D01*
X278544Y1923887D01*
X278389Y1925762D01*
X277924Y1927429D01*
X277304Y1928679D01*
X276374Y1929720D01*
X275134Y1930137D01*
G01X283504Y1917637D02*
Y1930137D01*
X287534Y1919720D01*
X291564Y1930137D01*
Y1917637D01*
G01X295904D02*
Y1930137D01*
X299934Y1919720D01*
X303964Y1930137D01*
Y1917637D01*
G01X238190Y185620D02*
X233540D01*
Y198120D01*
X238190D01*
G01X239800Y933651D02*
X235150D01*
Y946151D01*
X239800D01*
G01X250100Y601963D02*
X245450D01*
Y614463D01*
X250100D01*
G01X253500Y1760300D02*
X255500D01*
Y1757900D01*
X254900Y1757100D01*
X254200Y1756567D01*
X253200Y1756300D01*
X252200Y1756567D01*
X251500Y1757100D01*
X250900Y1757900D01*
X250500Y1758833D01*
X250300Y1759900D01*
Y1760833D01*
X250500Y1761633D01*
X250900Y1762567D01*
X251500Y1763367D01*
X252100Y1763900D01*
X252900Y1764300D01*
X253600D01*
X254400Y1764033D01*
X255000Y1763500D01*
G01X258900Y1756300D02*
Y1764300D01*
X261400D01*
X262200Y1763900D01*
X262700Y1763367D01*
X262900Y1762300D01*
X262700Y1761233D01*
X262100Y1760567D01*
X261400Y1760167D01*
X258900D01*
G01X261400D02*
X262900Y1756300D01*
G01X268900D02*
X268100Y1756433D01*
X267400Y1756967D01*
X266800Y1757767D01*
X266400Y1758700D01*
X266200Y1759767D01*
Y1760833D01*
X266400Y1761900D01*
X266800Y1762833D01*
X267400Y1763633D01*
X268100Y1764167D01*
X268900Y1764300D01*
X269700Y1764167D01*
X270400Y1763633D01*
X271000Y1762833D01*
X271400Y1761900D01*
X271600Y1760833D01*
Y1759767D01*
X271400Y1758700D01*
X271000Y1757767D01*
X270400Y1756967D01*
X269700Y1756433D01*
X268900Y1756300D01*
G01X274700Y1764300D02*
Y1758567D01*
X275100Y1757366D01*
X275900Y1756567D01*
X276900Y1756300D01*
X277900Y1756567D01*
X278700Y1757366D01*
X279100Y1758567D01*
Y1764300D01*
G01X282900Y1756300D02*
Y1764300D01*
X285300D01*
X286100Y1763900D01*
X286700Y1762967D01*
X286900Y1761900D01*
X286700Y1760833D01*
X286200Y1760033D01*
X285300Y1759633D01*
X282900D01*
G01X290800Y1757366D02*
X291600Y1756700D01*
X292500Y1756300D01*
X293300D01*
X294100Y1756700D01*
X294700Y1757366D01*
X295000Y1758300D01*
X294800Y1759233D01*
X294300Y1760033D01*
X293400Y1760567D01*
X292200Y1760833D01*
X291500Y1761367D01*
X291200Y1762300D01*
X291400Y1763233D01*
X291900Y1763900D01*
X292600Y1764300D01*
X293300D01*
X294000Y1764033D01*
X294600Y1763367D01*
G01X309700Y1760567D02*
X310100Y1760967D01*
X310400Y1761633D01*
X310600Y1762567D01*
X310400Y1763367D01*
X310000Y1763900D01*
X309300Y1764300D01*
X306600D01*
Y1756300D01*
X309900D01*
X310600Y1756833D01*
X311000Y1757633D01*
X311200Y1758567D01*
X311000Y1759500D01*
X310400Y1760300D01*
X309700Y1760567D01*
X306600D01*
G01X545610Y1914685D02*
X250334D01*
G01X306390Y185620D02*
X311040D01*
Y198120D01*
X306390D01*
G01X329322Y-314459D02*
Y-319459D01*
G01X327865Y-314459D02*
X330779D01*
G01X335689Y-319459D02*
X333155D01*
Y-314459D01*
X335689D01*
G01X334675Y-316876D02*
X333155D01*
G01X338255Y-314459D02*
Y-319459D01*
X340789D01*
G01X344622Y-319626D02*
X344495Y-319542D01*
Y-319376D01*
X344622Y-319292D01*
X344749Y-319376D01*
Y-319542D01*
X344622Y-319626D01*
G01Y-317376D02*
X344495Y-317292D01*
Y-317126D01*
X344622Y-317042D01*
X344749Y-317126D01*
Y-317292D01*
X344622Y-317376D01*
G01X349405Y-321126D02*
X348772Y-320292D01*
X348455Y-319459D01*
Y-316126D01*
X348772Y-315292D01*
X349405Y-314459D01*
G01X354822D02*
X354315Y-314626D01*
X353935Y-315042D01*
X353682Y-315542D01*
X353492Y-316209D01*
X353429Y-316959D01*
X353492Y-317709D01*
X353682Y-318376D01*
X353935Y-318876D01*
X354315Y-319292D01*
X354822Y-319459D01*
X355329Y-319292D01*
X355709Y-318876D01*
X355962Y-318376D01*
X356152Y-317709D01*
X356215Y-316959D01*
X356152Y-316209D01*
X355962Y-315542D01*
X355709Y-315042D01*
X355329Y-314626D01*
X354822Y-314459D01*
G01X358529Y-318459D02*
X358909Y-319042D01*
X359415Y-319376D01*
X359985Y-319459D01*
X360492Y-319376D01*
X360999Y-318959D01*
X361315Y-318459D01*
X361379Y-317959D01*
X361252Y-317376D01*
X360809Y-316959D01*
X360365Y-316792D01*
X359795D01*
G01X360365D02*
X360745Y-316542D01*
X361062Y-316126D01*
X361189Y-315626D01*
X361062Y-315126D01*
X360745Y-314709D01*
X360175Y-314459D01*
X359605Y-314542D01*
X359035Y-314876D01*
G01X365339Y-321126D02*
X365972Y-320292D01*
X366289Y-319459D01*
Y-316126D01*
X365972Y-315292D01*
X365339Y-314459D01*
G01X368729Y-318459D02*
X369109Y-319042D01*
X369615Y-319376D01*
X370185Y-319459D01*
X370692Y-319376D01*
X371199Y-318959D01*
X371515Y-318459D01*
X371579Y-317959D01*
X371452Y-317376D01*
X371009Y-316959D01*
X370565Y-316792D01*
X369995D01*
G01X370565D02*
X370945Y-316542D01*
X371262Y-316126D01*
X371389Y-315626D01*
X371262Y-315126D01*
X370945Y-314709D01*
X370375Y-314459D01*
X369805Y-314542D01*
X369235Y-314876D01*
G01X374019Y-315292D02*
X374399Y-314792D01*
X374842Y-314542D01*
X375349Y-314459D01*
X375982Y-314626D01*
X376425Y-315042D01*
X376552Y-315542D01*
X376489Y-316042D01*
X376235Y-316459D01*
X374969Y-317292D01*
X374399Y-317876D01*
X374019Y-318709D01*
X373892Y-319459D01*
X376552D01*
G01X380195D02*
X380322Y-318376D01*
X380512Y-317459D01*
X380765Y-316626D01*
X381082Y-315709D01*
X381589Y-314459D01*
X379055D01*
G01X384599Y-317792D02*
X386245D01*
G01X389319Y-315292D02*
X389699Y-314792D01*
X390142Y-314542D01*
X390649Y-314459D01*
X391282Y-314626D01*
X391725Y-315042D01*
X391852Y-315542D01*
X391789Y-316042D01*
X391535Y-316459D01*
X390269Y-317292D01*
X389699Y-317876D01*
X389319Y-318709D01*
X389192Y-319459D01*
X391852D01*
G01X394229Y-318459D02*
X394609Y-319042D01*
X395115Y-319376D01*
X395685Y-319459D01*
X396192Y-319376D01*
X396699Y-318959D01*
X397015Y-318459D01*
X397079Y-317959D01*
X396952Y-317376D01*
X396509Y-316959D01*
X396065Y-316792D01*
X395495D01*
G01X396065D02*
X396445Y-316542D01*
X396762Y-316126D01*
X396889Y-315626D01*
X396762Y-315126D01*
X396445Y-314709D01*
X395875Y-314459D01*
X395305Y-314542D01*
X394735Y-314876D01*
G01X401482Y-319459D02*
Y-314459D01*
X399139Y-318042D01*
X402305D01*
G01X404429Y-318709D02*
X404809Y-319126D01*
X405252Y-319376D01*
X405822Y-319459D01*
X406392Y-319292D01*
X406835Y-318959D01*
X407152Y-318376D01*
X407215Y-317709D01*
X407089Y-317042D01*
X406772Y-316626D01*
X406329Y-316292D01*
X405885Y-316209D01*
X405442Y-316292D01*
X404872Y-316626D01*
X405062Y-314459D01*
X406772D01*
G01X414819Y-319459D02*
Y-314459D01*
X417225D01*
G01X416339Y-316876D02*
X414819D01*
G01X419539Y-319459D02*
X421122Y-314459D01*
X422705Y-319459D01*
G01X422135Y-317709D02*
X420109D01*
G01X424892Y-319459D02*
X427552Y-314459D01*
G01X424892D02*
X427552Y-319459D01*
G01X431322Y-319626D02*
X431195Y-319542D01*
Y-319376D01*
X431322Y-319292D01*
X431449Y-319376D01*
Y-319542D01*
X431322Y-319626D01*
G01Y-317376D02*
X431195Y-317292D01*
Y-317126D01*
X431322Y-317042D01*
X431449Y-317126D01*
Y-317292D01*
X431322Y-317376D01*
G01X436105Y-321126D02*
X435472Y-320292D01*
X435155Y-319459D01*
Y-316126D01*
X435472Y-315292D01*
X436105Y-314459D01*
G01X441522D02*
X441015Y-314626D01*
X440635Y-315042D01*
X440382Y-315542D01*
X440192Y-316209D01*
X440129Y-316959D01*
X440192Y-317709D01*
X440382Y-318376D01*
X440635Y-318876D01*
X441015Y-319292D01*
X441522Y-319459D01*
X442029Y-319292D01*
X442409Y-318876D01*
X442662Y-318376D01*
X442852Y-317709D01*
X442915Y-316959D01*
X442852Y-316209D01*
X442662Y-315542D01*
X442409Y-315042D01*
X442029Y-314626D01*
X441522Y-314459D01*
G01X445229Y-318459D02*
X445609Y-319042D01*
X446115Y-319376D01*
X446685Y-319459D01*
X447192Y-319376D01*
X447699Y-318959D01*
X448015Y-318459D01*
X448079Y-317959D01*
X447952Y-317376D01*
X447509Y-316959D01*
X447065Y-316792D01*
X446495D01*
G01X447065D02*
X447445Y-316542D01*
X447762Y-316126D01*
X447889Y-315626D01*
X447762Y-315126D01*
X447445Y-314709D01*
X446875Y-314459D01*
X446305Y-314542D01*
X445735Y-314876D01*
G01X452039Y-321126D02*
X452672Y-320292D01*
X452989Y-319459D01*
Y-316126D01*
X452672Y-315292D01*
X452039Y-314459D01*
G01X455429Y-318459D02*
X455809Y-319042D01*
X456315Y-319376D01*
X456885Y-319459D01*
X457392Y-319376D01*
X457899Y-318959D01*
X458215Y-318459D01*
X458279Y-317959D01*
X458152Y-317376D01*
X457709Y-316959D01*
X457265Y-316792D01*
X456695D01*
G01X457265D02*
X457645Y-316542D01*
X457962Y-316126D01*
X458089Y-315626D01*
X457962Y-315126D01*
X457645Y-314709D01*
X457075Y-314459D01*
X456505Y-314542D01*
X455935Y-314876D01*
G01X460845Y-318876D02*
X461289Y-319292D01*
X461795Y-319459D01*
X462302Y-319292D01*
X462745Y-318792D01*
X463062Y-318042D01*
X463189Y-317292D01*
Y-316376D01*
X463062Y-315626D01*
X462745Y-314959D01*
X462365Y-314626D01*
X461922Y-314459D01*
X461415Y-314626D01*
X461035Y-314959D01*
X460782Y-315459D01*
X460655Y-316126D01*
X460782Y-316709D01*
X461099Y-317292D01*
X461479Y-317626D01*
X461922Y-317709D01*
X462429Y-317542D01*
X462809Y-317126D01*
X463189Y-316376D01*
G01X466895Y-319459D02*
X467022Y-318376D01*
X467212Y-317459D01*
X467465Y-316626D01*
X467782Y-315709D01*
X468289Y-314459D01*
X465755D01*
G01X471299Y-317792D02*
X472945D01*
G01X475829Y-318459D02*
X476209Y-319042D01*
X476715Y-319376D01*
X477285Y-319459D01*
X477792Y-319376D01*
X478299Y-318959D01*
X478615Y-318459D01*
X478679Y-317959D01*
X478552Y-317376D01*
X478109Y-316959D01*
X477665Y-316792D01*
X477095D01*
G01X477665D02*
X478045Y-316542D01*
X478362Y-316126D01*
X478489Y-315626D01*
X478362Y-315126D01*
X478045Y-314709D01*
X477475Y-314459D01*
X476905Y-314542D01*
X476335Y-314876D01*
G01X481119Y-317376D02*
X481562Y-316792D01*
X481942Y-316459D01*
X482449Y-316292D01*
X482892Y-316459D01*
X483209Y-316792D01*
X483462Y-317292D01*
X483525Y-317876D01*
X483462Y-318376D01*
X483209Y-318876D01*
X482829Y-319292D01*
X482385Y-319459D01*
X481879Y-319292D01*
X481435Y-318792D01*
X481182Y-318042D01*
X481119Y-317209D01*
X481245Y-316126D01*
X481435Y-315542D01*
X481752Y-314959D01*
X482195Y-314542D01*
X482639Y-314459D01*
X483082Y-314626D01*
X483399Y-315042D01*
G01X487422Y-319459D02*
Y-314459D01*
X486662Y-315459D01*
G01Y-319459D02*
X488182D01*
G01X493282D02*
Y-314459D01*
X490939Y-318042D01*
X494105D01*
G01X317322Y-249459D02*
Y-324459D01*
X817322D01*
Y-249459D01*
X317322D01*
G01X330700Y601963D02*
X335350D01*
Y614463D01*
X330700D01*
G01X320400Y933651D02*
X325050D01*
Y946151D01*
X320400D01*
G01X390600Y5000D02*
X391600Y0D01*
X392600Y5000D01*
X390600D01*
G01X391600Y571275D02*
Y0D01*
G01X410350Y607450D02*
Y602800D01*
X397850D01*
Y607450D01*
G01X410350Y650850D02*
Y655500D01*
X397850D01*
Y650850D01*
G01X391600Y686725D02*
Y1326772D01*
G01X392600Y1321772D02*
X391600Y1326772D01*
X390600Y1321772D01*
X392600D01*
G01X492960Y1893500D02*
Y1906000D01*
X487225Y1897042D01*
X494975D01*
G01X499470Y1893500D02*
Y1906000D01*
X503500Y1895583D01*
X507530Y1906000D01*
Y1893500D01*
G01X511870D02*
Y1906000D01*
X515900Y1895583D01*
X519930Y1906000D01*
Y1893500D01*
G01X512322Y-249459D02*
Y-324459D01*
G01Y-299459D02*
X615322D01*
Y-274459D01*
G01X512322D02*
X615322D01*
G01X529862Y1887126D02*
X498366D01*
G01D02*
X537736D01*
G01X529862Y1812322D02*
X545610Y1820196D01*
G01X581043Y1832007D02*
X537736D01*
G01X581043Y1828070D02*
X537736D01*
G01X545610Y1820196D02*
X529862Y1828070D01*
G01Y1832007D02*
X545610Y1839882D01*
G01X529862Y1851693D02*
Y1895000D01*
G01X545610Y1839882D02*
X529862Y1847756D01*
G01X577106Y1887126D02*
X537736D01*
G01X561662Y1788893D02*
Y1832200D01*
G01X545610Y1843818D02*
Y1895000D01*
G01Y1843818D02*
Y1922559D01*
G01Y1887126D02*
X577106D01*
G01X585600Y1794300D02*
X573100D01*
X575600Y1792440D01*
G01X585600D02*
Y1796160D01*
G01Y1802670D02*
X573100D01*
X583517Y1806700D01*
X573100Y1810730D01*
X585600D01*
G01Y1815070D02*
X573100D01*
X583517Y1819100D01*
X573100Y1823130D01*
X585600D01*
G01X605600Y1830100D02*
X607600D01*
Y1827700D01*
X607000Y1826900D01*
X606300Y1826367D01*
X605300Y1826100D01*
X604300Y1826367D01*
X603600Y1826900D01*
X603000Y1827700D01*
X602600Y1828633D01*
X602400Y1829700D01*
Y1830633D01*
X602600Y1831433D01*
X603000Y1832367D01*
X603600Y1833167D01*
X604200Y1833700D01*
X605000Y1834100D01*
X605700D01*
X606500Y1833833D01*
X607100Y1833300D01*
G01X611000Y1826100D02*
Y1834100D01*
X613500D01*
X614300Y1833700D01*
X614800Y1833167D01*
X615000Y1832100D01*
X614800Y1831033D01*
X614200Y1830367D01*
X613500Y1829967D01*
X611000D01*
G01X613500D02*
X615000Y1826100D01*
G01X621000D02*
X620200Y1826233D01*
X619500Y1826767D01*
X618900Y1827567D01*
X618500Y1828500D01*
X618300Y1829567D01*
Y1830633D01*
X618500Y1831700D01*
X618900Y1832633D01*
X619500Y1833433D01*
X620200Y1833967D01*
X621000Y1834100D01*
X621800Y1833967D01*
X622500Y1833433D01*
X623100Y1832633D01*
X623500Y1831700D01*
X623700Y1830633D01*
Y1829567D01*
X623500Y1828500D01*
X623100Y1827567D01*
X622500Y1826767D01*
X621800Y1826233D01*
X621000Y1826100D01*
G01X626800Y1834100D02*
Y1828367D01*
X627200Y1827166D01*
X628000Y1826367D01*
X629000Y1826100D01*
X630000Y1826367D01*
X630800Y1827166D01*
X631200Y1828367D01*
Y1834100D01*
G01X635000Y1826100D02*
Y1834100D01*
X637400D01*
X638200Y1833700D01*
X638800Y1832767D01*
X639000Y1831700D01*
X638800Y1830633D01*
X638300Y1829833D01*
X637400Y1829433D01*
X635000D01*
G01X642900Y1827166D02*
X643700Y1826500D01*
X644600Y1826100D01*
X645400D01*
X646200Y1826500D01*
X646800Y1827166D01*
X647100Y1828100D01*
X646900Y1829033D01*
X646400Y1829833D01*
X645500Y1830367D01*
X644300Y1830633D01*
X643600Y1831167D01*
X643300Y1832100D01*
X643500Y1833033D01*
X644000Y1833700D01*
X644700Y1834100D01*
X645400D01*
X646100Y1833833D01*
X646700Y1833167D01*
G01X658500Y1826100D02*
X661000Y1834100D01*
X663500Y1826100D01*
G01X662600Y1828900D02*
X659400D01*
G01X622829Y-309459D02*
Y-304459D01*
X624095D01*
X624602Y-304709D01*
X624982Y-305042D01*
X625299Y-305542D01*
X625552Y-306126D01*
X625615Y-306959D01*
X625552Y-307792D01*
X625299Y-308376D01*
X624982Y-308876D01*
X624602Y-309209D01*
X624095Y-309459D01*
X622829D01*
G01X627739D02*
X629322Y-304459D01*
X630905Y-309459D01*
G01X630335Y-307709D02*
X628309D01*
G01X634422Y-304459D02*
Y-309459D01*
G01X632965Y-304459D02*
X635879D01*
G01X640789Y-309459D02*
X638255D01*
Y-304459D01*
X640789D01*
G01X639775Y-306876D02*
X638255D01*
G01X644622Y-309626D02*
X644495Y-309542D01*
Y-309376D01*
X644622Y-309292D01*
X644749Y-309376D01*
Y-309542D01*
X644622Y-309626D01*
G01Y-307376D02*
X644495Y-307292D01*
Y-307126D01*
X644622Y-307042D01*
X644749Y-307126D01*
Y-307292D01*
X644622Y-307376D01*
G01X617322Y-249459D02*
Y-324459D01*
G01X615322Y-249459D02*
Y-324459D01*
G01X622955Y-284459D02*
Y-279459D01*
X624475D01*
X624982Y-279709D01*
X625362Y-280292D01*
X625489Y-280959D01*
X625362Y-281626D01*
X625045Y-282126D01*
X624475Y-282376D01*
X622955D01*
G01X628182Y-284626D02*
X630462Y-279459D01*
G01X632965Y-284459D02*
Y-279459D01*
X635879Y-284459D01*
Y-279459D01*
G01X639522Y-284626D02*
X639395Y-284542D01*
Y-284376D01*
X639522Y-284292D01*
X639649Y-284376D01*
Y-284542D01*
X639522Y-284626D01*
G01Y-282376D02*
X639395Y-282292D01*
Y-282126D01*
X639522Y-282042D01*
X639649Y-282126D01*
Y-282292D01*
X639522Y-282376D01*
G01X617322Y-299459D02*
X817322D01*
G01X622955Y-259459D02*
Y-254459D01*
X624475D01*
X624982Y-254709D01*
X625362Y-255292D01*
X625489Y-255959D01*
X625362Y-256626D01*
X625045Y-257126D01*
X624475Y-257376D01*
X622955D01*
G01X628055Y-259459D02*
Y-254459D01*
X629639D01*
X630145Y-254709D01*
X630462Y-255042D01*
X630589Y-255709D01*
X630462Y-256376D01*
X630082Y-256792D01*
X629639Y-257042D01*
X628055D01*
G01X629639D02*
X630589Y-259459D01*
G01X634422D02*
X633915Y-259376D01*
X633472Y-259042D01*
X633092Y-258542D01*
X632839Y-257959D01*
X632712Y-257292D01*
Y-256626D01*
X632839Y-255959D01*
X633092Y-255376D01*
X633472Y-254876D01*
X633915Y-254542D01*
X634422Y-254459D01*
X634929Y-254542D01*
X635372Y-254876D01*
X635752Y-255376D01*
X636005Y-255959D01*
X636132Y-256626D01*
Y-257292D01*
X636005Y-257959D01*
X635752Y-258542D01*
X635372Y-259042D01*
X634929Y-259376D01*
X634422Y-259459D01*
G01X638255Y-258459D02*
X638572Y-258959D01*
X638952Y-259292D01*
X639395Y-259459D01*
X639902Y-259292D01*
X640282Y-258959D01*
X640662Y-258459D01*
X640789Y-257792D01*
Y-254459D01*
G01X645889Y-259459D02*
X643355D01*
Y-254459D01*
X645889D01*
G01X644875Y-256876D02*
X643355D01*
G01X651115Y-254876D02*
X650735Y-254626D01*
X650292Y-254459D01*
X649785D01*
X649215Y-254709D01*
X648772Y-255126D01*
X648455Y-255626D01*
X648202Y-256459D01*
X648139Y-257209D01*
X648265Y-257959D01*
X648455Y-258459D01*
X648835Y-258959D01*
X649279Y-259292D01*
X649722Y-259459D01*
X650165D01*
X650609Y-259292D01*
X650989Y-259042D01*
X651305Y-258709D01*
G01X654822Y-254459D02*
Y-259459D01*
G01X653365Y-254459D02*
X656279D01*
G01X659922Y-259626D02*
X659795Y-259542D01*
Y-259376D01*
X659922Y-259292D01*
X660049Y-259376D01*
Y-259542D01*
X659922Y-259626D01*
G01Y-257376D02*
X659795Y-257292D01*
Y-257126D01*
X659922Y-257042D01*
X660049Y-257126D01*
Y-257292D01*
X659922Y-257376D01*
G01X617322Y-274459D02*
X817322D01*
G01X734955Y-301959D02*
Y-306959D01*
X737489D01*
G01X740562Y-301959D02*
X742082D01*
G01X741322D02*
Y-306959D01*
G01X740562D02*
X742082D01*
G01X746929Y-304292D02*
X747182Y-304042D01*
X747372Y-303626D01*
X747499Y-303042D01*
X747372Y-302542D01*
X747119Y-302209D01*
X746675Y-301959D01*
X744965D01*
Y-306959D01*
X747055D01*
X747499Y-306626D01*
X747752Y-306126D01*
X747879Y-305542D01*
X747752Y-304959D01*
X747372Y-304459D01*
X746929Y-304292D01*
X744965D01*
G01X751522Y-307126D02*
X751395Y-307042D01*
Y-306876D01*
X751522Y-306792D01*
X751649Y-306876D01*
Y-307042D01*
X751522Y-307126D01*
G01Y-304876D02*
X751395Y-304792D01*
Y-304626D01*
X751522Y-304542D01*
X751649Y-304626D01*
Y-304792D01*
X751522Y-304876D01*
G01X732322Y-299459D02*
Y-324459D01*
G01X779222Y-301959D02*
Y-306959D01*
G01X777765Y-301959D02*
X780679D01*
G01X784322Y-306959D02*
X783942Y-306876D01*
X783562Y-306542D01*
X783309Y-305959D01*
X783182Y-305292D01*
X783309Y-304626D01*
X783562Y-304042D01*
X783942Y-303709D01*
X784322Y-303626D01*
X784702Y-303709D01*
X785082Y-304042D01*
X785335Y-304626D01*
X785399Y-305292D01*
X785335Y-305959D01*
X785082Y-306542D01*
X784702Y-306876D01*
X784322Y-306959D01*
G01X789422D02*
X789042Y-306876D01*
X788662Y-306542D01*
X788409Y-305959D01*
X788282Y-305292D01*
X788409Y-304626D01*
X788662Y-304042D01*
X789042Y-303709D01*
X789422Y-303626D01*
X789802Y-303709D01*
X790182Y-304042D01*
X790435Y-304626D01*
X790499Y-305292D01*
X790435Y-305959D01*
X790182Y-306542D01*
X789802Y-306876D01*
X789422Y-306959D01*
G01X794522D02*
Y-301959D01*
G01X799622Y-307126D02*
X799495Y-307042D01*
Y-306876D01*
X799622Y-306792D01*
X799749Y-306876D01*
Y-307042D01*
X799622Y-307126D01*
G01Y-304876D02*
X799495Y-304792D01*
Y-304626D01*
X799622Y-304542D01*
X799749Y-304626D01*
Y-304792D01*
X799622Y-304876D01*
G01X775322Y-299459D02*
Y-324459D01*
G01Y-274459D02*
Y-299459D01*
G01X777955Y-281959D02*
Y-276959D01*
X779539D01*
X780045Y-277209D01*
X780362Y-277542D01*
X780489Y-278209D01*
X780362Y-278876D01*
X779982Y-279292D01*
X779539Y-279542D01*
X777955D01*
G01X779539D02*
X780489Y-281959D01*
G01X785589D02*
X783055D01*
Y-276959D01*
X785589D01*
G01X784575Y-279376D02*
X783055D01*
G01X787839Y-276959D02*
X789422Y-281959D01*
X791005Y-276959D01*
G01X794522Y-282126D02*
X794395Y-282042D01*
Y-281876D01*
X794522Y-281792D01*
X794649Y-281876D01*
Y-282042D01*
X794522Y-282126D01*
G01Y-279876D02*
X794395Y-279792D01*
Y-279626D01*
X794522Y-279542D01*
X794649Y-279626D01*
Y-279792D01*
X794522Y-279876D01*
G01X798082Y-326159D02*
X798162Y-326084D01*
X798222Y-325959D01*
X798262Y-325784D01*
X798222Y-325634D01*
X798142Y-325534D01*
X798002Y-325459D01*
X797462D01*
Y-326959D01*
X798122D01*
X798262Y-326859D01*
X798342Y-326709D01*
X798382Y-326534D01*
X798342Y-326359D01*
X798222Y-326209D01*
X798082Y-326159D01*
X797462D01*
G01X799482Y-326959D02*
Y-325959D01*
G01Y-326134D02*
X799402Y-326034D01*
X799282Y-325984D01*
X799142Y-325959D01*
X799002Y-326009D01*
X798882Y-326109D01*
X798802Y-326259D01*
X798762Y-326459D01*
X798802Y-326659D01*
X798882Y-326809D01*
X799002Y-326909D01*
X799142Y-326959D01*
X799282Y-326934D01*
X799402Y-326859D01*
X799482Y-326759D01*
G01X800022Y-326784D02*
X800122Y-326884D01*
X800262Y-326959D01*
X800382D01*
X800502Y-326909D01*
X800582Y-326834D01*
X800622Y-326734D01*
X800602Y-326584D01*
X800522Y-326509D01*
X800162Y-326359D01*
X800082Y-326184D01*
X800122Y-326059D01*
X800202Y-325984D01*
X800322Y-325959D01*
X800442Y-325984D01*
X800562Y-326059D01*
G01X801222Y-326284D02*
X801862D01*
X801802Y-326109D01*
X801702Y-326009D01*
X801562Y-325959D01*
X801422Y-325984D01*
X801302Y-326059D01*
X801222Y-326234D01*
X801182Y-326384D01*
Y-326534D01*
X801222Y-326684D01*
X801322Y-326834D01*
X801442Y-326934D01*
X801582Y-326959D01*
X801722Y-326909D01*
X801862Y-326759D01*
G01X802362Y-326959D02*
Y-325459D01*
G01Y-326209D02*
X802462Y-326059D01*
X802582Y-325984D01*
X802702Y-325959D01*
X802882Y-326009D01*
X803002Y-326109D01*
X803082Y-326284D01*
Y-326484D01*
X803042Y-326684D01*
X802962Y-326834D01*
X802822Y-326934D01*
X802702Y-326959D01*
X802582Y-326934D01*
X802462Y-326859D01*
X802362Y-326734D01*
G01X803922Y-326959D02*
X803802Y-326934D01*
X803682Y-326834D01*
X803602Y-326659D01*
X803562Y-326459D01*
X803602Y-326259D01*
X803682Y-326084D01*
X803802Y-325984D01*
X803922Y-325959D01*
X804042Y-325984D01*
X804162Y-326084D01*
X804242Y-326259D01*
X804262Y-326459D01*
X804242Y-326659D01*
X804162Y-326834D01*
X804042Y-326934D01*
X803922Y-326959D01*
G01X805482D02*
Y-325959D01*
G01Y-326134D02*
X805402Y-326034D01*
X805282Y-325984D01*
X805142Y-325959D01*
X805002Y-326009D01*
X804882Y-326109D01*
X804802Y-326259D01*
X804762Y-326459D01*
X804802Y-326659D01*
X804882Y-326809D01*
X805002Y-326909D01*
X805142Y-326959D01*
X805282Y-326934D01*
X805402Y-326859D01*
X805482Y-326759D01*
G01X806042Y-326959D02*
Y-325959D01*
G01Y-326159D02*
X806142Y-326059D01*
X806242Y-325984D01*
X806382Y-325959D01*
X806482Y-325984D01*
X806602Y-326059D01*
G01X807882Y-325459D02*
Y-326959D01*
G01Y-326734D02*
X807802Y-326859D01*
X807682Y-326934D01*
X807542Y-326959D01*
X807382Y-326909D01*
X807262Y-326784D01*
X807182Y-326634D01*
X807162Y-326459D01*
X807182Y-326284D01*
X807262Y-326134D01*
X807382Y-326009D01*
X807542Y-325959D01*
X807682Y-325984D01*
X807782Y-326034D01*
X807882Y-326134D01*
G01X809522Y-326959D02*
Y-325459D01*
X810022D01*
X810182Y-325534D01*
X810282Y-325634D01*
X810322Y-325834D01*
X810282Y-326034D01*
X810162Y-326159D01*
X810022Y-326234D01*
X809522D01*
G01X810022D02*
X810322Y-326959D01*
G01X810822Y-326284D02*
X811462D01*
X811402Y-326109D01*
X811302Y-326009D01*
X811162Y-325959D01*
X811022Y-325984D01*
X810902Y-326059D01*
X810822Y-326234D01*
X810782Y-326384D01*
Y-326534D01*
X810822Y-326684D01*
X810922Y-326834D01*
X811042Y-326934D01*
X811182Y-326959D01*
X811322Y-326909D01*
X811462Y-326759D01*
G01X811962Y-325959D02*
X812322Y-326959D01*
X812682Y-325959D01*
G01X813522Y-327009D02*
X813482Y-326984D01*
Y-326934D01*
X813522Y-326909D01*
X813562Y-326934D01*
Y-326984D01*
X813522Y-327009D01*
G01X814682Y-326959D02*
X814722Y-326634D01*
X814782Y-326359D01*
X814862Y-326109D01*
X814962Y-325834D01*
X815122Y-325459D01*
X814322D01*
G01X816082Y-326159D02*
X816162Y-326084D01*
X816222Y-325959D01*
X816262Y-325784D01*
X816222Y-325634D01*
X816142Y-325534D01*
X816002Y-325459D01*
X815462D01*
Y-326959D01*
X816122D01*
X816262Y-326859D01*
X816342Y-326709D01*
X816382Y-326534D01*
X816342Y-326359D01*
X816222Y-326209D01*
X816082Y-326159D01*
X815462D01*
G01X853718Y1268655D02*
X850618D01*
Y1269575D01*
X850773Y1269882D01*
X851135Y1270112D01*
X851548Y1270189D01*
X851961Y1270112D01*
X852271Y1269920D01*
X852426Y1269575D01*
Y1268655D01*
G01X850876Y1273365D02*
X850721Y1273135D01*
X850618Y1272867D01*
Y1272560D01*
X850773Y1272215D01*
X851031Y1271947D01*
X851341Y1271755D01*
X851858Y1271602D01*
X852323Y1271564D01*
X852788Y1271640D01*
X853098Y1271755D01*
X853408Y1271985D01*
X853615Y1272254D01*
X853718Y1272522D01*
Y1272790D01*
X853615Y1273059D01*
X853460Y1273289D01*
X853253Y1273480D01*
G01X852065Y1275929D02*
X851910Y1276082D01*
X851651Y1276197D01*
X851290Y1276274D01*
X850980Y1276197D01*
X850773Y1276044D01*
X850618Y1275775D01*
Y1274740D01*
X853718D01*
Y1276005D01*
X853511Y1276274D01*
X853201Y1276427D01*
X852840Y1276504D01*
X852478Y1276427D01*
X852168Y1276197D01*
X852065Y1275929D01*
Y1274740D01*
G01X850618Y1280864D02*
X853718Y1281822D01*
X850618Y1282780D01*
G01X853718Y1285689D02*
Y1284155D01*
X850618D01*
Y1285689D01*
G01X852116Y1285075D02*
Y1284155D01*
G01X853718Y1287140D02*
X850618D01*
X853718Y1288904D01*
X850618D01*
G01X853718Y1290279D02*
X850618D01*
Y1291045D01*
X850773Y1291352D01*
X850980Y1291582D01*
X851290Y1291774D01*
X851651Y1291927D01*
X852168Y1291965D01*
X852685Y1291927D01*
X853046Y1291774D01*
X853356Y1291582D01*
X853563Y1291352D01*
X853718Y1291045D01*
Y1290279D01*
G01Y1294222D02*
X853666Y1293915D01*
X853460Y1293647D01*
X853150Y1293417D01*
X852788Y1293264D01*
X852375Y1293187D01*
X851961D01*
X851548Y1293264D01*
X851186Y1293417D01*
X850876Y1293647D01*
X850670Y1293915D01*
X850618Y1294222D01*
X850670Y1294529D01*
X850876Y1294797D01*
X851186Y1295027D01*
X851548Y1295180D01*
X851961Y1295257D01*
X852375D01*
X852788Y1295180D01*
X853150Y1295027D01*
X853460Y1294797D01*
X853666Y1294529D01*
X853718Y1294222D01*
G01Y1296555D02*
X850618D01*
Y1297514D01*
X850773Y1297820D01*
X850980Y1298012D01*
X851393Y1298089D01*
X851806Y1298012D01*
X852065Y1297782D01*
X852220Y1297514D01*
Y1296555D01*
G01Y1297514D02*
X853718Y1298089D01*
G01X856018Y1277055D02*
X859118D01*
Y1278589D01*
G01Y1280922D02*
X859066Y1280615D01*
X858860Y1280347D01*
X858550Y1280117D01*
X858188Y1279964D01*
X857775Y1279887D01*
X857361D01*
X856948Y1279964D01*
X856586Y1280117D01*
X856276Y1280347D01*
X856070Y1280615D01*
X856018Y1280922D01*
X856070Y1281229D01*
X856276Y1281497D01*
X856586Y1281727D01*
X856948Y1281880D01*
X857361Y1281957D01*
X857775D01*
X858188Y1281880D01*
X858550Y1281727D01*
X858860Y1281497D01*
X859066Y1281229D01*
X859118Y1280922D01*
G01X857568Y1284252D02*
Y1285019D01*
X858498D01*
X858808Y1284789D01*
X859015Y1284520D01*
X859118Y1284137D01*
X859015Y1283754D01*
X858808Y1283485D01*
X858498Y1283255D01*
X858136Y1283102D01*
X857723Y1283025D01*
X857361D01*
X857051Y1283102D01*
X856690Y1283255D01*
X856380Y1283485D01*
X856173Y1283715D01*
X856018Y1284022D01*
Y1284290D01*
X856121Y1284597D01*
X856328Y1284827D01*
G01X859118Y1287122D02*
X859066Y1286815D01*
X858860Y1286547D01*
X858550Y1286317D01*
X858188Y1286164D01*
X857775Y1286087D01*
X857361D01*
X856948Y1286164D01*
X856586Y1286317D01*
X856276Y1286547D01*
X856070Y1286815D01*
X856018Y1287122D01*
X856070Y1287429D01*
X856276Y1287697D01*
X856586Y1287927D01*
X856948Y1288080D01*
X857361Y1288157D01*
X857775D01*
X858188Y1288080D01*
X858550Y1287927D01*
X858860Y1287697D01*
X859066Y1287429D01*
X859118Y1287122D01*
G01X845668Y1267717D02*
Y1326772D01*
X885038D01*
Y1267717D01*
X845668D01*
G01X1220500Y815100D02*
Y1192500D01*
X1918000D01*
Y815100D01*
X1220500D01*
G01Y852900D02*
X1918000D01*
G01X1220500Y890700D02*
X1918000D01*
G01X1220500Y928500D02*
X1918000D01*
G01X1220500Y966300D02*
X1918000D01*
G01X1220500Y1004100D02*
X1918000D01*
G01X1220500Y1041900D02*
X1918000D01*
G01X1220500Y1079700D02*
X1918000D01*
G01X1220500Y1117500D02*
X1918000D01*
G01X1220500Y1142500D02*
X1918000D01*
G01X1220500Y1167500D02*
X1918000D01*
G01X1310400Y1142500D02*
Y815100D01*
G01X1511900Y1142500D02*
Y815100D01*
G01X1713400Y1142500D02*
Y815100D01*
G01X1840500Y1142500D02*
Y815100D01*
G01X-320500Y-470483D02*
Y2626000D01*
X2967000D01*
Y-470483D01*
X-320500D01*
G01X-113413Y-6250D02*
X-114653Y-6667D01*
X-115583Y-7708D01*
X-116203Y-8958D01*
X-116668Y-10625D01*
X-116823Y-12500D01*
X-116668Y-14375D01*
X-116203Y-16042D01*
X-115583Y-17292D01*
X-114653Y-18333D01*
X-113413Y-18750D01*
X-112173Y-18333D01*
X-111243Y-17292D01*
X-110623Y-16042D01*
X-110158Y-14375D01*
X-110003Y-12500D01*
X-110158Y-10625D01*
X-110623Y-8958D01*
X-111243Y-7708D01*
X-112173Y-6667D01*
X-113413Y-6250D01*
G01X-113563Y18750D02*
X-114803Y18333D01*
X-115733Y17292D01*
X-116353Y16042D01*
X-116818Y14375D01*
X-116973Y12500D01*
X-116818Y10625D01*
X-116353Y8958D01*
X-115733Y7708D01*
X-114803Y6667D01*
X-113563Y6250D01*
X-112323Y6667D01*
X-111393Y7708D01*
X-110773Y8958D01*
X-110308Y10625D01*
X-110153Y12500D01*
X-110308Y14375D01*
X-110773Y16042D01*
X-111393Y17292D01*
X-112323Y18333D01*
X-113563Y18750D01*
G01X-107497Y1270797D02*
X-106567Y1269338D01*
X-105327Y1268505D01*
X-103932Y1268297D01*
X-102692Y1268505D01*
X-101452Y1269547D01*
X-100677Y1270797D01*
X-100522Y1272047D01*
X-100832Y1273505D01*
X-101917Y1274547D01*
X-103002Y1274964D01*
X-104397D01*
G01X-103002D02*
X-102072Y1275589D01*
X-101297Y1276630D01*
X-100987Y1277880D01*
X-101297Y1279130D01*
X-102072Y1280172D01*
X-103467Y1280797D01*
X-104862Y1280589D01*
X-106257Y1279755D01*
G01X-94632Y1278714D02*
X-93702Y1279963D01*
X-92617Y1280589D01*
X-91377Y1280797D01*
X-89827Y1280380D01*
X-88742Y1279339D01*
X-88432Y1278089D01*
X-88587Y1276838D01*
X-89207Y1275797D01*
X-92307Y1273714D01*
X-93702Y1272255D01*
X-94632Y1270172D01*
X-94942Y1268297D01*
X-88432D01*
G01X-82232Y1273505D02*
X-81147Y1274964D01*
X-80217Y1275797D01*
X-78977Y1276214D01*
X-77892Y1275797D01*
X-77117Y1274964D01*
X-76497Y1273714D01*
X-76342Y1272255D01*
X-76497Y1271005D01*
X-77117Y1269755D01*
X-78047Y1268714D01*
X-79132Y1268297D01*
X-80372Y1268714D01*
X-81457Y1269963D01*
X-82077Y1271839D01*
X-82232Y1273922D01*
X-81922Y1276630D01*
X-81457Y1278089D01*
X-80682Y1279547D01*
X-79597Y1280589D01*
X-78512Y1280797D01*
X-77427Y1280380D01*
X-76652Y1279339D01*
G01X-66887Y1267880D02*
X-67197Y1268089D01*
Y1268505D01*
X-66887Y1268714D01*
X-66577Y1268505D01*
Y1268089D01*
X-66887Y1267880D01*
G01X-57122Y1269755D02*
X-56037Y1268714D01*
X-54797Y1268297D01*
X-53557Y1268714D01*
X-52472Y1269963D01*
X-51697Y1271839D01*
X-51387Y1273714D01*
Y1276005D01*
X-51697Y1277880D01*
X-52472Y1279547D01*
X-53402Y1280380D01*
X-54487Y1280797D01*
X-55727Y1280380D01*
X-56657Y1279547D01*
X-57277Y1278297D01*
X-57587Y1276630D01*
X-57277Y1275172D01*
X-56502Y1273714D01*
X-55572Y1272880D01*
X-54487Y1272672D01*
X-53247Y1273088D01*
X-52317Y1274130D01*
X-51387Y1276005D01*
G01X-42087Y1268297D02*
Y1280797D01*
X-43947Y1278297D01*
G01Y1268297D02*
X-40227D01*
G01X-116637Y1293297D02*
Y1305797D01*
X-118497Y1303297D01*
G01Y1293297D02*
X-114777D01*
G01X-107182Y1303714D02*
X-106252Y1304963D01*
X-105167Y1305589D01*
X-103927Y1305797D01*
X-102377Y1305380D01*
X-101292Y1304339D01*
X-100982Y1303089D01*
X-101137Y1301838D01*
X-101757Y1300797D01*
X-104857Y1298714D01*
X-106252Y1297255D01*
X-107182Y1295172D01*
X-107492Y1293297D01*
X-100982D01*
G01X-91837D02*
X-90752Y1293505D01*
X-89512Y1294130D01*
X-88737Y1295172D01*
X-88427Y1296630D01*
X-88737Y1298088D01*
X-89667Y1299339D01*
X-91062Y1299964D01*
X-92612D01*
X-93542Y1300380D01*
X-94317Y1301422D01*
X-94627Y1302880D01*
X-94162Y1304339D01*
X-93077Y1305380D01*
X-91837Y1305797D01*
X-90597Y1305380D01*
X-89512Y1304339D01*
X-89047Y1302880D01*
X-89357Y1301422D01*
X-90132Y1300380D01*
X-91062Y1299964D01*
X-92612D01*
X-94007Y1299339D01*
X-94937Y1298088D01*
X-95247Y1296630D01*
X-94937Y1295172D01*
X-94162Y1294130D01*
X-92922Y1293505D01*
X-91837Y1293297D01*
G01X-79747D02*
X-79437Y1296005D01*
X-78972Y1298297D01*
X-78352Y1300380D01*
X-77577Y1302672D01*
X-76337Y1305797D01*
X-82537D01*
G01X-67037D02*
X-68277Y1305380D01*
X-69207Y1304339D01*
X-69827Y1303089D01*
X-70292Y1301422D01*
X-70447Y1299547D01*
X-70292Y1297672D01*
X-69827Y1296005D01*
X-69207Y1294755D01*
X-68277Y1293714D01*
X-67037Y1293297D01*
X-65797Y1293714D01*
X-64867Y1294755D01*
X-64247Y1296005D01*
X-63782Y1297672D01*
X-63627Y1299547D01*
X-63782Y1301422D01*
X-64247Y1303089D01*
X-64867Y1304339D01*
X-65797Y1305380D01*
X-67037Y1305797D01*
G01X-54637Y1292880D02*
X-54947Y1293089D01*
Y1293505D01*
X-54637Y1293714D01*
X-54327Y1293505D01*
Y1293089D01*
X-54637Y1292880D01*
G01X-40377Y1293297D02*
Y1305797D01*
X-46112Y1296839D01*
X-38362D01*
G01X-30147Y1293297D02*
X-29837Y1296005D01*
X-29372Y1298297D01*
X-28752Y1300380D01*
X-27977Y1302672D01*
X-26737Y1305797D01*
X-32937D01*
G01X-44428Y50617D02*
X-41328D01*
Y49697D01*
X-41483Y49390D01*
X-41845Y49160D01*
X-42258Y49083D01*
X-42671Y49160D01*
X-42981Y49352D01*
X-43136Y49697D01*
Y50617D01*
G01X-41586Y45907D02*
X-41431Y46137D01*
X-41328Y46405D01*
Y46712D01*
X-41483Y47057D01*
X-41741Y47325D01*
X-42051Y47517D01*
X-42568Y47670D01*
X-43033Y47708D01*
X-43498Y47632D01*
X-43808Y47517D01*
X-44118Y47287D01*
X-44325Y47018D01*
X-44428Y46750D01*
Y46482D01*
X-44325Y46213D01*
X-44170Y45983D01*
X-43963Y45792D01*
G01X-42775Y43343D02*
X-42620Y43190D01*
X-42361Y43075D01*
X-42000Y42998D01*
X-41690Y43075D01*
X-41483Y43228D01*
X-41328Y43497D01*
Y44532D01*
X-44428D01*
Y43267D01*
X-44221Y42998D01*
X-43911Y42845D01*
X-43550Y42768D01*
X-43188Y42845D01*
X-42878Y43075D01*
X-42775Y43343D01*
Y44532D01*
G01X-41328Y38408D02*
X-44428Y37450D01*
X-41328Y36492D01*
G01X-44428Y33583D02*
Y35117D01*
X-41328D01*
Y33583D01*
G01X-42826Y34197D02*
Y35117D01*
G01X-44428Y32132D02*
X-41328D01*
X-44428Y30368D01*
X-41328D01*
G01X-44428Y28993D02*
X-41328D01*
Y28227D01*
X-41483Y27920D01*
X-41690Y27690D01*
X-42000Y27498D01*
X-42361Y27345D01*
X-42878Y27307D01*
X-43395Y27345D01*
X-43756Y27498D01*
X-44066Y27690D01*
X-44273Y27920D01*
X-44428Y28227D01*
Y28993D01*
G01Y25050D02*
X-44376Y25357D01*
X-44170Y25625D01*
X-43860Y25855D01*
X-43498Y26008D01*
X-43085Y26085D01*
X-42671D01*
X-42258Y26008D01*
X-41896Y25855D01*
X-41586Y25625D01*
X-41380Y25357D01*
X-41328Y25050D01*
X-41380Y24743D01*
X-41586Y24475D01*
X-41896Y24245D01*
X-42258Y24092D01*
X-42671Y24015D01*
X-43085D01*
X-43498Y24092D01*
X-43860Y24245D01*
X-44170Y24475D01*
X-44376Y24743D01*
X-44428Y25050D01*
G01Y22717D02*
X-41328D01*
Y21758D01*
X-41483Y21452D01*
X-41690Y21260D01*
X-42103Y21183D01*
X-42516Y21260D01*
X-42775Y21490D01*
X-42930Y21758D01*
Y22717D01*
G01Y21758D02*
X-44428Y21183D01*
G01X-46728Y42217D02*
X-49828D01*
Y40683D01*
G01Y38350D02*
X-49776Y38657D01*
X-49570Y38925D01*
X-49260Y39155D01*
X-48898Y39308D01*
X-48485Y39385D01*
X-48071D01*
X-47658Y39308D01*
X-47296Y39155D01*
X-46986Y38925D01*
X-46780Y38657D01*
X-46728Y38350D01*
X-46780Y38043D01*
X-46986Y37775D01*
X-47296Y37545D01*
X-47658Y37392D01*
X-48071Y37315D01*
X-48485D01*
X-48898Y37392D01*
X-49260Y37545D01*
X-49570Y37775D01*
X-49776Y38043D01*
X-49828Y38350D01*
G01X-48278Y35020D02*
Y34253D01*
X-49208D01*
X-49518Y34483D01*
X-49725Y34752D01*
X-49828Y35135D01*
X-49725Y35518D01*
X-49518Y35787D01*
X-49208Y36017D01*
X-48846Y36170D01*
X-48433Y36247D01*
X-48071D01*
X-47761Y36170D01*
X-47400Y36017D01*
X-47090Y35787D01*
X-46883Y35557D01*
X-46728Y35250D01*
Y34982D01*
X-46831Y34675D01*
X-47038Y34445D01*
G01X-49828Y32150D02*
X-49776Y32457D01*
X-49570Y32725D01*
X-49260Y32955D01*
X-48898Y33108D01*
X-48485Y33185D01*
X-48071D01*
X-47658Y33108D01*
X-47296Y32955D01*
X-46986Y32725D01*
X-46780Y32457D01*
X-46728Y32150D01*
X-46780Y31843D01*
X-46986Y31575D01*
X-47296Y31345D01*
X-47658Y31192D01*
X-48071Y31115D01*
X-48485D01*
X-48898Y31192D01*
X-49260Y31345D01*
X-49570Y31575D01*
X-49776Y31843D01*
X-49828Y32150D01*
G01X-18750Y-41411D02*
X-18333Y-42651D01*
X-17292Y-43581D01*
X-16042Y-44201D01*
X-14375Y-44666D01*
X-12500Y-44821D01*
X-10625Y-44666D01*
X-8958Y-44201D01*
X-7708Y-43581D01*
X-6667Y-42651D01*
X-6250Y-41411D01*
X-6667Y-40171D01*
X-7708Y-39241D01*
X-8958Y-38621D01*
X-10625Y-38156D01*
X-12500Y-38001D01*
X-14375Y-38156D01*
X-16042Y-38621D01*
X-17292Y-39241D01*
X-18333Y-40171D01*
X-18750Y-41411D01*
G01X-24067Y641500D02*
Y649000D01*
X-21827D01*
X-21080Y648625D01*
X-20520Y647750D01*
X-20333Y646750D01*
X-20520Y645750D01*
X-20987Y645000D01*
X-21827Y644625D01*
X-24067D01*
G01X-14700Y649000D02*
Y641500D01*
G01X-16847Y649000D02*
X-12553D01*
G01X-9160Y641500D02*
Y649000D01*
G01X-5240D02*
Y641500D01*
G01Y645250D02*
X-9160D01*
G01X6250Y-41261D02*
X6667Y-42501D01*
X7708Y-43431D01*
X8958Y-44051D01*
X10625Y-44516D01*
X12500Y-44671D01*
X14375Y-44516D01*
X16042Y-44051D01*
X17292Y-43431D01*
X18333Y-42501D01*
X18750Y-41261D01*
X18333Y-40021D01*
X17292Y-39091D01*
X16042Y-38471D01*
X14375Y-38006D01*
X12500Y-37851D01*
X10625Y-38006D01*
X8958Y-38471D01*
X7708Y-39091D01*
X6667Y-40021D01*
X6250Y-41261D01*
G01X36467Y1358270D02*
X23967D01*
X32925Y1352535D01*
Y1360285D01*
G01X26050Y1365865D02*
X24801Y1366795D01*
X24175Y1367880D01*
X23967Y1369120D01*
X24384Y1370670D01*
X25425Y1371755D01*
X26675Y1372065D01*
X27926Y1371910D01*
X28967Y1371290D01*
X31050Y1368190D01*
X32509Y1366795D01*
X34592Y1365865D01*
X36467Y1365555D01*
Y1372065D01*
G01Y1380900D02*
X33759Y1381210D01*
X31467Y1381675D01*
X29384Y1382295D01*
X27092Y1383070D01*
X23967Y1384310D01*
Y1378110D01*
G01X36884Y1393610D02*
X36675Y1393300D01*
X36259D01*
X36050Y1393610D01*
X36259Y1393920D01*
X36675D01*
X36884Y1393610D01*
G01X36467Y1406010D02*
X23967D01*
X26467Y1404150D01*
G01X36467D02*
Y1407870D01*
G01Y1418100D02*
X33759Y1418410D01*
X31467Y1418875D01*
X29384Y1419495D01*
X27092Y1420270D01*
X23967Y1421510D01*
Y1415310D01*
G01X61250Y-308222D02*
X61042Y-307137D01*
X60417Y-305897D01*
X59375Y-305122D01*
X57917Y-304812D01*
X56459Y-305122D01*
X55208Y-306052D01*
X54583Y-307447D01*
Y-308997D01*
X54167Y-309927D01*
X53125Y-310702D01*
X51667Y-311012D01*
X50208Y-310547D01*
X49167Y-309462D01*
X48750Y-308222D01*
X49167Y-306982D01*
X50208Y-305897D01*
X51667Y-305432D01*
X53125Y-305742D01*
X54167Y-306517D01*
X54583Y-307447D01*
Y-308997D01*
X55208Y-310392D01*
X56459Y-311322D01*
X57917Y-311632D01*
X59375Y-311322D01*
X60417Y-310547D01*
X61042Y-309307D01*
X61250Y-308222D01*
G01X50833Y-298767D02*
X49584Y-297837D01*
X48958Y-296752D01*
X48750Y-295512D01*
X49167Y-293962D01*
X50208Y-292877D01*
X51458Y-292567D01*
X52709Y-292722D01*
X53750Y-293342D01*
X55833Y-296442D01*
X57292Y-297837D01*
X59375Y-298767D01*
X61250Y-299077D01*
Y-292567D01*
G01X59792Y-286057D02*
X60833Y-284972D01*
X61250Y-283732D01*
X60833Y-282492D01*
X59584Y-281407D01*
X57708Y-280632D01*
X55833Y-280322D01*
X53542D01*
X51667Y-280632D01*
X50000Y-281407D01*
X49167Y-282337D01*
X48750Y-283422D01*
X49167Y-284662D01*
X50000Y-285592D01*
X51250Y-286212D01*
X52917Y-286522D01*
X54375Y-286212D01*
X55833Y-285437D01*
X56667Y-284507D01*
X56875Y-283422D01*
X56459Y-282182D01*
X55417Y-281252D01*
X53542Y-280322D01*
G01X61667Y-271022D02*
X61458Y-271332D01*
X61042D01*
X60833Y-271022D01*
X61042Y-270712D01*
X61458D01*
X61667Y-271022D01*
G01X59792Y-261257D02*
X60833Y-260172D01*
X61250Y-258932D01*
X60833Y-257692D01*
X59584Y-256607D01*
X57708Y-255832D01*
X55833Y-255522D01*
X53542D01*
X51667Y-255832D01*
X50000Y-256607D01*
X49167Y-257537D01*
X48750Y-258622D01*
X49167Y-259862D01*
X50000Y-260792D01*
X51250Y-261412D01*
X52917Y-261722D01*
X54375Y-261412D01*
X55833Y-260637D01*
X56667Y-259707D01*
X56875Y-258622D01*
X56459Y-257382D01*
X55417Y-256452D01*
X53542Y-255522D01*
G01X50833Y-249167D02*
X49584Y-248237D01*
X48958Y-247152D01*
X48750Y-245912D01*
X49167Y-244362D01*
X50208Y-243277D01*
X51458Y-242967D01*
X52709Y-243122D01*
X53750Y-243742D01*
X55833Y-246842D01*
X57292Y-248237D01*
X59375Y-249167D01*
X61250Y-249477D01*
Y-242967D01*
G01X50833Y-214567D02*
X49584Y-213637D01*
X48958Y-212552D01*
X48750Y-211312D01*
X49167Y-209762D01*
X50208Y-208677D01*
X51458Y-208367D01*
X52709Y-208522D01*
X53750Y-209142D01*
X55833Y-212242D01*
X57292Y-213637D01*
X59375Y-214567D01*
X61250Y-214877D01*
Y-208367D01*
G01Y-199222D02*
X48750D01*
X51250Y-201082D01*
G01X61250D02*
Y-197362D01*
G01X61667Y-186822D02*
X61458Y-187132D01*
X61042D01*
X60833Y-186822D01*
X61042Y-186512D01*
X61458D01*
X61667Y-186822D01*
G01X48750Y-174422D02*
X49167Y-175662D01*
X50208Y-176592D01*
X51458Y-177212D01*
X53125Y-177677D01*
X55000Y-177832D01*
X56875Y-177677D01*
X58542Y-177212D01*
X59792Y-176592D01*
X60833Y-175662D01*
X61250Y-174422D01*
X60833Y-173182D01*
X59792Y-172252D01*
X58542Y-171632D01*
X56875Y-171167D01*
X55000Y-171012D01*
X53125Y-171167D01*
X51458Y-171632D01*
X50208Y-172252D01*
X49167Y-173182D01*
X48750Y-174422D01*
G01X61250Y-162022D02*
X61042Y-160937D01*
X60417Y-159697D01*
X59375Y-158922D01*
X57917Y-158612D01*
X56459Y-158922D01*
X55208Y-159852D01*
X54583Y-161247D01*
Y-162797D01*
X54167Y-163727D01*
X53125Y-164502D01*
X51667Y-164812D01*
X50208Y-164347D01*
X49167Y-163262D01*
X48750Y-162022D01*
X49167Y-160782D01*
X50208Y-159697D01*
X51667Y-159232D01*
X53125Y-159542D01*
X54167Y-160317D01*
X54583Y-161247D01*
Y-162797D01*
X55208Y-164192D01*
X56459Y-165122D01*
X57917Y-165432D01*
X59375Y-165122D01*
X60417Y-164347D01*
X61042Y-163107D01*
X61250Y-162022D01*
G01X61467Y1362760D02*
X48967D01*
X51467Y1360900D01*
G01X61467D02*
Y1364620D01*
G01X48967Y1375160D02*
X49384Y1373920D01*
X50425Y1372990D01*
X51675Y1372370D01*
X53342Y1371905D01*
X55217Y1371750D01*
X57092Y1371905D01*
X58759Y1372370D01*
X60009Y1372990D01*
X61050Y1373920D01*
X61467Y1375160D01*
X61050Y1376400D01*
X60009Y1377330D01*
X58759Y1377950D01*
X57092Y1378415D01*
X55217Y1378570D01*
X53342Y1378415D01*
X51675Y1377950D01*
X50425Y1377330D01*
X49384Y1376400D01*
X48967Y1375160D01*
G01X61884Y1387560D02*
X61675Y1387250D01*
X61259D01*
X61050Y1387560D01*
X61259Y1387870D01*
X61675D01*
X61884Y1387560D01*
G01X61467Y1399960D02*
X61259Y1401045D01*
X60634Y1402285D01*
X59592Y1403060D01*
X58134Y1403370D01*
X56676Y1403060D01*
X55425Y1402130D01*
X54800Y1400735D01*
Y1399185D01*
X54384Y1398255D01*
X53342Y1397480D01*
X51884Y1397170D01*
X50425Y1397635D01*
X49384Y1398720D01*
X48967Y1399960D01*
X49384Y1401200D01*
X50425Y1402285D01*
X51884Y1402750D01*
X53342Y1402440D01*
X54384Y1401665D01*
X54800Y1400735D01*
Y1399185D01*
X55425Y1397790D01*
X56676Y1396860D01*
X58134Y1396550D01*
X59592Y1396860D01*
X60634Y1397635D01*
X61259Y1398875D01*
X61467Y1399960D01*
G01X59592Y1408950D02*
X60634Y1409880D01*
X61259Y1410965D01*
X61467Y1412360D01*
X61050Y1413755D01*
X60217Y1414840D01*
X58759Y1415615D01*
X57092Y1415770D01*
X55425Y1415460D01*
X54384Y1414685D01*
X53550Y1413600D01*
X53342Y1412515D01*
X53550Y1411430D01*
X54384Y1410035D01*
X48967Y1410500D01*
Y1414685D01*
G01X85792Y-310857D02*
X86833Y-309772D01*
X87250Y-308532D01*
X86833Y-307292D01*
X85584Y-306207D01*
X83708Y-305432D01*
X81833Y-305122D01*
X79542D01*
X77667Y-305432D01*
X76000Y-306207D01*
X75167Y-307137D01*
X74750Y-308222D01*
X75167Y-309462D01*
X76000Y-310392D01*
X77250Y-311012D01*
X78917Y-311322D01*
X80375Y-311012D01*
X81833Y-310237D01*
X82667Y-309307D01*
X82875Y-308222D01*
X82459Y-306982D01*
X81417Y-306052D01*
X79542Y-305122D01*
G01X87250Y-296132D02*
X84542Y-295822D01*
X82250Y-295357D01*
X80167Y-294737D01*
X77875Y-293962D01*
X74750Y-292722D01*
Y-298922D01*
G01X85792Y-286057D02*
X86833Y-284972D01*
X87250Y-283732D01*
X86833Y-282492D01*
X85584Y-281407D01*
X83708Y-280632D01*
X81833Y-280322D01*
X79542D01*
X77667Y-280632D01*
X76000Y-281407D01*
X75167Y-282337D01*
X74750Y-283422D01*
X75167Y-284662D01*
X76000Y-285592D01*
X77250Y-286212D01*
X78917Y-286522D01*
X80375Y-286212D01*
X81833Y-285437D01*
X82667Y-284507D01*
X82875Y-283422D01*
X82459Y-282182D01*
X81417Y-281252D01*
X79542Y-280322D01*
G01X87667Y-271022D02*
X87458Y-271332D01*
X87042D01*
X86833Y-271022D01*
X87042Y-270712D01*
X87458D01*
X87667Y-271022D01*
G01X85792Y-261257D02*
X86833Y-260172D01*
X87250Y-258932D01*
X86833Y-257692D01*
X85584Y-256607D01*
X83708Y-255832D01*
X81833Y-255522D01*
X79542D01*
X77667Y-255832D01*
X76000Y-256607D01*
X75167Y-257537D01*
X74750Y-258622D01*
X75167Y-259862D01*
X76000Y-260792D01*
X77250Y-261412D01*
X78917Y-261722D01*
X80375Y-261412D01*
X81833Y-260637D01*
X82667Y-259707D01*
X82875Y-258622D01*
X82459Y-257382D01*
X81417Y-256452D01*
X79542Y-255522D01*
G01X76833Y-249167D02*
X75584Y-248237D01*
X74958Y-247152D01*
X74750Y-245912D01*
X75167Y-244362D01*
X76208Y-243277D01*
X77458Y-242967D01*
X78709Y-243122D01*
X79750Y-243742D01*
X81833Y-246842D01*
X83292Y-248237D01*
X85375Y-249167D01*
X87250Y-249477D01*
Y-242967D01*
G01X76833Y-214567D02*
X75584Y-213637D01*
X74958Y-212552D01*
X74750Y-211312D01*
X75167Y-209762D01*
X76208Y-208677D01*
X77458Y-208367D01*
X78709Y-208522D01*
X79750Y-209142D01*
X81833Y-212242D01*
X83292Y-213637D01*
X85375Y-214567D01*
X87250Y-214877D01*
Y-208367D01*
G01Y-197362D02*
X74750D01*
X83708Y-203097D01*
Y-195347D01*
G01X87667Y-186822D02*
X87458Y-187132D01*
X87042D01*
X86833Y-186822D01*
X87042Y-186512D01*
X87458D01*
X87667Y-186822D01*
G01X87250Y-174422D02*
X87042Y-173337D01*
X86417Y-172097D01*
X85375Y-171322D01*
X83917Y-171012D01*
X82459Y-171322D01*
X81208Y-172252D01*
X80583Y-173647D01*
Y-175197D01*
X80167Y-176127D01*
X79125Y-176902D01*
X77667Y-177212D01*
X76208Y-176747D01*
X75167Y-175662D01*
X74750Y-174422D01*
X75167Y-173182D01*
X76208Y-172097D01*
X77667Y-171632D01*
X79125Y-171942D01*
X80167Y-172717D01*
X80583Y-173647D01*
Y-175197D01*
X81208Y-176592D01*
X82459Y-177522D01*
X83917Y-177832D01*
X85375Y-177522D01*
X86417Y-176747D01*
X87042Y-175507D01*
X87250Y-174422D01*
G01X85792Y-164657D02*
X86833Y-163572D01*
X87250Y-162332D01*
X86833Y-161092D01*
X85584Y-160007D01*
X83708Y-159232D01*
X81833Y-158922D01*
X79542D01*
X77667Y-159232D01*
X76000Y-160007D01*
X75167Y-160937D01*
X74750Y-162022D01*
X75167Y-163262D01*
X76000Y-164192D01*
X77250Y-164812D01*
X78917Y-165122D01*
X80375Y-164812D01*
X81833Y-164037D01*
X82667Y-163107D01*
X82875Y-162022D01*
X82459Y-160782D01*
X81417Y-159852D01*
X79542Y-158922D01*
G01X80100Y-77042D02*
X79050Y-77825D01*
X78000Y-78217D01*
X73800D01*
X72750Y-77825D01*
X71700Y-77042D01*
G01X78000Y-71917D02*
X71700D01*
Y-70037D01*
X72015Y-69410D01*
X72750Y-68940D01*
X73590Y-68783D01*
X74430Y-68940D01*
X75060Y-69332D01*
X75375Y-70037D01*
Y-71917D01*
G01X73800Y-64050D02*
X78000D01*
G01X72120D02*
X72015Y-64207D01*
X71805D01*
X71700Y-64050D01*
X71805Y-63893D01*
X72015D01*
X72120Y-64050D01*
G01X78000Y-59082D02*
X73800D01*
G01X74850D02*
X74325Y-58768D01*
X73905Y-58298D01*
X73800Y-57672D01*
X73905Y-57123D01*
X74325Y-56653D01*
X75060Y-56418D01*
X78000D01*
G01X72225Y-43427D02*
X71910Y-43897D01*
X71700Y-44445D01*
Y-45072D01*
X72015Y-45777D01*
X72540Y-46325D01*
X73170Y-46717D01*
X74220Y-47030D01*
X75165Y-47108D01*
X76110Y-46952D01*
X76740Y-46717D01*
X77370Y-46247D01*
X77790Y-45698D01*
X78000Y-45150D01*
Y-44602D01*
X77790Y-44053D01*
X77475Y-43583D01*
X77055Y-43192D01*
G01X75165Y-40025D02*
Y-37518D01*
X74430Y-37753D01*
X74010Y-38145D01*
X73800Y-38693D01*
X73905Y-39242D01*
X74220Y-39712D01*
X74955Y-40025D01*
X75585Y-40182D01*
X76215D01*
X76845Y-40025D01*
X77475Y-39633D01*
X77895Y-39163D01*
X78000Y-38615D01*
X77790Y-38067D01*
X77160Y-37518D01*
G01X78000Y-33882D02*
X73800D01*
G01X74850D02*
X74325Y-33568D01*
X73905Y-33098D01*
X73800Y-32472D01*
X73905Y-31923D01*
X74325Y-31453D01*
X75060Y-31218D01*
X78000D01*
G01X71700Y-26250D02*
X78000D01*
G01X73800Y-27347D02*
Y-25153D01*
G01X75165Y-21125D02*
Y-18618D01*
X74430Y-18853D01*
X74010Y-19245D01*
X73800Y-19793D01*
X73905Y-20342D01*
X74220Y-20812D01*
X74955Y-21125D01*
X75585Y-21282D01*
X76215D01*
X76845Y-21125D01*
X77475Y-20733D01*
X77895Y-20263D01*
X78000Y-19715D01*
X77790Y-19167D01*
X77160Y-18618D01*
G01X78000Y-14747D02*
X73800D01*
G01X74640D02*
X74220Y-14355D01*
X73905Y-13963D01*
X73800Y-13415D01*
X73905Y-13023D01*
X74220Y-12553D01*
G01X80100Y-6958D02*
X79050Y-6175D01*
X78000Y-5783D01*
X73800D01*
X72750Y-6175D01*
X71700Y-6958D01*
G01X64655Y1537667D02*
X65585Y1538916D01*
X66670Y1539542D01*
X67910Y1539750D01*
X69460Y1539333D01*
X70545Y1538292D01*
X70855Y1537042D01*
X70700Y1535791D01*
X70080Y1534750D01*
X66980Y1532667D01*
X65585Y1531208D01*
X64655Y1529125D01*
X64345Y1527250D01*
X70855D01*
G01X80000Y1539750D02*
X78760Y1539333D01*
X77830Y1538292D01*
X77210Y1537042D01*
X76745Y1535375D01*
X76590Y1533500D01*
X76745Y1531625D01*
X77210Y1529958D01*
X77830Y1528708D01*
X78760Y1527667D01*
X80000Y1527250D01*
X81240Y1527667D01*
X82170Y1528708D01*
X82790Y1529958D01*
X83255Y1531625D01*
X83410Y1533500D01*
X83255Y1535375D01*
X82790Y1537042D01*
X82170Y1538292D01*
X81240Y1539333D01*
X80000Y1539750D01*
G01X88990Y1529750D02*
X89920Y1528291D01*
X91160Y1527458D01*
X92555Y1527250D01*
X93795Y1527458D01*
X95035Y1528500D01*
X95810Y1529750D01*
X95965Y1531000D01*
X95655Y1532458D01*
X94570Y1533500D01*
X93485Y1533917D01*
X92090D01*
G01X93485D02*
X94415Y1534542D01*
X95190Y1535583D01*
X95500Y1536833D01*
X95190Y1538083D01*
X94415Y1539125D01*
X93020Y1539750D01*
X91625Y1539542D01*
X90230Y1538708D01*
G01X101390Y1529125D02*
X102320Y1528083D01*
X103405Y1527458D01*
X104800Y1527250D01*
X106195Y1527667D01*
X107280Y1528500D01*
X108055Y1529958D01*
X108210Y1531625D01*
X107900Y1533292D01*
X107125Y1534333D01*
X106040Y1535167D01*
X104955Y1535375D01*
X103870Y1535167D01*
X102475Y1534333D01*
X102940Y1539750D01*
X107125D01*
G01X117200Y1526833D02*
X116890Y1527042D01*
Y1527458D01*
X117200Y1527667D01*
X117510Y1527458D01*
Y1527042D01*
X117200Y1526833D01*
G01X131460Y1527250D02*
Y1539750D01*
X125725Y1530792D01*
X133475D01*
G01X138590Y1529750D02*
X139520Y1528291D01*
X140760Y1527458D01*
X142155Y1527250D01*
X143395Y1527458D01*
X144635Y1528500D01*
X145410Y1529750D01*
X145565Y1531000D01*
X145255Y1532458D01*
X144170Y1533500D01*
X143085Y1533917D01*
X141690D01*
G01X143085D02*
X144015Y1534542D01*
X144790Y1535583D01*
X145100Y1536833D01*
X144790Y1538083D01*
X144015Y1539125D01*
X142620Y1539750D01*
X141225Y1539542D01*
X139830Y1538708D01*
G01X113022Y-321800D02*
X100522D01*
X103022Y-323660D01*
G01X113022D02*
Y-319940D01*
G01X100522Y-309400D02*
X100939Y-310640D01*
X101980Y-311570D01*
X103230Y-312190D01*
X104897Y-312655D01*
X106772Y-312810D01*
X108647Y-312655D01*
X110314Y-312190D01*
X111564Y-311570D01*
X112605Y-310640D01*
X113022Y-309400D01*
X112605Y-308160D01*
X111564Y-307230D01*
X110314Y-306610D01*
X108647Y-306145D01*
X106772Y-305990D01*
X104897Y-306145D01*
X103230Y-306610D01*
X101980Y-307230D01*
X100939Y-308160D01*
X100522Y-309400D01*
G01X107814Y-299945D02*
X106355Y-298860D01*
X105522Y-297930D01*
X105105Y-296690D01*
X105522Y-295605D01*
X106355Y-294830D01*
X107605Y-294210D01*
X109064Y-294055D01*
X110314Y-294210D01*
X111564Y-294830D01*
X112605Y-295760D01*
X113022Y-296845D01*
X112605Y-298085D01*
X111356Y-299170D01*
X109480Y-299790D01*
X107397Y-299945D01*
X104689Y-299635D01*
X103230Y-299170D01*
X101772Y-298395D01*
X100730Y-297310D01*
X100522Y-296225D01*
X100939Y-295140D01*
X101980Y-294365D01*
G01X113022Y-284910D02*
X110314Y-284600D01*
X108022Y-284135D01*
X105939Y-283515D01*
X103647Y-282740D01*
X100522Y-281500D01*
Y-287700D01*
G01X113439Y-272200D02*
X113230Y-272510D01*
X112814D01*
X112605Y-272200D01*
X112814Y-271890D01*
X113230D01*
X113439Y-272200D01*
G01X113022Y-260110D02*
X110314Y-259800D01*
X108022Y-259335D01*
X105939Y-258715D01*
X103647Y-257940D01*
X100522Y-256700D01*
Y-262900D01*
G01X102605Y-250345D02*
X101356Y-249415D01*
X100730Y-248330D01*
X100522Y-247090D01*
X100939Y-245540D01*
X101980Y-244455D01*
X103230Y-244145D01*
X104481Y-244300D01*
X105522Y-244920D01*
X107605Y-248020D01*
X109064Y-249415D01*
X111147Y-250345D01*
X113022Y-250655D01*
Y-244145D01*
G01X102605Y-215745D02*
X101356Y-214815D01*
X100730Y-213730D01*
X100522Y-212490D01*
X100939Y-210940D01*
X101980Y-209855D01*
X103230Y-209545D01*
X104481Y-209700D01*
X105522Y-210320D01*
X107605Y-213420D01*
X109064Y-214815D01*
X111147Y-215745D01*
X113022Y-216055D01*
Y-209545D01*
G01Y-200710D02*
X110314Y-200400D01*
X108022Y-199935D01*
X105939Y-199315D01*
X103647Y-198540D01*
X100522Y-197300D01*
Y-203500D01*
G01X113439Y-188000D02*
X113230Y-188310D01*
X112814D01*
X112605Y-188000D01*
X112814Y-187690D01*
X113230D01*
X113439Y-188000D01*
G01X113022Y-175600D02*
X100522D01*
X103022Y-177460D01*
G01X113022D02*
Y-173740D01*
G01X102605Y-166145D02*
X101356Y-165215D01*
X100730Y-164130D01*
X100522Y-162890D01*
X100939Y-161340D01*
X101980Y-160255D01*
X103230Y-159945D01*
X104481Y-160100D01*
X105522Y-160720D01*
X107605Y-163820D01*
X109064Y-165215D01*
X111147Y-166145D01*
X113022Y-166455D01*
Y-159945D01*
G01X95100Y-77042D02*
X94050Y-77825D01*
X93000Y-78217D01*
X88800D01*
X87750Y-77825D01*
X86700Y-77042D01*
G01X93000Y-71917D02*
X86700D01*
Y-70037D01*
X87015Y-69410D01*
X87750Y-68940D01*
X88590Y-68783D01*
X89430Y-68940D01*
X90060Y-69332D01*
X90375Y-70037D01*
Y-71917D01*
G01X88800Y-64050D02*
X93000D01*
G01X87120D02*
X87015Y-64207D01*
X86805D01*
X86700Y-64050D01*
X86805Y-63893D01*
X87015D01*
X87120Y-64050D01*
G01X93000Y-59082D02*
X88800D01*
G01X89850D02*
X89325Y-58768D01*
X88905Y-58298D01*
X88800Y-57672D01*
X88905Y-57123D01*
X89325Y-56653D01*
X90060Y-56418D01*
X93000D01*
G01X87225Y-43427D02*
X86910Y-43897D01*
X86700Y-44445D01*
Y-45072D01*
X87015Y-45777D01*
X87540Y-46325D01*
X88170Y-46717D01*
X89220Y-47030D01*
X90165Y-47108D01*
X91110Y-46952D01*
X91740Y-46717D01*
X92370Y-46247D01*
X92790Y-45698D01*
X93000Y-45150D01*
Y-44602D01*
X92790Y-44053D01*
X92475Y-43583D01*
X92055Y-43192D01*
G01X90165Y-40025D02*
Y-37518D01*
X89430Y-37753D01*
X89010Y-38145D01*
X88800Y-38693D01*
X88905Y-39242D01*
X89220Y-39712D01*
X89955Y-40025D01*
X90585Y-40182D01*
X91215D01*
X91845Y-40025D01*
X92475Y-39633D01*
X92895Y-39163D01*
X93000Y-38615D01*
X92790Y-38067D01*
X92160Y-37518D01*
G01X93000Y-33882D02*
X88800D01*
G01X89850D02*
X89325Y-33568D01*
X88905Y-33098D01*
X88800Y-32472D01*
X88905Y-31923D01*
X89325Y-31453D01*
X90060Y-31218D01*
X93000D01*
G01X86700Y-26250D02*
X93000D01*
G01X88800Y-27347D02*
Y-25153D01*
G01X90165Y-21125D02*
Y-18618D01*
X89430Y-18853D01*
X89010Y-19245D01*
X88800Y-19793D01*
X88905Y-20342D01*
X89220Y-20812D01*
X89955Y-21125D01*
X90585Y-21282D01*
X91215D01*
X91845Y-21125D01*
X92475Y-20733D01*
X92895Y-20263D01*
X93000Y-19715D01*
X92790Y-19167D01*
X92160Y-18618D01*
G01X93000Y-14747D02*
X88800D01*
G01X89640D02*
X89220Y-14355D01*
X88905Y-13963D01*
X88800Y-13415D01*
X88905Y-13023D01*
X89220Y-12553D01*
G01X95100Y-6958D02*
X94050Y-6175D01*
X93000Y-5783D01*
X88800D01*
X87750Y-6175D01*
X86700Y-6958D01*
G01X93178Y225021D02*
X85678D01*
Y227261D01*
X86053Y228008D01*
X86928Y228568D01*
X87928Y228755D01*
X88928Y228568D01*
X89678Y228101D01*
X90053Y227261D01*
Y225021D01*
G01X86303Y236441D02*
X85928Y235881D01*
X85678Y235228D01*
Y234481D01*
X86053Y233641D01*
X86678Y232988D01*
X87428Y232521D01*
X88678Y232148D01*
X89803Y232055D01*
X90928Y232241D01*
X91678Y232521D01*
X92428Y233081D01*
X92928Y233735D01*
X93178Y234388D01*
Y235041D01*
X92928Y235695D01*
X92553Y236255D01*
X92053Y236721D01*
G01X89178Y242635D02*
X88803Y243008D01*
X88178Y243288D01*
X87303Y243475D01*
X86553Y243288D01*
X86053Y242915D01*
X85678Y242261D01*
Y239741D01*
X93178D01*
Y242821D01*
X92678Y243475D01*
X91928Y243848D01*
X91053Y244035D01*
X90178Y243848D01*
X89428Y243288D01*
X89178Y242635D01*
Y239741D01*
G01X85678Y254555D02*
X93178Y256888D01*
X85678Y259221D01*
G01X93178Y266255D02*
Y262521D01*
X85678D01*
Y266255D01*
G01X89303Y264761D02*
Y262521D01*
G01X93178Y269741D02*
X85678D01*
X93178Y274035D01*
X85678D01*
G01X93178Y277335D02*
X85678D01*
Y279201D01*
X86053Y279948D01*
X86553Y280508D01*
X87303Y280975D01*
X88178Y281348D01*
X89428Y281441D01*
X90678Y281348D01*
X91553Y280975D01*
X92303Y280508D01*
X92803Y279948D01*
X93178Y279201D01*
Y277335D01*
G01Y286888D02*
X93053Y286141D01*
X92553Y285488D01*
X91803Y284928D01*
X90928Y284555D01*
X89928Y284368D01*
X88928D01*
X87928Y284555D01*
X87053Y284928D01*
X86303Y285488D01*
X85803Y286141D01*
X85678Y286888D01*
X85803Y287635D01*
X86303Y288288D01*
X87053Y288848D01*
X87928Y289221D01*
X88928Y289408D01*
X89928D01*
X90928Y289221D01*
X91803Y288848D01*
X92553Y288288D01*
X93053Y287635D01*
X93178Y286888D01*
G01Y292521D02*
X85678D01*
Y294855D01*
X86053Y295601D01*
X86553Y296068D01*
X87553Y296255D01*
X88553Y296068D01*
X89178Y295508D01*
X89553Y294855D01*
Y292521D01*
G01Y294855D02*
X93178Y296255D01*
G01X95522Y1352230D02*
X83022D01*
X85522Y1350370D01*
G01X95522D02*
Y1354090D01*
G01X83022Y1364630D02*
X83439Y1363390D01*
X84480Y1362460D01*
X85730Y1361840D01*
X87397Y1361375D01*
X89272Y1361220D01*
X91147Y1361375D01*
X92814Y1361840D01*
X94064Y1362460D01*
X95105Y1363390D01*
X95522Y1364630D01*
X95105Y1365870D01*
X94064Y1366800D01*
X92814Y1367420D01*
X91147Y1367885D01*
X89272Y1368040D01*
X87397Y1367885D01*
X85730Y1367420D01*
X84480Y1366800D01*
X83439Y1365870D01*
X83022Y1364630D01*
G01X95522Y1377030D02*
X83022D01*
X85522Y1375170D01*
G01X95522D02*
Y1378890D01*
G01Y1389120D02*
X92814Y1389430D01*
X90522Y1389895D01*
X88439Y1390515D01*
X86147Y1391290D01*
X83022Y1392530D01*
Y1386330D01*
G01X95939Y1401830D02*
X95730Y1401520D01*
X95314D01*
X95105Y1401830D01*
X95314Y1402140D01*
X95730D01*
X95939Y1401830D01*
G01X95522Y1413920D02*
X92814Y1414230D01*
X90522Y1414695D01*
X88439Y1415315D01*
X86147Y1416090D01*
X83022Y1417330D01*
Y1411130D01*
G01X85105Y1423685D02*
X83856Y1424615D01*
X83230Y1425700D01*
X83022Y1426940D01*
X83439Y1428490D01*
X84480Y1429575D01*
X85730Y1429885D01*
X86981Y1429730D01*
X88022Y1429110D01*
X90105Y1426010D01*
X91564Y1424615D01*
X93647Y1423685D01*
X95522Y1423375D01*
Y1429885D01*
G01X82940Y1504125D02*
X83870Y1503083D01*
X84955Y1502458D01*
X86350Y1502250D01*
X87745Y1502667D01*
X88830Y1503500D01*
X89605Y1504958D01*
X89760Y1506625D01*
X89450Y1508292D01*
X88675Y1509333D01*
X87590Y1510167D01*
X86505Y1510375D01*
X85420Y1510167D01*
X84025Y1509333D01*
X84490Y1514750D01*
X88675D01*
G01X98750Y1502250D02*
Y1514750D01*
X96890Y1512250D01*
G01Y1502250D02*
X100610D01*
G01X111150Y1501833D02*
X110840Y1502042D01*
Y1502458D01*
X111150Y1502667D01*
X111460Y1502458D01*
Y1502042D01*
X111150Y1501833D01*
G01X123240Y1502250D02*
X123550Y1504958D01*
X124015Y1507250D01*
X124635Y1509333D01*
X125410Y1511625D01*
X126650Y1514750D01*
X120450D01*
G01X128100Y-77042D02*
X127050Y-77825D01*
X126000Y-78217D01*
X121800D01*
X120750Y-77825D01*
X119700Y-77042D01*
G01X126000Y-71917D02*
X119700D01*
Y-70037D01*
X120015Y-69410D01*
X120750Y-68940D01*
X121590Y-68783D01*
X122430Y-68940D01*
X123060Y-69332D01*
X123375Y-70037D01*
Y-71917D01*
G01X121800Y-64050D02*
X126000D01*
G01X120120D02*
X120015Y-64207D01*
X119805D01*
X119700Y-64050D01*
X119805Y-63893D01*
X120015D01*
X120120Y-64050D01*
G01X126000Y-59082D02*
X121800D01*
G01X122850D02*
X122325Y-58768D01*
X121905Y-58298D01*
X121800Y-57672D01*
X121905Y-57123D01*
X122325Y-56653D01*
X123060Y-56418D01*
X126000D01*
G01X120225Y-43427D02*
X119910Y-43897D01*
X119700Y-44445D01*
Y-45072D01*
X120015Y-45777D01*
X120540Y-46325D01*
X121170Y-46717D01*
X122220Y-47030D01*
X123165Y-47108D01*
X124110Y-46952D01*
X124740Y-46717D01*
X125370Y-46247D01*
X125790Y-45698D01*
X126000Y-45150D01*
Y-44602D01*
X125790Y-44053D01*
X125475Y-43583D01*
X125055Y-43192D01*
G01X123165Y-40025D02*
Y-37518D01*
X122430Y-37753D01*
X122010Y-38145D01*
X121800Y-38693D01*
X121905Y-39242D01*
X122220Y-39712D01*
X122955Y-40025D01*
X123585Y-40182D01*
X124215D01*
X124845Y-40025D01*
X125475Y-39633D01*
X125895Y-39163D01*
X126000Y-38615D01*
X125790Y-38067D01*
X125160Y-37518D01*
G01X126000Y-33882D02*
X121800D01*
G01X122850D02*
X122325Y-33568D01*
X121905Y-33098D01*
X121800Y-32472D01*
X121905Y-31923D01*
X122325Y-31453D01*
X123060Y-31218D01*
X126000D01*
G01X119700Y-26250D02*
X126000D01*
G01X121800Y-27347D02*
Y-25153D01*
G01X123165Y-21125D02*
Y-18618D01*
X122430Y-18853D01*
X122010Y-19245D01*
X121800Y-19793D01*
X121905Y-20342D01*
X122220Y-20812D01*
X122955Y-21125D01*
X123585Y-21282D01*
X124215D01*
X124845Y-21125D01*
X125475Y-20733D01*
X125895Y-20263D01*
X126000Y-19715D01*
X125790Y-19167D01*
X125160Y-18618D01*
G01X126000Y-14747D02*
X121800D01*
G01X122640D02*
X122220Y-14355D01*
X121905Y-13963D01*
X121800Y-13415D01*
X121905Y-13023D01*
X122220Y-12553D01*
G01X128100Y-6958D02*
X127050Y-6175D01*
X126000Y-5783D01*
X121800D01*
X120750Y-6175D01*
X119700Y-6958D01*
G01X129980Y219553D02*
X122480D01*
Y221793D01*
X122855Y222540D01*
X123730Y223100D01*
X124730Y223287D01*
X125730Y223100D01*
X126480Y222633D01*
X126855Y221793D01*
Y219553D01*
G01X122480Y228920D02*
X129980D01*
G01X122480Y226773D02*
Y231067D01*
G01X129980Y234460D02*
X122480D01*
G01Y238380D02*
X129980D01*
G01X126230D02*
Y234460D01*
G01X101426Y247521D02*
X108926D01*
Y251255D01*
G01Y256888D02*
X108801Y256141D01*
X108301Y255488D01*
X107551Y254928D01*
X106676Y254555D01*
X105676Y254368D01*
X104676D01*
X103676Y254555D01*
X102801Y254928D01*
X102051Y255488D01*
X101551Y256141D01*
X101426Y256888D01*
X101551Y257635D01*
X102051Y258288D01*
X102801Y258848D01*
X103676Y259221D01*
X104676Y259408D01*
X105676D01*
X106676Y259221D01*
X107551Y258848D01*
X108301Y258288D01*
X108801Y257635D01*
X108926Y256888D01*
G01X105176Y264948D02*
Y266815D01*
X107426D01*
X108176Y266255D01*
X108676Y265601D01*
X108926Y264668D01*
X108676Y263735D01*
X108176Y263081D01*
X107426Y262521D01*
X106551Y262148D01*
X105551Y261961D01*
X104676D01*
X103926Y262148D01*
X103051Y262521D01*
X102301Y263081D01*
X101801Y263641D01*
X101426Y264388D01*
Y265041D01*
X101676Y265788D01*
X102176Y266348D01*
G01X108926Y271888D02*
X108801Y271141D01*
X108301Y270488D01*
X107551Y269928D01*
X106676Y269555D01*
X105676Y269368D01*
X104676D01*
X103676Y269555D01*
X102801Y269928D01*
X102051Y270488D01*
X101551Y271141D01*
X101426Y271888D01*
X101551Y272635D01*
X102051Y273288D01*
X102801Y273848D01*
X103676Y274221D01*
X104676Y274408D01*
X105676D01*
X106676Y274221D01*
X107551Y273848D01*
X108301Y273288D01*
X108801Y272635D01*
X108926Y271888D01*
G01X106513Y980670D02*
Y988170D01*
X108753D01*
X109500Y987795D01*
X110060Y986920D01*
X110247Y985920D01*
X110060Y984920D01*
X109593Y984170D01*
X108753Y983795D01*
X106513D01*
G01X115880Y988170D02*
Y980670D01*
G01X113733Y988170D02*
X118027D01*
G01X121420Y980670D02*
Y988170D01*
G01X125340D02*
Y980670D01*
G01Y984420D02*
X121420D01*
G01X110105Y1361835D02*
X108856Y1362765D01*
X108230Y1363850D01*
X108022Y1365090D01*
X108439Y1366640D01*
X109480Y1367725D01*
X110730Y1368035D01*
X111981Y1367880D01*
X113022Y1367260D01*
X115105Y1364160D01*
X116564Y1362765D01*
X118647Y1361835D01*
X120522Y1361525D01*
Y1368035D01*
G01X118647Y1373770D02*
X119689Y1374700D01*
X120314Y1375785D01*
X120522Y1377180D01*
X120105Y1378575D01*
X119272Y1379660D01*
X117814Y1380435D01*
X116147Y1380590D01*
X114480Y1380280D01*
X113439Y1379505D01*
X112605Y1378420D01*
X112397Y1377335D01*
X112605Y1376250D01*
X113439Y1374855D01*
X108022Y1375320D01*
Y1379505D01*
G01X120939Y1389580D02*
X120730Y1389270D01*
X120314D01*
X120105Y1389580D01*
X120314Y1389890D01*
X120730D01*
X120939Y1389580D01*
G01X120522Y1401980D02*
X120314Y1403065D01*
X119689Y1404305D01*
X118647Y1405080D01*
X117189Y1405390D01*
X115731Y1405080D01*
X114480Y1404150D01*
X113855Y1402755D01*
Y1401205D01*
X113439Y1400275D01*
X112397Y1399500D01*
X110939Y1399190D01*
X109480Y1399655D01*
X108439Y1400740D01*
X108022Y1401980D01*
X108439Y1403220D01*
X109480Y1404305D01*
X110939Y1404770D01*
X112397Y1404460D01*
X113439Y1403685D01*
X113855Y1402755D01*
Y1401205D01*
X114480Y1399810D01*
X115731Y1398880D01*
X117189Y1398570D01*
X118647Y1398880D01*
X119689Y1399655D01*
X120314Y1400895D01*
X120522Y1401980D01*
G01X118647Y1410970D02*
X119689Y1411900D01*
X120314Y1412985D01*
X120522Y1414380D01*
X120105Y1415775D01*
X119272Y1416860D01*
X117814Y1417635D01*
X116147Y1417790D01*
X114480Y1417480D01*
X113439Y1416705D01*
X112605Y1415620D01*
X112397Y1414535D01*
X112605Y1413450D01*
X113439Y1412055D01*
X108022Y1412520D01*
Y1416705D01*
G01X140250Y-319422D02*
X127750D01*
X130250Y-321282D01*
G01X140250D02*
Y-317562D01*
G01Y-307022D02*
X127750D01*
X130250Y-308882D01*
G01X140250D02*
Y-305162D01*
G01X135042Y-297567D02*
X133583Y-296482D01*
X132750Y-295552D01*
X132333Y-294312D01*
X132750Y-293227D01*
X133583Y-292452D01*
X134833Y-291832D01*
X136292Y-291677D01*
X137542Y-291832D01*
X138792Y-292452D01*
X139833Y-293382D01*
X140250Y-294467D01*
X139833Y-295707D01*
X138584Y-296792D01*
X136708Y-297412D01*
X134625Y-297567D01*
X131917Y-297257D01*
X130458Y-296792D01*
X129000Y-296017D01*
X127958Y-294932D01*
X127750Y-293847D01*
X128167Y-292762D01*
X129208Y-291987D01*
G01X140250Y-282532D02*
X137542Y-282222D01*
X135250Y-281757D01*
X133167Y-281137D01*
X130875Y-280362D01*
X127750Y-279122D01*
Y-285322D01*
G01X140667Y-269822D02*
X140458Y-270132D01*
X140042D01*
X139833Y-269822D01*
X140042Y-269512D01*
X140458D01*
X140667Y-269822D01*
G01X140250Y-257732D02*
X137542Y-257422D01*
X135250Y-256957D01*
X133167Y-256337D01*
X130875Y-255562D01*
X127750Y-254322D01*
Y-260522D01*
G01X129833Y-247967D02*
X128584Y-247037D01*
X127958Y-245952D01*
X127750Y-244712D01*
X128167Y-243162D01*
X129208Y-242077D01*
X130458Y-241767D01*
X131709Y-241922D01*
X132750Y-242542D01*
X134833Y-245642D01*
X136292Y-247037D01*
X138375Y-247967D01*
X140250Y-248277D01*
Y-241767D01*
G01X129833Y-213367D02*
X128584Y-212437D01*
X127958Y-211352D01*
X127750Y-210112D01*
X128167Y-208562D01*
X129208Y-207477D01*
X130458Y-207167D01*
X131709Y-207322D01*
X132750Y-207942D01*
X134833Y-211042D01*
X136292Y-212437D01*
X138375Y-213367D01*
X140250Y-213677D01*
Y-207167D01*
G01X138792Y-200657D02*
X139833Y-199572D01*
X140250Y-198332D01*
X139833Y-197092D01*
X138584Y-196007D01*
X136708Y-195232D01*
X134833Y-194922D01*
X132542D01*
X130667Y-195232D01*
X129000Y-196007D01*
X128167Y-196937D01*
X127750Y-198022D01*
X128167Y-199262D01*
X129000Y-200192D01*
X130250Y-200812D01*
X131917Y-201122D01*
X133375Y-200812D01*
X134833Y-200037D01*
X135667Y-199107D01*
X135875Y-198022D01*
X135459Y-196782D01*
X134417Y-195852D01*
X132542Y-194922D01*
G01X140667Y-185622D02*
X140458Y-185932D01*
X140042D01*
X139833Y-185622D01*
X140042Y-185312D01*
X140458D01*
X140667Y-185622D01*
G01X135042Y-176167D02*
X133583Y-175082D01*
X132750Y-174152D01*
X132333Y-172912D01*
X132750Y-171827D01*
X133583Y-171052D01*
X134833Y-170432D01*
X136292Y-170277D01*
X137542Y-170432D01*
X138792Y-171052D01*
X139833Y-171982D01*
X140250Y-173067D01*
X139833Y-174307D01*
X138584Y-175392D01*
X136708Y-176012D01*
X134625Y-176167D01*
X131917Y-175857D01*
X130458Y-175392D01*
X129000Y-174617D01*
X127958Y-173532D01*
X127750Y-172447D01*
X128167Y-171362D01*
X129208Y-170587D01*
G01X135042Y-163767D02*
X133583Y-162682D01*
X132750Y-161752D01*
X132333Y-160512D01*
X132750Y-159427D01*
X133583Y-158652D01*
X134833Y-158032D01*
X136292Y-157877D01*
X137542Y-158032D01*
X138792Y-158652D01*
X139833Y-159582D01*
X140250Y-160667D01*
X139833Y-161907D01*
X138584Y-162992D01*
X136708Y-163612D01*
X134625Y-163767D01*
X131917Y-163457D01*
X130458Y-162992D01*
X129000Y-162217D01*
X127958Y-161132D01*
X127750Y-160047D01*
X128167Y-158962D01*
X129208Y-158187D01*
G01X154577Y1355980D02*
X142077D01*
X144577Y1354120D01*
G01X154577D02*
Y1357840D01*
G01X149369Y1365435D02*
X147910Y1366520D01*
X147077Y1367450D01*
X146660Y1368690D01*
X147077Y1369775D01*
X147910Y1370550D01*
X149160Y1371170D01*
X150619Y1371325D01*
X151869Y1371170D01*
X153119Y1370550D01*
X154160Y1369620D01*
X154577Y1368535D01*
X154160Y1367295D01*
X152911Y1366210D01*
X151035Y1365590D01*
X148952Y1365435D01*
X146244Y1365745D01*
X144785Y1366210D01*
X143327Y1366985D01*
X142285Y1368070D01*
X142077Y1369155D01*
X142494Y1370240D01*
X143535Y1371015D01*
G01X142077Y1380780D02*
X142494Y1379540D01*
X143535Y1378610D01*
X144785Y1377990D01*
X146452Y1377525D01*
X148327Y1377370D01*
X150202Y1377525D01*
X151869Y1377990D01*
X153119Y1378610D01*
X154160Y1379540D01*
X154577Y1380780D01*
X154160Y1382020D01*
X153119Y1382950D01*
X151869Y1383570D01*
X150202Y1384035D01*
X148327Y1384190D01*
X146452Y1384035D01*
X144785Y1383570D01*
X143535Y1382950D01*
X142494Y1382020D01*
X142077Y1380780D01*
G01X154577Y1393180D02*
X154369Y1394265D01*
X153744Y1395505D01*
X152702Y1396280D01*
X151244Y1396590D01*
X149786Y1396280D01*
X148535Y1395350D01*
X147910Y1393955D01*
Y1392405D01*
X147494Y1391475D01*
X146452Y1390700D01*
X144994Y1390390D01*
X143535Y1390855D01*
X142494Y1391940D01*
X142077Y1393180D01*
X142494Y1394420D01*
X143535Y1395505D01*
X144994Y1395970D01*
X146452Y1395660D01*
X147494Y1394885D01*
X147910Y1393955D01*
Y1392405D01*
X148535Y1391010D01*
X149786Y1390080D01*
X151244Y1389770D01*
X152702Y1390080D01*
X153744Y1390855D01*
X154369Y1392095D01*
X154577Y1393180D01*
G01X154994Y1405580D02*
X154785Y1405270D01*
X154369D01*
X154160Y1405580D01*
X154369Y1405890D01*
X154785D01*
X154994Y1405580D01*
G01X144160Y1415035D02*
X142911Y1415965D01*
X142285Y1417050D01*
X142077Y1418290D01*
X142494Y1419840D01*
X143535Y1420925D01*
X144785Y1421235D01*
X146036Y1421080D01*
X147077Y1420460D01*
X149160Y1417360D01*
X150619Y1415965D01*
X152702Y1415035D01*
X154577Y1414725D01*
Y1421235D01*
G01Y1430070D02*
X151869Y1430380D01*
X149577Y1430845D01*
X147494Y1431465D01*
X145202Y1432240D01*
X142077Y1433480D01*
Y1427280D01*
G01X179577Y1370390D02*
X167077D01*
X176035Y1364655D01*
Y1372405D01*
G01X167077Y1380930D02*
X167494Y1379690D01*
X168535Y1378760D01*
X169785Y1378140D01*
X171452Y1377675D01*
X173327Y1377520D01*
X175202Y1377675D01*
X176869Y1378140D01*
X178119Y1378760D01*
X179160Y1379690D01*
X179577Y1380930D01*
X179160Y1382170D01*
X178119Y1383100D01*
X176869Y1383720D01*
X175202Y1384185D01*
X173327Y1384340D01*
X171452Y1384185D01*
X169785Y1383720D01*
X168535Y1383100D01*
X167494Y1382170D01*
X167077Y1380930D01*
G01X179994Y1393330D02*
X179785Y1393020D01*
X179369D01*
X179160Y1393330D01*
X179369Y1393640D01*
X179785D01*
X179994Y1393330D01*
G01X179577Y1405730D02*
X179369Y1406815D01*
X178744Y1408055D01*
X177702Y1408830D01*
X176244Y1409140D01*
X174786Y1408830D01*
X173535Y1407900D01*
X172910Y1406505D01*
Y1404955D01*
X172494Y1404025D01*
X171452Y1403250D01*
X169994Y1402940D01*
X168535Y1403405D01*
X167494Y1404490D01*
X167077Y1405730D01*
X167494Y1406970D01*
X168535Y1408055D01*
X169994Y1408520D01*
X171452Y1408210D01*
X172494Y1407435D01*
X172910Y1406505D01*
Y1404955D01*
X173535Y1403560D01*
X174786Y1402630D01*
X176244Y1402320D01*
X177702Y1402630D01*
X178744Y1403405D01*
X179369Y1404645D01*
X179577Y1405730D01*
G01X177702Y1414720D02*
X178744Y1415650D01*
X179369Y1416735D01*
X179577Y1418130D01*
X179160Y1419525D01*
X178327Y1420610D01*
X176869Y1421385D01*
X175202Y1421540D01*
X173535Y1421230D01*
X172494Y1420455D01*
X171660Y1419370D01*
X171452Y1418285D01*
X171660Y1417200D01*
X172494Y1415805D01*
X167077Y1416270D01*
Y1420455D01*
G01X213433Y642000D02*
Y649500D01*
X215673D01*
X216420Y649125D01*
X216980Y648250D01*
X217167Y647250D01*
X216980Y646250D01*
X216513Y645500D01*
X215673Y645125D01*
X213433D01*
G01X222800Y649500D02*
Y642000D01*
G01X220653Y649500D02*
X224947D01*
G01X228340Y642000D02*
Y649500D01*
G01X232260D02*
Y642000D01*
G01Y645750D02*
X228340D01*
G01X231995Y221037D02*
X232925Y222286D01*
X234010Y222912D01*
X235250Y223120D01*
X236800Y222703D01*
X237885Y221662D01*
X238195Y220412D01*
X238040Y219161D01*
X237420Y218120D01*
X234320Y216037D01*
X232925Y214578D01*
X231995Y212495D01*
X231685Y210620D01*
X238195D01*
G01X247340Y223120D02*
X246100Y222703D01*
X245170Y221662D01*
X244550Y220412D01*
X244085Y218745D01*
X243930Y216870D01*
X244085Y214995D01*
X244550Y213328D01*
X245170Y212078D01*
X246100Y211037D01*
X247340Y210620D01*
X248580Y211037D01*
X249510Y212078D01*
X250130Y213328D01*
X250595Y214995D01*
X250750Y216870D01*
X250595Y218745D01*
X250130Y220412D01*
X249510Y221662D01*
X248580Y222703D01*
X247340Y223120D01*
G01X261600Y210620D02*
Y223120D01*
X255865Y214162D01*
X263615D01*
G01X268730Y213120D02*
X269660Y211661D01*
X270900Y210828D01*
X272295Y210620D01*
X273535Y210828D01*
X274775Y211870D01*
X275550Y213120D01*
X275705Y214370D01*
X275395Y215828D01*
X274310Y216870D01*
X273225Y217287D01*
X271830D01*
G01X273225D02*
X274155Y217912D01*
X274930Y218953D01*
X275240Y220203D01*
X274930Y221453D01*
X274155Y222495D01*
X272760Y223120D01*
X271365Y222912D01*
X269970Y222078D01*
G01X284540Y210203D02*
X284230Y210412D01*
Y210828D01*
X284540Y211037D01*
X284850Y210828D01*
Y210412D01*
X284540Y210203D01*
G01X296630Y210620D02*
X296940Y213328D01*
X297405Y215620D01*
X298025Y217703D01*
X298800Y219995D01*
X300040Y223120D01*
X293840D01*
G01X309340D02*
X308100Y222703D01*
X307170Y221662D01*
X306550Y220412D01*
X306085Y218745D01*
X305930Y216870D01*
X306085Y214995D01*
X306550Y213328D01*
X307170Y212078D01*
X308100Y211037D01*
X309340Y210620D01*
X310580Y211037D01*
X311510Y212078D01*
X312130Y213328D01*
X312595Y214995D01*
X312750Y216870D01*
X312595Y218745D01*
X312130Y220412D01*
X311510Y221662D01*
X310580Y222703D01*
X309340Y223120D01*
G01X240115Y960109D02*
X241200Y959068D01*
X242440Y958651D01*
X243680Y959068D01*
X244765Y960317D01*
X245540Y962193D01*
X245850Y964068D01*
Y966359D01*
X245540Y968234D01*
X244765Y969901D01*
X243835Y970734D01*
X242750Y971151D01*
X241510Y970734D01*
X240580Y969901D01*
X239960Y968651D01*
X239650Y966984D01*
X239960Y965526D01*
X240735Y964068D01*
X241665Y963234D01*
X242750Y963026D01*
X243990Y963442D01*
X244920Y964484D01*
X245850Y966359D01*
G01X251740Y960526D02*
X252670Y959484D01*
X253755Y958859D01*
X255150Y958651D01*
X256545Y959068D01*
X257630Y959901D01*
X258405Y961359D01*
X258560Y963026D01*
X258250Y964693D01*
X257475Y965734D01*
X256390Y966568D01*
X255305Y966776D01*
X254220Y966568D01*
X252825Y965734D01*
X253290Y971151D01*
X257475D01*
G01X264605Y969068D02*
X265535Y970317D01*
X266620Y970943D01*
X267860Y971151D01*
X269410Y970734D01*
X270495Y969693D01*
X270805Y968443D01*
X270650Y967192D01*
X270030Y966151D01*
X266930Y964068D01*
X265535Y962609D01*
X264605Y960526D01*
X264295Y958651D01*
X270805D01*
G01X281810D02*
Y971151D01*
X276075Y962193D01*
X283825D01*
G01X292350Y958234D02*
X292040Y958443D01*
Y958859D01*
X292350Y959068D01*
X292660Y958859D01*
Y958443D01*
X292350Y958234D01*
G01X304750Y971151D02*
X303510Y970734D01*
X302580Y969693D01*
X301960Y968443D01*
X301495Y966776D01*
X301340Y964901D01*
X301495Y963026D01*
X301960Y961359D01*
X302580Y960109D01*
X303510Y959068D01*
X304750Y958651D01*
X305990Y959068D01*
X306920Y960109D01*
X307540Y961359D01*
X308005Y963026D01*
X308160Y964901D01*
X308005Y966776D01*
X307540Y968443D01*
X306920Y969693D01*
X305990Y970734D01*
X304750Y971151D01*
G01X317150Y958651D02*
Y971151D01*
X315290Y968651D01*
G01Y958651D02*
X319010D01*
G01X244080Y187495D02*
X245010Y186453D01*
X246095Y185828D01*
X247490Y185620D01*
X248885Y186037D01*
X249970Y186870D01*
X250745Y188328D01*
X250900Y189995D01*
X250590Y191662D01*
X249815Y192703D01*
X248730Y193537D01*
X247645Y193745D01*
X246560Y193537D01*
X245165Y192703D01*
X245630Y198120D01*
X249815D01*
G01X259890Y185620D02*
Y198120D01*
X258030Y195620D01*
G01Y185620D02*
X261750D01*
G01X272290Y185203D02*
X271980Y185412D01*
Y185828D01*
X272290Y186037D01*
X272600Y185828D01*
Y185412D01*
X272290Y185203D01*
G01X282055Y187078D02*
X283140Y186037D01*
X284380Y185620D01*
X285620Y186037D01*
X286705Y187286D01*
X287480Y189162D01*
X287790Y191037D01*
Y193328D01*
X287480Y195203D01*
X286705Y196870D01*
X285775Y197703D01*
X284690Y198120D01*
X283450Y197703D01*
X282520Y196870D01*
X281900Y195620D01*
X281590Y193953D01*
X281900Y192495D01*
X282675Y191037D01*
X283605Y190203D01*
X284690Y189995D01*
X285930Y190411D01*
X286860Y191453D01*
X287790Y193328D01*
G01X297090Y185620D02*
Y198120D01*
X295230Y195620D01*
G01Y185620D02*
X298950D01*
G01X259400Y601963D02*
Y614463D01*
X257540Y611963D01*
G01Y601963D02*
X261260D01*
G01X268390Y603838D02*
X269320Y602796D01*
X270405Y602171D01*
X271800Y601963D01*
X273195Y602380D01*
X274280Y603213D01*
X275055Y604671D01*
X275210Y606338D01*
X274900Y608005D01*
X274125Y609046D01*
X273040Y609880D01*
X271955Y610088D01*
X270870Y609880D01*
X269475Y609046D01*
X269940Y614463D01*
X274125D01*
G01X283890Y601963D02*
X284200Y604671D01*
X284665Y606963D01*
X285285Y609046D01*
X286060Y611338D01*
X287300Y614463D01*
X281100D01*
G01X296600Y601546D02*
X296290Y601755D01*
Y602171D01*
X296600Y602380D01*
X296910Y602171D01*
Y601755D01*
X296600Y601546D01*
G01X306055Y607171D02*
X307140Y608630D01*
X308070Y609463D01*
X309310Y609880D01*
X310395Y609463D01*
X311170Y608630D01*
X311790Y607380D01*
X311945Y605921D01*
X311790Y604671D01*
X311170Y603421D01*
X310240Y602380D01*
X309155Y601963D01*
X307915Y602380D01*
X306830Y603629D01*
X306210Y605505D01*
X306055Y607588D01*
X306365Y610296D01*
X306830Y611755D01*
X307605Y613213D01*
X308690Y614255D01*
X309775Y614463D01*
X310860Y614046D01*
X311635Y613005D01*
G01X318455Y607171D02*
X319540Y608630D01*
X320470Y609463D01*
X321710Y609880D01*
X322795Y609463D01*
X323570Y608630D01*
X324190Y607380D01*
X324345Y605921D01*
X324190Y604671D01*
X323570Y603421D01*
X322640Y602380D01*
X321555Y601963D01*
X320315Y602380D01*
X319230Y603629D01*
X318610Y605505D01*
X318455Y607588D01*
X318765Y610296D01*
X319230Y611755D01*
X320005Y613213D01*
X321090Y614255D01*
X322175Y614463D01*
X323260Y614046D01*
X324035Y613005D01*
G01X250105Y632171D02*
X251190Y633630D01*
X252120Y634463D01*
X253360Y634880D01*
X254445Y634463D01*
X255220Y633630D01*
X255840Y632380D01*
X255995Y630921D01*
X255840Y629671D01*
X255220Y628421D01*
X254290Y627380D01*
X253205Y626963D01*
X251965Y627380D01*
X250880Y628629D01*
X250260Y630505D01*
X250105Y632588D01*
X250415Y635296D01*
X250880Y636755D01*
X251655Y638213D01*
X252740Y639255D01*
X253825Y639463D01*
X254910Y639046D01*
X255685Y638005D01*
G01X262505Y637380D02*
X263435Y638629D01*
X264520Y639255D01*
X265760Y639463D01*
X267310Y639046D01*
X268395Y638005D01*
X268705Y636755D01*
X268550Y635504D01*
X267930Y634463D01*
X264830Y632380D01*
X263435Y630921D01*
X262505Y628838D01*
X262195Y626963D01*
X268705D01*
G01X277850Y639463D02*
X276610Y639046D01*
X275680Y638005D01*
X275060Y636755D01*
X274595Y635088D01*
X274440Y633213D01*
X274595Y631338D01*
X275060Y629671D01*
X275680Y628421D01*
X276610Y627380D01*
X277850Y626963D01*
X279090Y627380D01*
X280020Y628421D01*
X280640Y629671D01*
X281105Y631338D01*
X281260Y633213D01*
X281105Y635088D01*
X280640Y636755D01*
X280020Y638005D01*
X279090Y639046D01*
X277850Y639463D01*
G01X289940Y626963D02*
X290250Y629671D01*
X290715Y631963D01*
X291335Y634046D01*
X292110Y636338D01*
X293350Y639463D01*
X287150D01*
G01X302650Y626546D02*
X302340Y626755D01*
Y627171D01*
X302650Y627380D01*
X302960Y627171D01*
Y626755D01*
X302650Y626546D01*
G01X315050Y626963D02*
Y639463D01*
X313190Y636963D01*
G01Y626963D02*
X316910D01*
G01X324040Y629463D02*
X324970Y628004D01*
X326210Y627171D01*
X327605Y626963D01*
X328845Y627171D01*
X330085Y628213D01*
X330860Y629463D01*
X331015Y630713D01*
X330705Y632171D01*
X329620Y633213D01*
X328535Y633630D01*
X327140D01*
G01X328535D02*
X329465Y634255D01*
X330240Y635296D01*
X330550Y636546D01*
X330240Y637796D01*
X329465Y638838D01*
X328070Y639463D01*
X326675Y639255D01*
X325280Y638421D01*
G01X246155Y944068D02*
X247085Y945317D01*
X248170Y945943D01*
X249410Y946151D01*
X250960Y945734D01*
X252045Y944693D01*
X252355Y943443D01*
X252200Y942192D01*
X251580Y941151D01*
X248480Y939068D01*
X247085Y937609D01*
X246155Y935526D01*
X245845Y933651D01*
X252355D01*
G01X263360D02*
Y946151D01*
X257625Y937193D01*
X265375D01*
G01X273900Y933651D02*
Y946151D01*
X272040Y943651D01*
G01Y933651D02*
X275760D01*
G01X286300Y933234D02*
X285990Y933443D01*
Y933859D01*
X286300Y934068D01*
X286610Y933859D01*
Y933443D01*
X286300Y933234D01*
G01X296065Y935109D02*
X297150Y934068D01*
X298390Y933651D01*
X299630Y934068D01*
X300715Y935317D01*
X301490Y937193D01*
X301800Y939068D01*
Y941359D01*
X301490Y943234D01*
X300715Y944901D01*
X299785Y945734D01*
X298700Y946151D01*
X297460Y945734D01*
X296530Y944901D01*
X295910Y943651D01*
X295600Y941984D01*
X295910Y940526D01*
X296685Y939068D01*
X297615Y938234D01*
X298700Y938026D01*
X299940Y938442D01*
X300870Y939484D01*
X301800Y941359D01*
G01X311100Y933651D02*
Y946151D01*
X309240Y943651D01*
G01Y933651D02*
X312960D01*
G01X331395Y-304184D02*
X330925Y-303869D01*
X330377Y-303659D01*
X329750D01*
X329045Y-303974D01*
X328497Y-304499D01*
X328105Y-305129D01*
X327792Y-306179D01*
X327714Y-307124D01*
X327870Y-308069D01*
X328105Y-308699D01*
X328575Y-309329D01*
X329124Y-309749D01*
X329672Y-309959D01*
X330220D01*
X330769Y-309749D01*
X331239Y-309434D01*
X331630Y-309014D01*
G01X335032Y-303659D02*
X336912D01*
G01X335972D02*
Y-309959D01*
G01X335032D02*
X336912D01*
G01X342272Y-303659D02*
Y-309959D01*
G01X340470Y-303659D02*
X344074D01*
G01X348572Y-309959D02*
Y-307124D01*
X347005Y-303659D01*
G01X350139D02*
X348572Y-307124D01*
G01X359449Y-308699D02*
X359919Y-309434D01*
X360545Y-309854D01*
X361250Y-309959D01*
X361877Y-309854D01*
X362504Y-309329D01*
X362895Y-308699D01*
X362974Y-308069D01*
X362817Y-307334D01*
X362269Y-306809D01*
X361720Y-306599D01*
X361015D01*
G01X361720D02*
X362190Y-306284D01*
X362582Y-305759D01*
X362739Y-305129D01*
X362582Y-304499D01*
X362190Y-303974D01*
X361485Y-303659D01*
X360780Y-303764D01*
X360075Y-304184D01*
G01X365749Y-308699D02*
X366219Y-309434D01*
X366845Y-309854D01*
X367550Y-309959D01*
X368177Y-309854D01*
X368804Y-309329D01*
X369195Y-308699D01*
X369274Y-308069D01*
X369117Y-307334D01*
X368569Y-306809D01*
X368020Y-306599D01*
X367315D01*
G01X368020D02*
X368490Y-306284D01*
X368882Y-305759D01*
X369039Y-305129D01*
X368882Y-304499D01*
X368490Y-303974D01*
X367785Y-303659D01*
X367080Y-303764D01*
X366375Y-304184D01*
G01X372049Y-308699D02*
X372519Y-309434D01*
X373145Y-309854D01*
X373850Y-309959D01*
X374477Y-309854D01*
X375104Y-309329D01*
X375495Y-308699D01*
X375574Y-308069D01*
X375417Y-307334D01*
X374869Y-306809D01*
X374320Y-306599D01*
X373615D01*
G01X374320D02*
X374790Y-306284D01*
X375182Y-305759D01*
X375339Y-305129D01*
X375182Y-304499D01*
X374790Y-303974D01*
X374085Y-303659D01*
X373380Y-303764D01*
X372675Y-304184D01*
G01X379915Y-309959D02*
X380072Y-308594D01*
X380307Y-307439D01*
X380620Y-306389D01*
X381012Y-305234D01*
X381639Y-303659D01*
X378505D01*
G01X386215Y-309959D02*
X386372Y-308594D01*
X386607Y-307439D01*
X386920Y-306389D01*
X387312Y-305234D01*
X387939Y-303659D01*
X384805D01*
G01X392515Y-311114D02*
X392829Y-309749D01*
G01X398972Y-303659D02*
Y-309959D01*
G01X397170Y-303659D02*
X400774D01*
G01X403314Y-309959D02*
X405272Y-303659D01*
X407230Y-309959D01*
G01X406525Y-307754D02*
X404019D01*
G01X410632Y-303659D02*
X412512D01*
G01X411572D02*
Y-309959D01*
G01X410632D02*
X412512D01*
G01X415522Y-303659D02*
X416619Y-309959D01*
X417872Y-303659D01*
X419125Y-309959D01*
X420222Y-303659D01*
G01X422214Y-309959D02*
X424172Y-303659D01*
X426130Y-309959D01*
G01X425425Y-307754D02*
X422919D01*
G01X428670Y-309959D02*
Y-303659D01*
X432274Y-309959D01*
Y-303659D01*
G01X442680Y-312059D02*
X441897Y-311009D01*
X441505Y-309959D01*
Y-305759D01*
X441897Y-304709D01*
X442680Y-303659D01*
G01X454105Y-309959D02*
Y-303659D01*
X456064D01*
X456690Y-303974D01*
X457082Y-304394D01*
X457239Y-305234D01*
X457082Y-306074D01*
X456612Y-306599D01*
X456064Y-306914D01*
X454105D01*
G01X456064D02*
X457239Y-309959D01*
G01X461972Y-310169D02*
X461815Y-310064D01*
Y-309854D01*
X461972Y-309749D01*
X462129Y-309854D01*
Y-310064D01*
X461972Y-310169D01*
G01X468272Y-309959D02*
X467645Y-309854D01*
X467097Y-309434D01*
X466627Y-308804D01*
X466314Y-308069D01*
X466157Y-307229D01*
Y-306389D01*
X466314Y-305549D01*
X466627Y-304814D01*
X467097Y-304184D01*
X467645Y-303764D01*
X468272Y-303659D01*
X468899Y-303764D01*
X469447Y-304184D01*
X469917Y-304814D01*
X470230Y-305549D01*
X470387Y-306389D01*
Y-307229D01*
X470230Y-308069D01*
X469917Y-308804D01*
X469447Y-309434D01*
X468899Y-309854D01*
X468272Y-309959D01*
G01X474572Y-310169D02*
X474415Y-310064D01*
Y-309854D01*
X474572Y-309749D01*
X474729Y-309854D01*
Y-310064D01*
X474572Y-310169D01*
G01X482595Y-304184D02*
X482125Y-303869D01*
X481577Y-303659D01*
X480950D01*
X480245Y-303974D01*
X479697Y-304499D01*
X479305Y-305129D01*
X478992Y-306179D01*
X478914Y-307124D01*
X479070Y-308069D01*
X479305Y-308699D01*
X479775Y-309329D01*
X480324Y-309749D01*
X480872Y-309959D01*
X481420D01*
X481969Y-309749D01*
X482439Y-309434D01*
X482830Y-309014D01*
G01X487172Y-310169D02*
X487015Y-310064D01*
Y-309854D01*
X487172Y-309749D01*
X487329Y-309854D01*
Y-310064D01*
X487172Y-310169D01*
G01X493864Y-312059D02*
X494647Y-311009D01*
X495039Y-309959D01*
Y-305759D01*
X494647Y-304709D01*
X493864Y-303659D01*
G01X330142Y-296809D02*
X331709D01*
Y-298699D01*
X331239Y-299329D01*
X330690Y-299749D01*
X329907Y-299959D01*
X329124Y-299749D01*
X328575Y-299329D01*
X328105Y-298699D01*
X327792Y-297964D01*
X327635Y-297124D01*
Y-296389D01*
X327792Y-295759D01*
X328105Y-295024D01*
X328575Y-294394D01*
X329045Y-293974D01*
X329672Y-293659D01*
X330220D01*
X330847Y-293869D01*
X331317Y-294289D01*
G01X334249Y-293659D02*
Y-298174D01*
X334562Y-299119D01*
X335189Y-299749D01*
X335972Y-299959D01*
X336755Y-299749D01*
X337382Y-299119D01*
X337695Y-298174D01*
Y-293659D01*
G01X341332D02*
X343212D01*
G01X342272D02*
Y-299959D01*
G01X341332D02*
X343212D01*
G01X346927Y-299119D02*
X347554Y-299644D01*
X348259Y-299959D01*
X348885D01*
X349512Y-299644D01*
X349982Y-299119D01*
X350217Y-298384D01*
X350060Y-297649D01*
X349669Y-297019D01*
X348964Y-296599D01*
X348024Y-296389D01*
X347475Y-295969D01*
X347240Y-295234D01*
X347397Y-294499D01*
X347789Y-293974D01*
X348337Y-293659D01*
X348885D01*
X349434Y-293869D01*
X349904Y-294394D01*
G01X353227Y-299959D02*
Y-293659D01*
G01X356517D02*
Y-299959D01*
G01Y-296809D02*
X353227D01*
G01X359214Y-299959D02*
X361172Y-293659D01*
X363130Y-299959D01*
G01X362425Y-297754D02*
X359919D01*
G01X365670Y-299959D02*
Y-293659D01*
X369274Y-299959D01*
Y-293659D01*
G01X378349Y-299959D02*
Y-293659D01*
X379915D01*
X380542Y-293974D01*
X381012Y-294394D01*
X381404Y-295024D01*
X381717Y-295759D01*
X381795Y-296809D01*
X381717Y-297859D01*
X381404Y-298594D01*
X381012Y-299224D01*
X380542Y-299644D01*
X379915Y-299959D01*
X378349D01*
G01X385432Y-293659D02*
X387312D01*
G01X386372D02*
Y-299959D01*
G01X385432D02*
X387312D01*
G01X391027Y-299119D02*
X391654Y-299644D01*
X392359Y-299959D01*
X392985D01*
X393612Y-299644D01*
X394082Y-299119D01*
X394317Y-298384D01*
X394160Y-297649D01*
X393769Y-297019D01*
X393064Y-296599D01*
X392124Y-296389D01*
X391575Y-295969D01*
X391340Y-295234D01*
X391497Y-294499D01*
X391889Y-293974D01*
X392437Y-293659D01*
X392985D01*
X393534Y-293869D01*
X394004Y-294394D01*
G01X398972Y-293659D02*
Y-299959D01*
G01X397170Y-293659D02*
X400774D01*
G01X405272Y-300169D02*
X405115Y-300064D01*
Y-299854D01*
X405272Y-299749D01*
X405429Y-299854D01*
Y-300064D01*
X405272Y-300169D01*
G01X411415Y-301114D02*
X411729Y-299749D01*
G01X417872Y-293659D02*
Y-299959D01*
G01X416070Y-293659D02*
X419674D01*
G01X422214Y-299959D02*
X424172Y-293659D01*
X426130Y-299959D01*
G01X425425Y-297754D02*
X422919D01*
G01X430472Y-299959D02*
X429845Y-299854D01*
X429297Y-299434D01*
X428827Y-298804D01*
X428514Y-298069D01*
X428357Y-297229D01*
Y-296389D01*
X428514Y-295549D01*
X428827Y-294814D01*
X429297Y-294184D01*
X429845Y-293764D01*
X430472Y-293659D01*
X431099Y-293764D01*
X431647Y-294184D01*
X432117Y-294814D01*
X432430Y-295549D01*
X432587Y-296389D01*
Y-297229D01*
X432430Y-298069D01*
X432117Y-298804D01*
X431647Y-299434D01*
X431099Y-299854D01*
X430472Y-299959D01*
G01X436772D02*
Y-297124D01*
X435205Y-293659D01*
G01X438339D02*
X436772Y-297124D01*
G01X441349Y-293659D02*
Y-298174D01*
X441662Y-299119D01*
X442289Y-299749D01*
X443072Y-299959D01*
X443855Y-299749D01*
X444482Y-299119D01*
X444795Y-298174D01*
Y-293659D01*
G01X447414Y-299959D02*
X449372Y-293659D01*
X451330Y-299959D01*
G01X450625Y-297754D02*
X448119D01*
G01X453870Y-299959D02*
Y-293659D01*
X457474Y-299959D01*
Y-293659D01*
G01X327870Y-289959D02*
Y-283659D01*
X331474Y-289959D01*
Y-283659D01*
G01X335972Y-289959D02*
X335345Y-289854D01*
X334797Y-289434D01*
X334327Y-288804D01*
X334014Y-288069D01*
X333857Y-287229D01*
Y-286389D01*
X334014Y-285549D01*
X334327Y-284814D01*
X334797Y-284184D01*
X335345Y-283764D01*
X335972Y-283659D01*
X336599Y-283764D01*
X337147Y-284184D01*
X337617Y-284814D01*
X337930Y-285549D01*
X338087Y-286389D01*
Y-287229D01*
X337930Y-288069D01*
X337617Y-288804D01*
X337147Y-289434D01*
X336599Y-289854D01*
X335972Y-289959D01*
G01X342272Y-290169D02*
X342115Y-290064D01*
Y-289854D01*
X342272Y-289749D01*
X342429Y-289854D01*
Y-290064D01*
X342272Y-290169D01*
G01X347084Y-284709D02*
X347554Y-284079D01*
X348102Y-283764D01*
X348729Y-283659D01*
X349512Y-283869D01*
X350060Y-284394D01*
X350217Y-285024D01*
X350139Y-285654D01*
X349825Y-286179D01*
X348259Y-287229D01*
X347554Y-287964D01*
X347084Y-289014D01*
X346927Y-289959D01*
X350217D01*
G01X354872D02*
Y-283659D01*
X353932Y-284919D01*
G01Y-289959D02*
X355812D01*
G01X361172D02*
Y-283659D01*
X360232Y-284919D01*
G01Y-289959D02*
X362112D01*
G01X367315Y-291114D02*
X367629Y-289749D01*
G01X371422Y-283659D02*
X372519Y-289959D01*
X373772Y-283659D01*
X375025Y-289959D01*
X376122Y-283659D01*
G01X381639Y-289959D02*
X378505D01*
Y-283659D01*
X381639D01*
G01X380385Y-286704D02*
X378505D01*
G01X384570Y-289959D02*
Y-283659D01*
X388174Y-289959D01*
Y-283659D01*
G01X391027Y-289959D02*
Y-283659D01*
G01X394317D02*
Y-289959D01*
G01Y-286809D02*
X391027D01*
G01X397249Y-283659D02*
Y-288174D01*
X397562Y-289119D01*
X398189Y-289749D01*
X398972Y-289959D01*
X399755Y-289749D01*
X400382Y-289119D01*
X400695Y-288174D01*
Y-283659D01*
G01X403314Y-289959D02*
X405272Y-283659D01*
X407230Y-289959D01*
G01X406525Y-287754D02*
X404019D01*
G01X416384Y-284709D02*
X416854Y-284079D01*
X417402Y-283764D01*
X418029Y-283659D01*
X418812Y-283869D01*
X419360Y-284394D01*
X419517Y-285024D01*
X419439Y-285654D01*
X419125Y-286179D01*
X417559Y-287229D01*
X416854Y-287964D01*
X416384Y-289014D01*
X416227Y-289959D01*
X419517D01*
G01X422370D02*
Y-283659D01*
X425974Y-289959D01*
Y-283659D01*
G01X428749Y-289959D02*
Y-283659D01*
X430315D01*
X430942Y-283974D01*
X431412Y-284394D01*
X431804Y-285024D01*
X432117Y-285759D01*
X432195Y-286809D01*
X432117Y-287859D01*
X431804Y-288594D01*
X431412Y-289224D01*
X430942Y-289644D01*
X430315Y-289959D01*
X428749D01*
G01X441505D02*
Y-283659D01*
X443464D01*
X444090Y-283974D01*
X444482Y-284394D01*
X444639Y-285234D01*
X444482Y-286074D01*
X444012Y-286599D01*
X443464Y-286914D01*
X441505D01*
G01X443464D02*
X444639Y-289959D01*
G01X447649D02*
Y-283659D01*
X449215D01*
X449842Y-283974D01*
X450312Y-284394D01*
X450704Y-285024D01*
X451017Y-285759D01*
X451095Y-286809D01*
X451017Y-287859D01*
X450704Y-288594D01*
X450312Y-289224D01*
X449842Y-289644D01*
X449215Y-289959D01*
X447649D01*
G01X455672Y-290169D02*
X455515Y-290064D01*
Y-289854D01*
X455672Y-289749D01*
X455829Y-289854D01*
Y-290064D01*
X455672Y-290169D01*
G01X351972Y-279259D02*
X349452Y-278842D01*
X347247Y-277176D01*
X345357Y-274676D01*
X344097Y-271759D01*
X343467Y-268426D01*
Y-265092D01*
X344097Y-261759D01*
X345357Y-258842D01*
X347247Y-256343D01*
X349452Y-254676D01*
X351972Y-254259D01*
X354492Y-254676D01*
X356697Y-256343D01*
X358587Y-258842D01*
X359847Y-261759D01*
X360477Y-265092D01*
Y-268426D01*
X359847Y-271759D01*
X358587Y-274676D01*
X356697Y-277176D01*
X354492Y-278842D01*
X351972Y-279259D01*
G01X354492Y-272592D02*
X358272Y-279259D01*
G01X371817Y-262593D02*
Y-274259D01*
X373077Y-277176D01*
X374967Y-278842D01*
X377172Y-279259D01*
X379377Y-278842D01*
X381267Y-277176D01*
X382527Y-274259D01*
G01Y-279259D02*
Y-262593D01*
G01X408042Y-279259D02*
Y-262593D01*
G01Y-265509D02*
X406782Y-263843D01*
X404892Y-263009D01*
X402687Y-262593D01*
X400482Y-263426D01*
X398592Y-265092D01*
X397332Y-267593D01*
X396702Y-270926D01*
X397332Y-274259D01*
X398592Y-276760D01*
X400482Y-278426D01*
X402687Y-279259D01*
X404892Y-278842D01*
X406782Y-277593D01*
X408042Y-275926D01*
G01X422217Y-279259D02*
Y-262593D01*
G01Y-266759D02*
X423477Y-264676D01*
X425367Y-263009D01*
X427887Y-262593D01*
X430092Y-263009D01*
X431982Y-264676D01*
X432927Y-267593D01*
Y-279259D01*
G01X452772Y-254259D02*
Y-279259D01*
G01X448362Y-262593D02*
X457182D01*
G01X483642Y-279259D02*
Y-262593D01*
G01Y-265509D02*
X482382Y-263843D01*
X480492Y-263009D01*
X478287Y-262593D01*
X476082Y-263426D01*
X474192Y-265092D01*
X472932Y-267593D01*
X472302Y-270926D01*
X472932Y-274259D01*
X474192Y-276760D01*
X476082Y-278426D01*
X478287Y-279259D01*
X480492Y-278842D01*
X482382Y-277593D01*
X483642Y-275926D01*
G01X385350Y585600D02*
X372850D01*
X375350Y583740D01*
G01X385350D02*
Y587460D01*
G01X382850Y594590D02*
X384309Y595520D01*
X385142Y596760D01*
X385350Y598155D01*
X385142Y599395D01*
X384100Y600635D01*
X382850Y601410D01*
X381600Y601565D01*
X380142Y601255D01*
X379100Y600170D01*
X378683Y599085D01*
Y597690D01*
G01Y599085D02*
X378058Y600015D01*
X377017Y600790D01*
X375767Y601100D01*
X374517Y600790D01*
X373475Y600015D01*
X372850Y598620D01*
X373058Y597225D01*
X373892Y595830D01*
G01X374933Y607455D02*
X373684Y608385D01*
X373058Y609470D01*
X372850Y610710D01*
X373267Y612260D01*
X374308Y613345D01*
X375558Y613655D01*
X376809Y613500D01*
X377850Y612880D01*
X379933Y609780D01*
X381392Y608385D01*
X383475Y607455D01*
X385350Y607145D01*
Y613655D01*
G01X380142Y619855D02*
X378683Y620940D01*
X377850Y621870D01*
X377433Y623110D01*
X377850Y624195D01*
X378683Y624970D01*
X379933Y625590D01*
X381392Y625745D01*
X382642Y625590D01*
X383892Y624970D01*
X384933Y624040D01*
X385350Y622955D01*
X384933Y621715D01*
X383684Y620630D01*
X381808Y620010D01*
X379725Y619855D01*
X377017Y620165D01*
X375558Y620630D01*
X374100Y621405D01*
X373058Y622490D01*
X372850Y623575D01*
X373267Y624660D01*
X374308Y625435D01*
G01X385350Y634890D02*
X382642Y635200D01*
X380350Y635665D01*
X378267Y636285D01*
X375975Y637060D01*
X372850Y638300D01*
Y632100D01*
G01X385767Y647600D02*
X385558Y647290D01*
X385142D01*
X384933Y647600D01*
X385142Y647910D01*
X385558D01*
X385767Y647600D01*
G01X385350Y659690D02*
X382642Y660000D01*
X380350Y660465D01*
X378267Y661085D01*
X375975Y661860D01*
X372850Y663100D01*
Y656900D01*
G01X374933Y669455D02*
X373684Y670385D01*
X373058Y671470D01*
X372850Y672710D01*
X373267Y674260D01*
X374308Y675345D01*
X375558Y675655D01*
X376809Y675500D01*
X377850Y674880D01*
X379933Y671780D01*
X381392Y670385D01*
X383475Y669455D01*
X385350Y669145D01*
Y675655D01*
G01X407850Y613340D02*
X409309Y614270D01*
X410142Y615510D01*
X410350Y616905D01*
X410142Y618145D01*
X409100Y619385D01*
X407850Y620160D01*
X406600Y620315D01*
X405142Y620005D01*
X404100Y618920D01*
X403683Y617835D01*
Y616440D01*
G01Y617835D02*
X403058Y618765D01*
X402017Y619540D01*
X400767Y619850D01*
X399517Y619540D01*
X398475Y618765D01*
X397850Y617370D01*
X398058Y615975D01*
X398892Y614580D01*
G01X407850Y625740D02*
X409309Y626670D01*
X410142Y627910D01*
X410350Y629305D01*
X410142Y630545D01*
X409100Y631785D01*
X407850Y632560D01*
X406600Y632715D01*
X405142Y632405D01*
X404100Y631320D01*
X403683Y630235D01*
Y628840D01*
G01Y630235D02*
X403058Y631165D01*
X402017Y631940D01*
X400767Y632250D01*
X399517Y631940D01*
X398475Y631165D01*
X397850Y629770D01*
X398058Y628375D01*
X398892Y626980D01*
G01X410350Y641240D02*
X407642Y641550D01*
X405350Y642015D01*
X403267Y642635D01*
X400975Y643410D01*
X397850Y644650D01*
Y638450D01*
G01X523322Y-258959D02*
Y-266959D01*
X527322D01*
G01X535122D02*
Y-261626D01*
G01Y-262559D02*
X534722Y-262026D01*
X534122Y-261759D01*
X533422Y-261626D01*
X532722Y-261892D01*
X532122Y-262426D01*
X531722Y-263226D01*
X531522Y-264292D01*
X531722Y-265359D01*
X532122Y-266159D01*
X532722Y-266692D01*
X533422Y-266959D01*
X534122Y-266826D01*
X534722Y-266426D01*
X535122Y-265893D01*
G01X539222Y-269359D02*
X539822Y-269626D01*
X540622Y-269359D01*
X541122Y-268826D01*
X541522Y-268159D01*
X542122Y-266026D01*
X543422Y-261626D01*
G01X540222D02*
X542122Y-266026D01*
G01X547822Y-263359D02*
X551022D01*
X550722Y-262426D01*
X550222Y-261892D01*
X549522Y-261626D01*
X548822Y-261759D01*
X548222Y-262159D01*
X547822Y-263092D01*
X547622Y-263893D01*
Y-264692D01*
X547822Y-265492D01*
X548322Y-266292D01*
X548922Y-266826D01*
X549622Y-266959D01*
X550322Y-266692D01*
X551022Y-265893D01*
G01X555922Y-266959D02*
Y-261626D01*
G01Y-262692D02*
X556422Y-262159D01*
X556922Y-261759D01*
X557622Y-261626D01*
X558122Y-261759D01*
X558722Y-262159D01*
G01X542022Y-316959D02*
Y-308959D01*
X546622Y-316959D01*
Y-308959D01*
G01X552322Y-311626D02*
Y-316959D01*
G01Y-309492D02*
X552122Y-309359D01*
Y-309092D01*
X552322Y-308959D01*
X552522Y-309092D01*
Y-309359D01*
X552322Y-309492D01*
G01X558622Y-316959D02*
Y-311626D01*
G01Y-312959D02*
X559022Y-312292D01*
X559622Y-311759D01*
X560422Y-311626D01*
X561122Y-311759D01*
X561722Y-312292D01*
X562022Y-313226D01*
Y-316959D01*
G01X570122D02*
Y-311626D01*
G01Y-312559D02*
X569722Y-312026D01*
X569122Y-311759D01*
X568422Y-311626D01*
X567722Y-311892D01*
X567122Y-312426D01*
X566722Y-313226D01*
X566522Y-314292D01*
X566722Y-315359D01*
X567122Y-316159D01*
X567722Y-316692D01*
X568422Y-316959D01*
X569122Y-316826D01*
X569722Y-316426D01*
X570122Y-315893D01*
G01X547422Y-291959D02*
Y-283959D01*
X551222D01*
G01X549822Y-287826D02*
X547422D01*
G01X554822Y-291959D02*
X557322Y-283959D01*
X559822Y-291959D01*
G01X558922Y-289159D02*
X555722D01*
G01X566122Y-287692D02*
X566522Y-287292D01*
X566822Y-286626D01*
X567022Y-285692D01*
X566822Y-284892D01*
X566422Y-284359D01*
X565722Y-283959D01*
X563022D01*
Y-291959D01*
X566322D01*
X567022Y-291426D01*
X567422Y-290626D01*
X567622Y-289692D01*
X567422Y-288759D01*
X566822Y-287959D01*
X566122Y-287692D01*
X563022D01*
G01X649922Y-310292D02*
X650522Y-309492D01*
X651222Y-309092D01*
X652022Y-308959D01*
X653022Y-309226D01*
X653722Y-309892D01*
X653922Y-310692D01*
X653822Y-311493D01*
X653422Y-312159D01*
X651422Y-313492D01*
X650522Y-314426D01*
X649922Y-315759D01*
X649722Y-316959D01*
X653922D01*
G01X659822Y-308959D02*
X659022Y-309226D01*
X658422Y-309892D01*
X658022Y-310692D01*
X657722Y-311759D01*
X657622Y-312959D01*
X657722Y-314159D01*
X658022Y-315226D01*
X658422Y-316026D01*
X659022Y-316692D01*
X659822Y-316959D01*
X660622Y-316692D01*
X661222Y-316026D01*
X661622Y-315226D01*
X661922Y-314159D01*
X662022Y-312959D01*
X661922Y-311759D01*
X661622Y-310692D01*
X661222Y-309892D01*
X660622Y-309226D01*
X659822Y-308959D01*
G01X665922Y-310292D02*
X666522Y-309492D01*
X667222Y-309092D01*
X668022Y-308959D01*
X669022Y-309226D01*
X669722Y-309892D01*
X669922Y-310692D01*
X669822Y-311493D01*
X669422Y-312159D01*
X667422Y-313492D01*
X666522Y-314426D01*
X665922Y-315759D01*
X665722Y-316959D01*
X669922D01*
G01X673922Y-310292D02*
X674522Y-309492D01*
X675222Y-309092D01*
X676022Y-308959D01*
X677022Y-309226D01*
X677722Y-309892D01*
X677922Y-310692D01*
X677822Y-311493D01*
X677422Y-312159D01*
X675422Y-313492D01*
X674522Y-314426D01*
X673922Y-315759D01*
X673722Y-316959D01*
X677922D01*
G01X682022Y-317226D02*
X685622Y-308959D01*
G01X691822Y-316959D02*
Y-308959D01*
X690622Y-310559D01*
G01Y-316959D02*
X693022D01*
G01X697922Y-310292D02*
X698522Y-309492D01*
X699222Y-309092D01*
X700022Y-308959D01*
X701022Y-309226D01*
X701722Y-309892D01*
X701922Y-310692D01*
X701822Y-311493D01*
X701422Y-312159D01*
X699422Y-313492D01*
X698522Y-314426D01*
X697922Y-315759D01*
X697722Y-316959D01*
X701922D01*
G01X706022Y-317226D02*
X709622Y-308959D01*
G01X715822D02*
X715022Y-309226D01*
X714422Y-309892D01*
X714022Y-310692D01*
X713722Y-311759D01*
X713622Y-312959D01*
X713722Y-314159D01*
X714022Y-315226D01*
X714422Y-316026D01*
X715022Y-316692D01*
X715822Y-316959D01*
X716622Y-316692D01*
X717222Y-316026D01*
X717622Y-315226D01*
X717922Y-314159D01*
X718022Y-312959D01*
X717922Y-311759D01*
X717622Y-310692D01*
X717222Y-309892D01*
X716622Y-309226D01*
X715822Y-308959D01*
G01X722122Y-316026D02*
X722822Y-316692D01*
X723622Y-316959D01*
X724422Y-316692D01*
X725122Y-315893D01*
X725622Y-314692D01*
X725822Y-313492D01*
Y-312026D01*
X725622Y-310826D01*
X725122Y-309759D01*
X724522Y-309226D01*
X723822Y-308959D01*
X723022Y-309226D01*
X722422Y-309759D01*
X722022Y-310559D01*
X721822Y-311626D01*
X722022Y-312559D01*
X722522Y-313492D01*
X723122Y-314026D01*
X723822Y-314159D01*
X724622Y-313893D01*
X725222Y-313226D01*
X725822Y-312026D01*
G01X649622Y-291959D02*
Y-283959D01*
X651622D01*
X652422Y-284359D01*
X653022Y-284892D01*
X653522Y-285692D01*
X653922Y-286626D01*
X654022Y-287959D01*
X653922Y-289292D01*
X653522Y-290226D01*
X653022Y-291026D01*
X652422Y-291559D01*
X651622Y-291959D01*
X649622D01*
G01X657322D02*
X659822Y-283959D01*
X662322Y-291959D01*
G01X661422Y-289159D02*
X658222D01*
G01X667822Y-283959D02*
X667022Y-284226D01*
X666422Y-284892D01*
X666022Y-285692D01*
X665722Y-286759D01*
X665622Y-287959D01*
X665722Y-289159D01*
X666022Y-290226D01*
X666422Y-291026D01*
X667022Y-291692D01*
X667822Y-291959D01*
X668622Y-291692D01*
X669222Y-291026D01*
X669622Y-290226D01*
X669922Y-289159D01*
X670022Y-287959D01*
X669922Y-286759D01*
X669622Y-285692D01*
X669222Y-284892D01*
X668622Y-284226D01*
X667822Y-283959D01*
G01X673922Y-291959D02*
Y-283959D01*
X677722D01*
G01X676322Y-287826D02*
X673922D01*
G01X683822Y-283959D02*
X683022Y-284226D01*
X682422Y-284892D01*
X682022Y-285692D01*
X681722Y-286759D01*
X681622Y-287959D01*
X681722Y-289159D01*
X682022Y-290226D01*
X682422Y-291026D01*
X683022Y-291692D01*
X683822Y-291959D01*
X684622Y-291692D01*
X685222Y-291026D01*
X685622Y-290226D01*
X685922Y-289159D01*
X686022Y-287959D01*
X685922Y-286759D01*
X685622Y-285692D01*
X685222Y-284892D01*
X684622Y-284226D01*
X683822Y-283959D01*
G01X691822D02*
Y-291959D01*
G01X689522Y-283959D02*
X694122D01*
G01X697922Y-291959D02*
Y-283959D01*
X701722D01*
G01X700322Y-287826D02*
X697922D01*
G01X708622Y-287692D02*
X709022Y-287292D01*
X709322Y-286626D01*
X709522Y-285692D01*
X709322Y-284892D01*
X708922Y-284359D01*
X708222Y-283959D01*
X705522D01*
Y-291959D01*
X708822D01*
X709522Y-291426D01*
X709922Y-290626D01*
X710122Y-289692D01*
X709922Y-288759D01*
X709322Y-287959D01*
X708622Y-287692D01*
X705522D01*
G01X713922Y-288626D02*
X714622Y-287692D01*
X715222Y-287159D01*
X716022Y-286892D01*
X716722Y-287159D01*
X717222Y-287692D01*
X717622Y-288492D01*
X717722Y-289426D01*
X717622Y-290226D01*
X717222Y-291026D01*
X716622Y-291692D01*
X715922Y-291959D01*
X715122Y-291692D01*
X714422Y-290893D01*
X714022Y-289692D01*
X713922Y-288359D01*
X714122Y-286626D01*
X714422Y-285692D01*
X714922Y-284759D01*
X715622Y-284092D01*
X716322Y-283959D01*
X717022Y-284226D01*
X717522Y-284892D01*
G01X721622Y-291959D02*
Y-283959D01*
X723622D01*
X724422Y-284359D01*
X725022Y-284892D01*
X725522Y-285692D01*
X725922Y-286626D01*
X726022Y-287959D01*
X725922Y-289292D01*
X725522Y-290226D01*
X725022Y-291026D01*
X724422Y-291559D01*
X723622Y-291959D01*
X721622D01*
G01X731822Y-283959D02*
X731022Y-284226D01*
X730422Y-284892D01*
X730022Y-285692D01*
X729722Y-286759D01*
X729622Y-287959D01*
X729722Y-289159D01*
X730022Y-290226D01*
X730422Y-291026D01*
X731022Y-291692D01*
X731822Y-291959D01*
X732622Y-291692D01*
X733222Y-291026D01*
X733622Y-290226D01*
X733922Y-289159D01*
X734022Y-287959D01*
X733922Y-286759D01*
X733622Y-285692D01*
X733222Y-284892D01*
X732622Y-284226D01*
X731822Y-283959D01*
G01X649862Y-270000D02*
Y-263700D01*
X652838D01*
G01X651742Y-266745D02*
X649862D01*
G01X657650Y-263700D02*
X657023Y-263910D01*
X656553Y-264435D01*
X656240Y-265065D01*
X656005Y-265905D01*
X655927Y-266850D01*
X656005Y-267795D01*
X656240Y-268635D01*
X656553Y-269265D01*
X657023Y-269790D01*
X657650Y-270000D01*
X658277Y-269790D01*
X658747Y-269265D01*
X659060Y-268635D01*
X659295Y-267795D01*
X659373Y-266850D01*
X659295Y-265905D01*
X659060Y-265065D01*
X658747Y-264435D01*
X658277Y-263910D01*
X657650Y-263700D01*
G01X663950D02*
Y-270000D01*
G01X662148Y-263700D02*
X665752D01*
G01X667900Y-272100D02*
X672600D01*
G01X674983Y-270000D02*
Y-263700D01*
X676863D01*
X677490Y-264015D01*
X677960Y-264750D01*
X678117Y-265590D01*
X677960Y-266430D01*
X677568Y-267060D01*
X676863Y-267375D01*
X674983D01*
G01X684573Y-264225D02*
X684103Y-263910D01*
X683555Y-263700D01*
X682928D01*
X682223Y-264015D01*
X681675Y-264540D01*
X681283Y-265170D01*
X680970Y-266220D01*
X680892Y-267165D01*
X681048Y-268110D01*
X681283Y-268740D01*
X681753Y-269370D01*
X682302Y-269790D01*
X682850Y-270000D01*
X683398D01*
X683947Y-269790D01*
X684417Y-269475D01*
X684808Y-269055D01*
G01X689777Y-266640D02*
X690090Y-266325D01*
X690325Y-265800D01*
X690482Y-265065D01*
X690325Y-264435D01*
X690012Y-264015D01*
X689463Y-263700D01*
X687348D01*
Y-270000D01*
X689933D01*
X690482Y-269580D01*
X690795Y-268950D01*
X690952Y-268215D01*
X690795Y-267480D01*
X690325Y-266850D01*
X689777Y-266640D01*
X687348D01*
G01X693100Y-272100D02*
X697800D01*
G01X700262Y-270000D02*
Y-263700D01*
X703238D01*
G01X702142Y-266745D02*
X700262D01*
G01X706092Y-270000D02*
X708050Y-263700D01*
X710008Y-270000D01*
G01X709303Y-267795D02*
X706797D01*
G01X712548Y-270000D02*
Y-263700D01*
X716152Y-270000D01*
Y-263700D01*
G01X718300Y-272100D02*
X723000D01*
G01X727577Y-266640D02*
X727890Y-266325D01*
X728125Y-265800D01*
X728282Y-265065D01*
X728125Y-264435D01*
X727812Y-264015D01*
X727263Y-263700D01*
X725148D01*
Y-270000D01*
X727733D01*
X728282Y-269580D01*
X728595Y-268950D01*
X728752Y-268215D01*
X728595Y-267480D01*
X728125Y-266850D01*
X727577Y-266640D01*
X725148D01*
G01X733250Y-270000D02*
X732623Y-269895D01*
X732075Y-269475D01*
X731605Y-268845D01*
X731292Y-268110D01*
X731135Y-267270D01*
Y-266430D01*
X731292Y-265590D01*
X731605Y-264855D01*
X732075Y-264225D01*
X732623Y-263805D01*
X733250Y-263700D01*
X733877Y-263805D01*
X734425Y-264225D01*
X734895Y-264855D01*
X735208Y-265590D01*
X735365Y-266430D01*
Y-267270D01*
X735208Y-268110D01*
X734895Y-268845D01*
X734425Y-269475D01*
X733877Y-269895D01*
X733250Y-270000D01*
G01X737592D02*
X739550Y-263700D01*
X741508Y-270000D01*
G01X740803Y-267795D02*
X738297D01*
G01X744283Y-270000D02*
Y-263700D01*
X746242D01*
X746868Y-264015D01*
X747260Y-264435D01*
X747417Y-265275D01*
X747260Y-266115D01*
X746790Y-266640D01*
X746242Y-266955D01*
X744283D01*
G01X746242D02*
X747417Y-270000D01*
G01X750427D02*
Y-263700D01*
X751993D01*
X752620Y-264015D01*
X753090Y-264435D01*
X753482Y-265065D01*
X753795Y-265800D01*
X753873Y-266850D01*
X753795Y-267900D01*
X753482Y-268635D01*
X753090Y-269265D01*
X752620Y-269685D01*
X751993Y-270000D01*
X750427D01*
G01X756100Y-272100D02*
X760800D01*
G01X762713Y-270000D02*
Y-263700D01*
X764750Y-268950D01*
X766787Y-263700D01*
Y-270000D01*
G01X769483D02*
Y-263700D01*
X771363D01*
X771990Y-264015D01*
X772460Y-264750D01*
X772617Y-265590D01*
X772460Y-266430D01*
X772068Y-267060D01*
X771363Y-267375D01*
X769483D01*
G01X775627Y-269055D02*
X776097Y-269580D01*
X776645Y-269895D01*
X777350Y-270000D01*
X778055Y-269790D01*
X778603Y-269370D01*
X778995Y-268635D01*
X779073Y-267795D01*
X778917Y-266955D01*
X778525Y-266430D01*
X777977Y-266010D01*
X777428Y-265905D01*
X776880Y-266010D01*
X776175Y-266430D01*
X776410Y-263700D01*
X778525D01*
G01X783650D02*
X783023Y-263910D01*
X782553Y-264435D01*
X782240Y-265065D01*
X782005Y-265905D01*
X781927Y-266850D01*
X782005Y-267795D01*
X782240Y-268635D01*
X782553Y-269265D01*
X783023Y-269790D01*
X783650Y-270000D01*
X784277Y-269790D01*
X784747Y-269265D01*
X785060Y-268635D01*
X785295Y-267795D01*
X785373Y-266850D01*
X785295Y-265905D01*
X785060Y-265065D01*
X784747Y-264435D01*
X784277Y-263910D01*
X783650Y-263700D01*
G01X790890Y-270000D02*
Y-263700D01*
X787992Y-268215D01*
X791908D01*
G01X796250Y-270000D02*
X796798Y-269895D01*
X797425Y-269580D01*
X797817Y-269055D01*
X797973Y-268320D01*
X797817Y-267585D01*
X797347Y-266955D01*
X796642Y-266640D01*
X795858D01*
X795388Y-266430D01*
X794997Y-265905D01*
X794840Y-265170D01*
X795075Y-264435D01*
X795623Y-263910D01*
X796250Y-263700D01*
X796877Y-263910D01*
X797425Y-264435D01*
X797660Y-265170D01*
X797503Y-265905D01*
X797112Y-266430D01*
X796642Y-266640D01*
X795858D01*
X795153Y-266955D01*
X794683Y-267585D01*
X794527Y-268320D01*
X794683Y-269055D01*
X795075Y-269580D01*
X795702Y-269895D01*
X796250Y-270000D01*
G01X738322Y-319959D02*
Y-311959D01*
X737122Y-313559D01*
G01Y-319959D02*
X739522D01*
G01X744422Y-316626D02*
X745122Y-315692D01*
X745722Y-315159D01*
X746522Y-314892D01*
X747222Y-315159D01*
X747722Y-315692D01*
X748122Y-316492D01*
X748222Y-317426D01*
X748122Y-318226D01*
X747722Y-319026D01*
X747122Y-319692D01*
X746422Y-319959D01*
X745622Y-319692D01*
X744922Y-318893D01*
X744522Y-317692D01*
X744422Y-316359D01*
X744622Y-314626D01*
X744922Y-313692D01*
X745422Y-312759D01*
X746122Y-312092D01*
X746822Y-311959D01*
X747522Y-312226D01*
X748022Y-312892D01*
G01X754322Y-320226D02*
X754122Y-320092D01*
Y-319826D01*
X754322Y-319692D01*
X754522Y-319826D01*
Y-320092D01*
X754322Y-320226D01*
G01X760422Y-316626D02*
X761122Y-315692D01*
X761722Y-315159D01*
X762522Y-314892D01*
X763222Y-315159D01*
X763722Y-315692D01*
X764122Y-316492D01*
X764222Y-317426D01*
X764122Y-318226D01*
X763722Y-319026D01*
X763122Y-319692D01*
X762422Y-319959D01*
X761622Y-319692D01*
X760922Y-318893D01*
X760522Y-317692D01*
X760422Y-316359D01*
X760622Y-314626D01*
X760922Y-313692D01*
X761422Y-312759D01*
X762122Y-312092D01*
X762822Y-311959D01*
X763522Y-312226D01*
X764022Y-312892D01*
G01X783322Y-319959D02*
Y-311959D01*
X782122Y-313559D01*
G01Y-319959D02*
X784522D01*
G01X791122D02*
X791322Y-318226D01*
X791622Y-316759D01*
X792022Y-315426D01*
X792522Y-313959D01*
X793322Y-311959D01*
X789322D01*
G01X799322Y-320226D02*
X799122Y-320092D01*
Y-319826D01*
X799322Y-319692D01*
X799522Y-319826D01*
Y-320092D01*
X799322Y-320226D01*
G01X805422Y-313292D02*
X806022Y-312492D01*
X806722Y-312092D01*
X807522Y-311959D01*
X808522Y-312226D01*
X809222Y-312892D01*
X809422Y-313692D01*
X809322Y-314493D01*
X808922Y-315159D01*
X806922Y-316492D01*
X806022Y-317426D01*
X805422Y-318759D01*
X805222Y-319959D01*
X809422D01*
G01X803122Y-294959D02*
Y-286959D01*
X805122D01*
X805922Y-287359D01*
X806522Y-287892D01*
X807022Y-288692D01*
X807422Y-289626D01*
X807522Y-290959D01*
X807422Y-292292D01*
X807022Y-293226D01*
X806522Y-294026D01*
X805922Y-294559D01*
X805122Y-294959D01*
X803122D01*
G01X1600300Y1499100D02*
G03I-200000J0D01*
G01X1231505Y1123750D02*
Y1136250D01*
X1237395D01*
G01X1235225Y1130208D02*
X1231505D01*
G01X1244990Y1136250D02*
X1248710D01*
G01X1246850D02*
Y1123750D01*
G01X1244990D02*
X1248710D01*
G01X1260180Y1130000D02*
X1263280D01*
Y1126250D01*
X1262350Y1125000D01*
X1261265Y1124167D01*
X1259715Y1123750D01*
X1258165Y1124167D01*
X1257080Y1125000D01*
X1256150Y1126250D01*
X1255530Y1127708D01*
X1255220Y1129375D01*
Y1130833D01*
X1255530Y1132083D01*
X1256150Y1133542D01*
X1257080Y1134792D01*
X1258010Y1135625D01*
X1259250Y1136250D01*
X1260335D01*
X1261575Y1135833D01*
X1262505Y1135000D01*
G01X1268240Y1136250D02*
Y1127292D01*
X1268860Y1125416D01*
X1270100Y1124167D01*
X1271650Y1123750D01*
X1273200Y1124167D01*
X1274440Y1125416D01*
X1275060Y1127292D01*
Y1136250D01*
G01X1280950Y1123750D02*
Y1136250D01*
X1284825D01*
X1286065Y1135625D01*
X1286840Y1134792D01*
X1287150Y1133125D01*
X1286840Y1131458D01*
X1285910Y1130417D01*
X1284825Y1129792D01*
X1280950D01*
G01X1284825D02*
X1287150Y1123750D01*
G01X1299550D02*
X1293350D01*
Y1136250D01*
X1299550D01*
G01X1297070Y1130208D02*
X1293350D01*
G01X1325212Y1342613D02*
Y1348913D01*
X1327092D01*
X1327719Y1348598D01*
X1328189Y1347863D01*
X1328346Y1347023D01*
X1328189Y1346183D01*
X1327797Y1345553D01*
X1327092Y1345238D01*
X1325212D01*
G01X1333079Y1342613D02*
Y1348913D01*
G01X1338204Y1345448D02*
X1340711D01*
X1340476Y1346183D01*
X1340084Y1346603D01*
X1339536Y1346813D01*
X1338987Y1346708D01*
X1338517Y1346393D01*
X1338204Y1345658D01*
X1338047Y1345028D01*
Y1344398D01*
X1338204Y1343768D01*
X1338596Y1343138D01*
X1339066Y1342718D01*
X1339614Y1342613D01*
X1340162Y1342823D01*
X1340711Y1343453D01*
G01X1347089Y1342613D02*
Y1346813D01*
G01Y1346078D02*
X1346776Y1346498D01*
X1346306Y1346708D01*
X1345757Y1346813D01*
X1345209Y1346603D01*
X1344739Y1346183D01*
X1344426Y1345553D01*
X1344269Y1344713D01*
X1344426Y1343873D01*
X1344739Y1343243D01*
X1345209Y1342823D01*
X1345757Y1342613D01*
X1346306Y1342718D01*
X1346776Y1343033D01*
X1347089Y1343453D01*
G01X1350804Y1343348D02*
X1351196Y1342928D01*
X1351744Y1342613D01*
X1352214D01*
X1352684Y1342823D01*
X1352997Y1343138D01*
X1353154Y1343558D01*
X1353076Y1344188D01*
X1352762Y1344503D01*
X1351352Y1345133D01*
X1351039Y1345868D01*
X1351196Y1346393D01*
X1351509Y1346708D01*
X1351979Y1346813D01*
X1352449Y1346708D01*
X1352919Y1346393D01*
G01X1357104Y1345448D02*
X1359611D01*
X1359376Y1346183D01*
X1358984Y1346603D01*
X1358436Y1346813D01*
X1357887Y1346708D01*
X1357417Y1346393D01*
X1357104Y1345658D01*
X1356947Y1345028D01*
Y1344398D01*
X1357104Y1343768D01*
X1357496Y1343138D01*
X1357966Y1342718D01*
X1358514Y1342613D01*
X1359062Y1342823D01*
X1359611Y1343453D01*
G01X1369782Y1342613D02*
Y1346813D01*
G01Y1345973D02*
X1370174Y1346393D01*
X1370566Y1346708D01*
X1371114Y1346813D01*
X1371506Y1346708D01*
X1371976Y1346393D01*
G01X1376004Y1345448D02*
X1378511D01*
X1378276Y1346183D01*
X1377884Y1346603D01*
X1377336Y1346813D01*
X1376787Y1346708D01*
X1376317Y1346393D01*
X1376004Y1345658D01*
X1375847Y1345028D01*
Y1344398D01*
X1376004Y1343768D01*
X1376396Y1343138D01*
X1376866Y1342718D01*
X1377414Y1342613D01*
X1377962Y1342823D01*
X1378511Y1343453D01*
G01X1383009Y1342613D02*
Y1347968D01*
X1383166Y1348493D01*
X1383479Y1348808D01*
X1383949Y1348913D01*
X1384419Y1348703D01*
X1384654Y1348178D01*
G01X1383714Y1346393D02*
X1382147D01*
G01X1388604Y1345448D02*
X1391111D01*
X1390876Y1346183D01*
X1390484Y1346603D01*
X1389936Y1346813D01*
X1389387Y1346708D01*
X1388917Y1346393D01*
X1388604Y1345658D01*
X1388447Y1345028D01*
Y1344398D01*
X1388604Y1343768D01*
X1388996Y1343138D01*
X1389466Y1342718D01*
X1390014Y1342613D01*
X1390562Y1342823D01*
X1391111Y1343453D01*
G01X1394982Y1342613D02*
Y1346813D01*
G01Y1345973D02*
X1395374Y1346393D01*
X1395766Y1346708D01*
X1396314Y1346813D01*
X1396706Y1346708D01*
X1397176Y1346393D01*
G01X1408679Y1348913D02*
Y1342613D01*
G01X1407582Y1346813D02*
X1409776D01*
G01X1414979Y1342613D02*
X1414509Y1342718D01*
X1414039Y1343138D01*
X1413726Y1343873D01*
X1413569Y1344713D01*
X1413726Y1345553D01*
X1414039Y1346288D01*
X1414509Y1346708D01*
X1414979Y1346813D01*
X1415449Y1346708D01*
X1415919Y1346288D01*
X1416232Y1345553D01*
X1416311Y1344713D01*
X1416232Y1343873D01*
X1415919Y1343138D01*
X1415449Y1342718D01*
X1414979Y1342613D01*
G01X1426404Y1343348D02*
X1426796Y1342928D01*
X1427344Y1342613D01*
X1427814D01*
X1428284Y1342823D01*
X1428597Y1343138D01*
X1428754Y1343558D01*
X1428676Y1344188D01*
X1428362Y1344503D01*
X1426952Y1345133D01*
X1426639Y1345868D01*
X1426796Y1346393D01*
X1427109Y1346708D01*
X1427579Y1346813D01*
X1428049Y1346708D01*
X1428519Y1346393D01*
G01X1433879Y1348913D02*
Y1342613D01*
G01X1432782Y1346813D02*
X1434976D01*
G01X1441589Y1342613D02*
Y1346813D01*
G01Y1346078D02*
X1441276Y1346498D01*
X1440806Y1346708D01*
X1440257Y1346813D01*
X1439709Y1346603D01*
X1439239Y1346183D01*
X1438926Y1345553D01*
X1438769Y1344713D01*
X1438926Y1343873D01*
X1439239Y1343243D01*
X1439709Y1342823D01*
X1440257Y1342613D01*
X1440806Y1342718D01*
X1441276Y1343033D01*
X1441589Y1343453D01*
G01X1447732Y1346288D02*
X1447184Y1346708D01*
X1446714Y1346813D01*
X1446087Y1346603D01*
X1445617Y1346183D01*
X1445304Y1345448D01*
X1445226Y1344713D01*
X1445304Y1343978D01*
X1445617Y1343348D01*
X1446087Y1342823D01*
X1446714Y1342613D01*
X1447262Y1342823D01*
X1447732Y1343243D01*
G01X1451447Y1342613D02*
Y1348913D01*
G01X1453954Y1346813D02*
X1451447Y1344398D01*
G01X1452466Y1345343D02*
X1454111Y1342613D01*
G01X1457747Y1346813D02*
Y1343873D01*
X1458061Y1343138D01*
X1458531Y1342718D01*
X1459079Y1342613D01*
X1459627Y1342718D01*
X1460097Y1343138D01*
X1460411Y1343873D01*
G01Y1342613D02*
Y1346813D01*
G01X1463969Y1340513D02*
Y1346813D01*
G01Y1345868D02*
X1464361Y1346393D01*
X1464752Y1346708D01*
X1465379Y1346813D01*
X1465927Y1346708D01*
X1466476Y1346183D01*
X1466711Y1345448D01*
X1466789Y1344713D01*
X1466711Y1343978D01*
X1466476Y1343243D01*
X1466006Y1342823D01*
X1465379Y1342613D01*
X1464831Y1342718D01*
X1464282Y1343033D01*
X1463969Y1343453D01*
G01X1477509Y1342613D02*
Y1347968D01*
X1477666Y1348493D01*
X1477979Y1348808D01*
X1478449Y1348913D01*
X1478919Y1348703D01*
X1479154Y1348178D01*
G01X1478214Y1346393D02*
X1476647D01*
G01X1484279Y1346813D02*
Y1342613D01*
G01Y1348493D02*
X1484122Y1348598D01*
Y1348808D01*
X1484279Y1348913D01*
X1484436Y1348808D01*
Y1348598D01*
X1484279Y1348493D01*
G01X1490579Y1342613D02*
Y1348913D01*
G01X1495704Y1345448D02*
X1498211D01*
X1497976Y1346183D01*
X1497584Y1346603D01*
X1497036Y1346813D01*
X1496487Y1346708D01*
X1496017Y1346393D01*
X1495704Y1345658D01*
X1495547Y1345028D01*
Y1344398D01*
X1495704Y1343768D01*
X1496096Y1343138D01*
X1496566Y1342718D01*
X1497114Y1342613D01*
X1497662Y1342823D01*
X1498211Y1343453D01*
G01X1503179Y1342403D02*
X1503022Y1342508D01*
Y1342718D01*
X1503179Y1342823D01*
X1503336Y1342718D01*
Y1342508D01*
X1503179Y1342403D01*
G01X1325083Y1356800D02*
Y1363100D01*
X1326963D01*
X1327590Y1362785D01*
X1328060Y1362050D01*
X1328217Y1361210D01*
X1328060Y1360370D01*
X1327668Y1359740D01*
X1326963Y1359425D01*
X1325083D01*
G01X1334360Y1356800D02*
Y1361000D01*
G01Y1360265D02*
X1334047Y1360685D01*
X1333577Y1360895D01*
X1333028Y1361000D01*
X1332480Y1360790D01*
X1332010Y1360370D01*
X1331697Y1359740D01*
X1331540Y1358900D01*
X1331697Y1358060D01*
X1332010Y1357430D01*
X1332480Y1357010D01*
X1333028Y1356800D01*
X1333577Y1356905D01*
X1334047Y1357220D01*
X1334360Y1357640D01*
G01X1340660Y1363100D02*
Y1356800D01*
G01Y1357745D02*
X1340347Y1357220D01*
X1339877Y1356905D01*
X1339328Y1356800D01*
X1338702Y1357010D01*
X1338232Y1357535D01*
X1337918Y1358165D01*
X1337840Y1358900D01*
X1337918Y1359635D01*
X1338232Y1360265D01*
X1338702Y1360790D01*
X1339328Y1361000D01*
X1339877Y1360895D01*
X1340268Y1360685D01*
X1340660Y1360265D01*
G01X1351850Y1363100D02*
Y1356800D01*
G01X1350753Y1361000D02*
X1352947D01*
G01X1358150Y1356800D02*
X1357680Y1356905D01*
X1357210Y1357325D01*
X1356897Y1358060D01*
X1356740Y1358900D01*
X1356897Y1359740D01*
X1357210Y1360475D01*
X1357680Y1360895D01*
X1358150Y1361000D01*
X1358620Y1360895D01*
X1359090Y1360475D01*
X1359403Y1359740D01*
X1359482Y1358900D01*
X1359403Y1358060D01*
X1359090Y1357325D01*
X1358620Y1356905D01*
X1358150Y1356800D01*
G01X1369183D02*
Y1363100D01*
X1371063D01*
X1371690Y1362785D01*
X1372160Y1362050D01*
X1372317Y1361210D01*
X1372160Y1360370D01*
X1371768Y1359740D01*
X1371063Y1359425D01*
X1369183D01*
G01X1378460Y1356800D02*
Y1361000D01*
G01Y1360265D02*
X1378147Y1360685D01*
X1377677Y1360895D01*
X1377128Y1361000D01*
X1376580Y1360790D01*
X1376110Y1360370D01*
X1375797Y1359740D01*
X1375640Y1358900D01*
X1375797Y1358060D01*
X1376110Y1357430D01*
X1376580Y1357010D01*
X1377128Y1356800D01*
X1377677Y1356905D01*
X1378147Y1357220D01*
X1378460Y1357640D01*
G01X1384760Y1363100D02*
Y1356800D01*
G01Y1357745D02*
X1384447Y1357220D01*
X1383977Y1356905D01*
X1383428Y1356800D01*
X1382802Y1357010D01*
X1382332Y1357535D01*
X1382018Y1358165D01*
X1381940Y1358900D01*
X1382018Y1359635D01*
X1382332Y1360265D01*
X1382802Y1360790D01*
X1383428Y1361000D01*
X1383977Y1360895D01*
X1384368Y1360685D01*
X1384760Y1360265D01*
G01X1395950Y1363100D02*
Y1356800D01*
G01X1394853Y1361000D02*
X1397047D01*
G01X1400918Y1356800D02*
Y1363100D01*
G01Y1360055D02*
X1401310Y1360580D01*
X1401702Y1360895D01*
X1402328Y1361000D01*
X1402798Y1360895D01*
X1403347Y1360475D01*
X1403582Y1359845D01*
Y1356800D01*
G01X1408550Y1361000D02*
Y1356800D01*
G01Y1362680D02*
X1408393Y1362785D01*
Y1362995D01*
X1408550Y1363100D01*
X1408707Y1362995D01*
Y1362785D01*
X1408550Y1362680D01*
G01X1416103Y1360475D02*
X1415555Y1360895D01*
X1415085Y1361000D01*
X1414458Y1360790D01*
X1413988Y1360370D01*
X1413675Y1359635D01*
X1413597Y1358900D01*
X1413675Y1358165D01*
X1413988Y1357535D01*
X1414458Y1357010D01*
X1415085Y1356800D01*
X1415633Y1357010D01*
X1416103Y1357430D01*
G01X1419818Y1356800D02*
Y1363100D01*
G01X1422325Y1361000D02*
X1419818Y1358585D01*
G01X1420837Y1359530D02*
X1422482Y1356800D01*
G01X1426118D02*
Y1361000D01*
G01Y1359950D02*
X1426432Y1360475D01*
X1426902Y1360895D01*
X1427528Y1361000D01*
X1428077Y1360895D01*
X1428547Y1360475D01*
X1428782Y1359740D01*
Y1356800D01*
G01X1432575Y1359635D02*
X1435082D01*
X1434847Y1360370D01*
X1434455Y1360790D01*
X1433907Y1361000D01*
X1433358Y1360895D01*
X1432888Y1360580D01*
X1432575Y1359845D01*
X1432418Y1359215D01*
Y1358585D01*
X1432575Y1357955D01*
X1432967Y1357325D01*
X1433437Y1356905D01*
X1433985Y1356800D01*
X1434533Y1357010D01*
X1435082Y1357640D01*
G01X1438875Y1357535D02*
X1439267Y1357115D01*
X1439815Y1356800D01*
X1440285D01*
X1440755Y1357010D01*
X1441068Y1357325D01*
X1441225Y1357745D01*
X1441147Y1358375D01*
X1440833Y1358690D01*
X1439423Y1359320D01*
X1439110Y1360055D01*
X1439267Y1360580D01*
X1439580Y1360895D01*
X1440050Y1361000D01*
X1440520Y1360895D01*
X1440990Y1360580D01*
G01X1445175Y1357535D02*
X1445567Y1357115D01*
X1446115Y1356800D01*
X1446585D01*
X1447055Y1357010D01*
X1447368Y1357325D01*
X1447525Y1357745D01*
X1447447Y1358375D01*
X1447133Y1358690D01*
X1445723Y1359320D01*
X1445410Y1360055D01*
X1445567Y1360580D01*
X1445880Y1360895D01*
X1446350Y1361000D01*
X1446820Y1360895D01*
X1447290Y1360580D01*
G01X1310608Y1627697D02*
Y1633997D01*
X1312488D01*
X1313115Y1633682D01*
X1313585Y1632947D01*
X1313742Y1632107D01*
X1313585Y1631267D01*
X1313193Y1630637D01*
X1312488Y1630322D01*
X1310608D01*
G01X1318475Y1627697D02*
Y1633997D01*
G01X1323600Y1630532D02*
X1326107D01*
X1325872Y1631267D01*
X1325480Y1631687D01*
X1324932Y1631897D01*
X1324383Y1631792D01*
X1323913Y1631477D01*
X1323600Y1630742D01*
X1323443Y1630112D01*
Y1629482D01*
X1323600Y1628852D01*
X1323992Y1628222D01*
X1324462Y1627802D01*
X1325010Y1627697D01*
X1325558Y1627907D01*
X1326107Y1628537D01*
G01X1332485Y1627697D02*
Y1631897D01*
G01Y1631162D02*
X1332172Y1631582D01*
X1331702Y1631792D01*
X1331153Y1631897D01*
X1330605Y1631687D01*
X1330135Y1631267D01*
X1329822Y1630637D01*
X1329665Y1629797D01*
X1329822Y1628957D01*
X1330135Y1628327D01*
X1330605Y1627907D01*
X1331153Y1627697D01*
X1331702Y1627802D01*
X1332172Y1628117D01*
X1332485Y1628537D01*
G01X1336200Y1628432D02*
X1336592Y1628012D01*
X1337140Y1627697D01*
X1337610D01*
X1338080Y1627907D01*
X1338393Y1628222D01*
X1338550Y1628642D01*
X1338472Y1629272D01*
X1338158Y1629587D01*
X1336748Y1630217D01*
X1336435Y1630952D01*
X1336592Y1631477D01*
X1336905Y1631792D01*
X1337375Y1631897D01*
X1337845Y1631792D01*
X1338315Y1631477D01*
G01X1342500Y1630532D02*
X1345007D01*
X1344772Y1631267D01*
X1344380Y1631687D01*
X1343832Y1631897D01*
X1343283Y1631792D01*
X1342813Y1631477D01*
X1342500Y1630742D01*
X1342343Y1630112D01*
Y1629482D01*
X1342500Y1628852D01*
X1342892Y1628222D01*
X1343362Y1627802D01*
X1343910Y1627697D01*
X1344458Y1627907D01*
X1345007Y1628537D01*
G01X1355178Y1627697D02*
Y1631897D01*
G01Y1631057D02*
X1355570Y1631477D01*
X1355962Y1631792D01*
X1356510Y1631897D01*
X1356902Y1631792D01*
X1357372Y1631477D01*
G01X1361400Y1630532D02*
X1363907D01*
X1363672Y1631267D01*
X1363280Y1631687D01*
X1362732Y1631897D01*
X1362183Y1631792D01*
X1361713Y1631477D01*
X1361400Y1630742D01*
X1361243Y1630112D01*
Y1629482D01*
X1361400Y1628852D01*
X1361792Y1628222D01*
X1362262Y1627802D01*
X1362810Y1627697D01*
X1363358Y1627907D01*
X1363907Y1628537D01*
G01X1368405Y1627697D02*
Y1633052D01*
X1368562Y1633577D01*
X1368875Y1633892D01*
X1369345Y1633997D01*
X1369815Y1633787D01*
X1370050Y1633262D01*
G01X1369110Y1631477D02*
X1367543D01*
G01X1374000Y1630532D02*
X1376507D01*
X1376272Y1631267D01*
X1375880Y1631687D01*
X1375332Y1631897D01*
X1374783Y1631792D01*
X1374313Y1631477D01*
X1374000Y1630742D01*
X1373843Y1630112D01*
Y1629482D01*
X1374000Y1628852D01*
X1374392Y1628222D01*
X1374862Y1627802D01*
X1375410Y1627697D01*
X1375958Y1627907D01*
X1376507Y1628537D01*
G01X1380378Y1627697D02*
Y1631897D01*
G01Y1631057D02*
X1380770Y1631477D01*
X1381162Y1631792D01*
X1381710Y1631897D01*
X1382102Y1631792D01*
X1382572Y1631477D01*
G01X1394075Y1633997D02*
Y1627697D01*
G01X1392978Y1631897D02*
X1395172D01*
G01X1400375Y1627697D02*
X1399905Y1627802D01*
X1399435Y1628222D01*
X1399122Y1628957D01*
X1398965Y1629797D01*
X1399122Y1630637D01*
X1399435Y1631372D01*
X1399905Y1631792D01*
X1400375Y1631897D01*
X1400845Y1631792D01*
X1401315Y1631372D01*
X1401628Y1630637D01*
X1401707Y1629797D01*
X1401628Y1628957D01*
X1401315Y1628222D01*
X1400845Y1627802D01*
X1400375Y1627697D01*
G01X1411800Y1628432D02*
X1412192Y1628012D01*
X1412740Y1627697D01*
X1413210D01*
X1413680Y1627907D01*
X1413993Y1628222D01*
X1414150Y1628642D01*
X1414072Y1629272D01*
X1413758Y1629587D01*
X1412348Y1630217D01*
X1412035Y1630952D01*
X1412192Y1631477D01*
X1412505Y1631792D01*
X1412975Y1631897D01*
X1413445Y1631792D01*
X1413915Y1631477D01*
G01X1419275Y1633997D02*
Y1627697D01*
G01X1418178Y1631897D02*
X1420372D01*
G01X1426985Y1627697D02*
Y1631897D01*
G01Y1631162D02*
X1426672Y1631582D01*
X1426202Y1631792D01*
X1425653Y1631897D01*
X1425105Y1631687D01*
X1424635Y1631267D01*
X1424322Y1630637D01*
X1424165Y1629797D01*
X1424322Y1628957D01*
X1424635Y1628327D01*
X1425105Y1627907D01*
X1425653Y1627697D01*
X1426202Y1627802D01*
X1426672Y1628117D01*
X1426985Y1628537D01*
G01X1433128Y1631372D02*
X1432580Y1631792D01*
X1432110Y1631897D01*
X1431483Y1631687D01*
X1431013Y1631267D01*
X1430700Y1630532D01*
X1430622Y1629797D01*
X1430700Y1629062D01*
X1431013Y1628432D01*
X1431483Y1627907D01*
X1432110Y1627697D01*
X1432658Y1627907D01*
X1433128Y1628327D01*
G01X1436843Y1627697D02*
Y1633997D01*
G01X1439350Y1631897D02*
X1436843Y1629482D01*
G01X1437862Y1630427D02*
X1439507Y1627697D01*
G01X1443143Y1631897D02*
Y1628957D01*
X1443457Y1628222D01*
X1443927Y1627802D01*
X1444475Y1627697D01*
X1445023Y1627802D01*
X1445493Y1628222D01*
X1445807Y1628957D01*
G01Y1627697D02*
Y1631897D01*
G01X1449365Y1625597D02*
Y1631897D01*
G01Y1630952D02*
X1449757Y1631477D01*
X1450148Y1631792D01*
X1450775Y1631897D01*
X1451323Y1631792D01*
X1451872Y1631267D01*
X1452107Y1630532D01*
X1452185Y1629797D01*
X1452107Y1629062D01*
X1451872Y1628327D01*
X1451402Y1627907D01*
X1450775Y1627697D01*
X1450227Y1627802D01*
X1449678Y1628117D01*
X1449365Y1628537D01*
G01X1462905Y1627697D02*
Y1633052D01*
X1463062Y1633577D01*
X1463375Y1633892D01*
X1463845Y1633997D01*
X1464315Y1633787D01*
X1464550Y1633262D01*
G01X1463610Y1631477D02*
X1462043D01*
G01X1469675Y1631897D02*
Y1627697D01*
G01Y1633577D02*
X1469518Y1633682D01*
Y1633892D01*
X1469675Y1633997D01*
X1469832Y1633892D01*
Y1633682D01*
X1469675Y1633577D01*
G01X1475975Y1627697D02*
Y1633997D01*
G01X1481100Y1630532D02*
X1483607D01*
X1483372Y1631267D01*
X1482980Y1631687D01*
X1482432Y1631897D01*
X1481883Y1631792D01*
X1481413Y1631477D01*
X1481100Y1630742D01*
X1480943Y1630112D01*
Y1629482D01*
X1481100Y1628852D01*
X1481492Y1628222D01*
X1481962Y1627802D01*
X1482510Y1627697D01*
X1483058Y1627907D01*
X1483607Y1628537D01*
G01X1488575Y1627487D02*
X1488418Y1627592D01*
Y1627802D01*
X1488575Y1627907D01*
X1488732Y1627802D01*
Y1627592D01*
X1488575Y1627487D01*
G01X1310421Y1641087D02*
Y1647387D01*
X1312458Y1642137D01*
X1314495Y1647387D01*
Y1641087D01*
G01X1320168D02*
Y1645287D01*
G01Y1644552D02*
X1319855Y1644972D01*
X1319385Y1645182D01*
X1318836Y1645287D01*
X1318288Y1645077D01*
X1317818Y1644657D01*
X1317505Y1644027D01*
X1317348Y1643187D01*
X1317505Y1642347D01*
X1317818Y1641717D01*
X1318288Y1641297D01*
X1318836Y1641087D01*
X1319385Y1641192D01*
X1319855Y1641507D01*
X1320168Y1641927D01*
G01X1323883Y1641822D02*
X1324275Y1641402D01*
X1324823Y1641087D01*
X1325293D01*
X1325763Y1641297D01*
X1326076Y1641612D01*
X1326233Y1642032D01*
X1326155Y1642662D01*
X1325841Y1642977D01*
X1324431Y1643607D01*
X1324118Y1644342D01*
X1324275Y1644867D01*
X1324588Y1645182D01*
X1325058Y1645287D01*
X1325528Y1645182D01*
X1325998Y1644867D01*
G01X1330026Y1641087D02*
Y1647387D01*
G01X1332533Y1645287D02*
X1330026Y1642872D01*
G01X1331045Y1643817D02*
X1332690Y1641087D01*
G01X1343958Y1647387D02*
Y1641087D01*
G01X1342861Y1645287D02*
X1345055D01*
G01X1350258Y1641087D02*
X1349788Y1641192D01*
X1349318Y1641612D01*
X1349005Y1642347D01*
X1348848Y1643187D01*
X1349005Y1644027D01*
X1349318Y1644762D01*
X1349788Y1645182D01*
X1350258Y1645287D01*
X1350728Y1645182D01*
X1351198Y1644762D01*
X1351511Y1644027D01*
X1351590Y1643187D01*
X1351511Y1642347D01*
X1351198Y1641612D01*
X1350728Y1641192D01*
X1350258Y1641087D01*
G01X1360821D02*
Y1647387D01*
X1362858Y1642137D01*
X1364895Y1647387D01*
Y1641087D01*
G01X1370568D02*
Y1645287D01*
G01Y1644552D02*
X1370255Y1644972D01*
X1369785Y1645182D01*
X1369236Y1645287D01*
X1368688Y1645077D01*
X1368218Y1644657D01*
X1367905Y1644027D01*
X1367748Y1643187D01*
X1367905Y1642347D01*
X1368218Y1641717D01*
X1368688Y1641297D01*
X1369236Y1641087D01*
X1369785Y1641192D01*
X1370255Y1641507D01*
X1370568Y1641927D01*
G01X1374283Y1641822D02*
X1374675Y1641402D01*
X1375223Y1641087D01*
X1375693D01*
X1376163Y1641297D01*
X1376476Y1641612D01*
X1376633Y1642032D01*
X1376555Y1642662D01*
X1376241Y1642977D01*
X1374831Y1643607D01*
X1374518Y1644342D01*
X1374675Y1644867D01*
X1374988Y1645182D01*
X1375458Y1645287D01*
X1375928Y1645182D01*
X1376398Y1644867D01*
G01X1380426Y1641087D02*
Y1647387D01*
G01X1382933Y1645287D02*
X1380426Y1642872D01*
G01X1381445Y1643817D02*
X1383090Y1641087D01*
G01X1394358Y1647387D02*
Y1641087D01*
G01X1393261Y1645287D02*
X1395455D01*
G01X1399326Y1641087D02*
Y1647387D01*
G01Y1644342D02*
X1399718Y1644867D01*
X1400110Y1645182D01*
X1400736Y1645287D01*
X1401206Y1645182D01*
X1401755Y1644762D01*
X1401990Y1644132D01*
Y1641087D01*
G01X1406958Y1645287D02*
Y1641087D01*
G01Y1646967D02*
X1406801Y1647072D01*
Y1647282D01*
X1406958Y1647387D01*
X1407115Y1647282D01*
Y1647072D01*
X1406958Y1646967D01*
G01X1414511Y1644762D02*
X1413963Y1645182D01*
X1413493Y1645287D01*
X1412866Y1645077D01*
X1412396Y1644657D01*
X1412083Y1643922D01*
X1412005Y1643187D01*
X1412083Y1642452D01*
X1412396Y1641822D01*
X1412866Y1641297D01*
X1413493Y1641087D01*
X1414041Y1641297D01*
X1414511Y1641717D01*
G01X1418226Y1641087D02*
Y1647387D01*
G01X1420733Y1645287D02*
X1418226Y1642872D01*
G01X1419245Y1643817D02*
X1420890Y1641087D01*
G01X1424526D02*
Y1645287D01*
G01Y1644237D02*
X1424840Y1644762D01*
X1425310Y1645182D01*
X1425936Y1645287D01*
X1426485Y1645182D01*
X1426955Y1644762D01*
X1427190Y1644027D01*
Y1641087D01*
G01X1430983Y1643922D02*
X1433490D01*
X1433255Y1644657D01*
X1432863Y1645077D01*
X1432315Y1645287D01*
X1431766Y1645182D01*
X1431296Y1644867D01*
X1430983Y1644132D01*
X1430826Y1643502D01*
Y1642872D01*
X1430983Y1642242D01*
X1431375Y1641612D01*
X1431845Y1641192D01*
X1432393Y1641087D01*
X1432941Y1641297D01*
X1433490Y1641927D01*
G01X1437283Y1641822D02*
X1437675Y1641402D01*
X1438223Y1641087D01*
X1438693D01*
X1439163Y1641297D01*
X1439476Y1641612D01*
X1439633Y1642032D01*
X1439555Y1642662D01*
X1439241Y1642977D01*
X1437831Y1643607D01*
X1437518Y1644342D01*
X1437675Y1644867D01*
X1437988Y1645182D01*
X1438458Y1645287D01*
X1438928Y1645182D01*
X1439398Y1644867D01*
G01X1443583Y1641822D02*
X1443975Y1641402D01*
X1444523Y1641087D01*
X1444993D01*
X1445463Y1641297D01*
X1445776Y1641612D01*
X1445933Y1642032D01*
X1445855Y1642662D01*
X1445541Y1642977D01*
X1444131Y1643607D01*
X1443818Y1644342D01*
X1443975Y1644867D01*
X1444288Y1645182D01*
X1444758Y1645287D01*
X1445228Y1645182D01*
X1445698Y1644867D01*
G01X1333805Y1123750D02*
Y1136250D01*
X1339695D01*
G01X1337525Y1130208D02*
X1333805D01*
G01X1347290Y1136250D02*
X1351010D01*
G01X1349150D02*
Y1123750D01*
G01X1347290D02*
X1351010D01*
G01X1357985D02*
Y1136250D01*
X1365115Y1123750D01*
Y1136250D01*
G01X1372090D02*
X1375810D01*
G01X1373950D02*
Y1123750D01*
G01X1372090D02*
X1375810D01*
G01X1383095Y1125416D02*
X1384335Y1124375D01*
X1385730Y1123750D01*
X1386970D01*
X1388210Y1124375D01*
X1389140Y1125416D01*
X1389605Y1126875D01*
X1389295Y1128333D01*
X1388520Y1129583D01*
X1387125Y1130417D01*
X1385265Y1130833D01*
X1384180Y1131667D01*
X1383715Y1133125D01*
X1384025Y1134583D01*
X1384800Y1135625D01*
X1385885Y1136250D01*
X1386970D01*
X1388055Y1135833D01*
X1388985Y1134792D01*
G01X1395495Y1123750D02*
Y1136250D01*
G01X1402005D02*
Y1123750D01*
G01Y1130000D02*
X1395495D01*
G01X1414250Y1123750D02*
X1408050D01*
Y1136250D01*
X1414250D01*
G01X1411770Y1130208D02*
X1408050D01*
G01X1420140Y1123750D02*
Y1136250D01*
X1423240D01*
X1424480Y1135625D01*
X1425410Y1134792D01*
X1426185Y1133542D01*
X1426805Y1132083D01*
X1426960Y1130000D01*
X1426805Y1127917D01*
X1426185Y1126458D01*
X1425410Y1125208D01*
X1424480Y1124375D01*
X1423240Y1123750D01*
X1420140D01*
G01X1431300Y1119583D02*
X1440600D01*
G01X1445095Y1125416D02*
X1446335Y1124375D01*
X1447730Y1123750D01*
X1448970D01*
X1450210Y1124375D01*
X1451140Y1125416D01*
X1451605Y1126875D01*
X1451295Y1128333D01*
X1450520Y1129583D01*
X1449125Y1130417D01*
X1447265Y1130833D01*
X1446180Y1131667D01*
X1445715Y1133125D01*
X1446025Y1134583D01*
X1446800Y1135625D01*
X1447885Y1136250D01*
X1448970D01*
X1450055Y1135833D01*
X1450985Y1134792D01*
G01X1458890Y1136250D02*
X1462610D01*
G01X1460750D02*
Y1123750D01*
G01X1458890D02*
X1462610D01*
G01X1470205Y1136250D02*
X1476095D01*
X1470205Y1123750D01*
X1476095D01*
G01X1488650D02*
X1482450D01*
Y1136250D01*
X1488650D01*
G01X1486170Y1130208D02*
X1482450D01*
G01X1344400Y1668100D02*
X1340400D01*
Y1676100D01*
X1344400D01*
G01X1342800Y1672233D02*
X1340400D01*
G01X1352200Y1676100D02*
Y1668100D01*
G01Y1669300D02*
X1351800Y1668633D01*
X1351200Y1668233D01*
X1350500Y1668100D01*
X1349700Y1668367D01*
X1349100Y1669033D01*
X1348700Y1669833D01*
X1348600Y1670767D01*
X1348700Y1671700D01*
X1349100Y1672500D01*
X1349700Y1673167D01*
X1350500Y1673433D01*
X1351200Y1673300D01*
X1351700Y1673033D01*
X1352200Y1672500D01*
G01X1357000Y1666100D02*
X1357700Y1665567D01*
X1358500Y1665433D01*
X1359200Y1665567D01*
X1359800Y1666233D01*
X1360200Y1667167D01*
Y1673433D01*
G01Y1672367D02*
X1359800Y1672900D01*
X1359200Y1673300D01*
X1358500Y1673433D01*
X1357700Y1673167D01*
X1357200Y1672633D01*
X1356800Y1671700D01*
X1356600Y1670767D01*
X1356700Y1669967D01*
X1357100Y1669033D01*
X1357700Y1668367D01*
X1358500Y1668100D01*
X1359100Y1668233D01*
X1359800Y1668767D01*
X1360200Y1669300D01*
G01X1364900Y1671700D02*
X1368100D01*
X1367800Y1672633D01*
X1367300Y1673167D01*
X1366600Y1673433D01*
X1365900Y1673300D01*
X1365300Y1672900D01*
X1364900Y1671967D01*
X1364700Y1671166D01*
Y1670367D01*
X1364900Y1669567D01*
X1365400Y1668767D01*
X1366000Y1668233D01*
X1366700Y1668100D01*
X1367400Y1668367D01*
X1368100Y1669166D01*
G01X1384600Y1675433D02*
X1384000Y1675833D01*
X1383300Y1676100D01*
X1382500D01*
X1381600Y1675700D01*
X1380900Y1675033D01*
X1380400Y1674233D01*
X1380000Y1672900D01*
X1379900Y1671700D01*
X1380100Y1670500D01*
X1380400Y1669700D01*
X1381000Y1668900D01*
X1381700Y1668367D01*
X1382400Y1668100D01*
X1383100D01*
X1383800Y1668367D01*
X1384400Y1668767D01*
X1384900Y1669300D01*
G01X1390400Y1668100D02*
X1389800Y1668233D01*
X1389200Y1668767D01*
X1388800Y1669700D01*
X1388600Y1670767D01*
X1388800Y1671833D01*
X1389200Y1672767D01*
X1389800Y1673300D01*
X1390400Y1673433D01*
X1391000Y1673300D01*
X1391600Y1672767D01*
X1392000Y1671833D01*
X1392100Y1670767D01*
X1392000Y1669700D01*
X1391600Y1668767D01*
X1391000Y1668233D01*
X1390400Y1668100D01*
G01X1396700D02*
Y1673433D01*
G01Y1672100D02*
X1397100Y1672767D01*
X1397700Y1673300D01*
X1398500Y1673433D01*
X1399200Y1673300D01*
X1399800Y1672767D01*
X1400100Y1671833D01*
Y1668100D01*
G01X1404700D02*
Y1673433D01*
G01Y1672100D02*
X1405100Y1672767D01*
X1405700Y1673300D01*
X1406500Y1673433D01*
X1407200Y1673300D01*
X1407800Y1672767D01*
X1408100Y1671833D01*
Y1668100D01*
G01X1412900Y1671700D02*
X1416100D01*
X1415800Y1672633D01*
X1415300Y1673167D01*
X1414600Y1673433D01*
X1413900Y1673300D01*
X1413300Y1672900D01*
X1412900Y1671967D01*
X1412700Y1671166D01*
Y1670367D01*
X1412900Y1669567D01*
X1413400Y1668767D01*
X1414000Y1668233D01*
X1414700Y1668100D01*
X1415400Y1668367D01*
X1416100Y1669166D01*
G01X1424000Y1672767D02*
X1423300Y1673300D01*
X1422700Y1673433D01*
X1421900Y1673167D01*
X1421300Y1672633D01*
X1420900Y1671700D01*
X1420800Y1670767D01*
X1420900Y1669833D01*
X1421300Y1669033D01*
X1421900Y1668367D01*
X1422700Y1668100D01*
X1423400Y1668367D01*
X1424000Y1668900D01*
G01X1430400Y1676100D02*
Y1668100D01*
G01X1429000Y1673433D02*
X1431800D01*
G01X1438400Y1668100D02*
X1437800Y1668233D01*
X1437200Y1668767D01*
X1436800Y1669700D01*
X1436600Y1670767D01*
X1436800Y1671833D01*
X1437200Y1672767D01*
X1437800Y1673300D01*
X1438400Y1673433D01*
X1439000Y1673300D01*
X1439600Y1672767D01*
X1440000Y1671833D01*
X1440100Y1670767D01*
X1440000Y1669700D01*
X1439600Y1668767D01*
X1439000Y1668233D01*
X1438400Y1668100D01*
G01X1445000D02*
Y1673433D01*
G01Y1672367D02*
X1445500Y1672900D01*
X1446000Y1673300D01*
X1446700Y1673433D01*
X1447200Y1673300D01*
X1447800Y1672900D01*
G01X1367500Y1420000D02*
Y1372000D01*
G01Y1377000D02*
X1362500Y1378500D01*
Y1375500D01*
X1367500Y1377000D01*
G01D02*
X1352500D01*
G01X1364500Y1587720D02*
Y1486000D01*
X1367500D01*
Y1426000D01*
X1372500Y1406000D01*
X1382500D01*
X1387500Y1426000D01*
Y1486000D01*
X1390500D01*
Y1590600D01*
G01X1364583Y1595131D02*
Y1623131D01*
G01X1349583Y1618131D02*
X1364583D01*
G01D02*
X1359583Y1616631D01*
Y1619631D01*
X1364583Y1618131D01*
G01X1386350Y827750D02*
Y840250D01*
X1384490Y837750D01*
G01Y827750D02*
X1388210D01*
G01X1395805Y838167D02*
X1396735Y839416D01*
X1397820Y840042D01*
X1399060Y840250D01*
X1400610Y839833D01*
X1401695Y838792D01*
X1402005Y837542D01*
X1401850Y836291D01*
X1401230Y835250D01*
X1398130Y833167D01*
X1396735Y831708D01*
X1395805Y829625D01*
X1395495Y827750D01*
X1402005D01*
G01X1407740Y829625D02*
X1408670Y828583D01*
X1409755Y827958D01*
X1411150Y827750D01*
X1412545Y828167D01*
X1413630Y829000D01*
X1414405Y830458D01*
X1414560Y832125D01*
X1414250Y833792D01*
X1413475Y834833D01*
X1412390Y835667D01*
X1411305Y835875D01*
X1410220Y835667D01*
X1408825Y834833D01*
X1409290Y840250D01*
X1413475D01*
G01X1423550Y827333D02*
X1423240Y827542D01*
Y827958D01*
X1423550Y828167D01*
X1423860Y827958D01*
Y827542D01*
X1423550Y827333D01*
G01X1435950Y840250D02*
X1434710Y839833D01*
X1433780Y838792D01*
X1433160Y837542D01*
X1432695Y835875D01*
X1432540Y834000D01*
X1432695Y832125D01*
X1433160Y830458D01*
X1433780Y829208D01*
X1434710Y828167D01*
X1435950Y827750D01*
X1437190Y828167D01*
X1438120Y829208D01*
X1438740Y830458D01*
X1439205Y832125D01*
X1439360Y834000D01*
X1439205Y835875D01*
X1438740Y837542D01*
X1438120Y838792D01*
X1437190Y839833D01*
X1435950Y840250D01*
G01X1389140Y867425D02*
X1390070Y866383D01*
X1391155Y865758D01*
X1392550Y865550D01*
X1393945Y865967D01*
X1395030Y866800D01*
X1395805Y868258D01*
X1395960Y869925D01*
X1395650Y871592D01*
X1394875Y872633D01*
X1393790Y873467D01*
X1392705Y873675D01*
X1391620Y873467D01*
X1390225Y872633D01*
X1390690Y878050D01*
X1394875D01*
G01X1402315Y867008D02*
X1403400Y865967D01*
X1404640Y865550D01*
X1405880Y865967D01*
X1406965Y867216D01*
X1407740Y869092D01*
X1408050Y870967D01*
Y873258D01*
X1407740Y875133D01*
X1406965Y876800D01*
X1406035Y877633D01*
X1404950Y878050D01*
X1403710Y877633D01*
X1402780Y876800D01*
X1402160Y875550D01*
X1401850Y873883D01*
X1402160Y872425D01*
X1402935Y870967D01*
X1403865Y870133D01*
X1404950Y869925D01*
X1406190Y870341D01*
X1407120Y871383D01*
X1408050Y873258D01*
G01X1417350Y865133D02*
X1417040Y865342D01*
Y865758D01*
X1417350Y865967D01*
X1417660Y865758D01*
Y865342D01*
X1417350Y865133D01*
G01X1429750Y878050D02*
X1428510Y877633D01*
X1427580Y876592D01*
X1426960Y875342D01*
X1426495Y873675D01*
X1426340Y871800D01*
X1426495Y869925D01*
X1426960Y868258D01*
X1427580Y867008D01*
X1428510Y865967D01*
X1429750Y865550D01*
X1430990Y865967D01*
X1431920Y867008D01*
X1432540Y868258D01*
X1433005Y869925D01*
X1433160Y871800D01*
X1433005Y873675D01*
X1432540Y875342D01*
X1431920Y876592D01*
X1430990Y877633D01*
X1429750Y878050D01*
G01X1383405Y913767D02*
X1384335Y915016D01*
X1385420Y915642D01*
X1386660Y915850D01*
X1388210Y915433D01*
X1389295Y914392D01*
X1389605Y913142D01*
X1389450Y911891D01*
X1388830Y910850D01*
X1385730Y908767D01*
X1384335Y907308D01*
X1383405Y905225D01*
X1383095Y903350D01*
X1389605D01*
G01X1395340Y905225D02*
X1396270Y904183D01*
X1397355Y903558D01*
X1398750Y903350D01*
X1400145Y903767D01*
X1401230Y904600D01*
X1402005Y906058D01*
X1402160Y907725D01*
X1401850Y909392D01*
X1401075Y910433D01*
X1399990Y911267D01*
X1398905Y911475D01*
X1397820Y911267D01*
X1396425Y910433D01*
X1396890Y915850D01*
X1401075D01*
G01X1408205Y913767D02*
X1409135Y915016D01*
X1410220Y915642D01*
X1411460Y915850D01*
X1413010Y915433D01*
X1414095Y914392D01*
X1414405Y913142D01*
X1414250Y911891D01*
X1413630Y910850D01*
X1410530Y908767D01*
X1409135Y907308D01*
X1408205Y905225D01*
X1407895Y903350D01*
X1414405D01*
G01X1423550Y902933D02*
X1423240Y903142D01*
Y903558D01*
X1423550Y903767D01*
X1423860Y903558D01*
Y903142D01*
X1423550Y902933D01*
G01X1435950Y915850D02*
X1434710Y915433D01*
X1433780Y914392D01*
X1433160Y913142D01*
X1432695Y911475D01*
X1432540Y909600D01*
X1432695Y907725D01*
X1433160Y906058D01*
X1433780Y904808D01*
X1434710Y903767D01*
X1435950Y903350D01*
X1437190Y903767D01*
X1438120Y904808D01*
X1438740Y906058D01*
X1439205Y907725D01*
X1439360Y909600D01*
X1439205Y911475D01*
X1438740Y913142D01*
X1438120Y914392D01*
X1437190Y915433D01*
X1435950Y915850D01*
G01X1386350Y941150D02*
Y953650D01*
X1384490Y951150D01*
G01Y941150D02*
X1388210D01*
G01X1398750D02*
Y953650D01*
X1396890Y951150D01*
G01Y941150D02*
X1400610D01*
G01X1408515Y942608D02*
X1409600Y941567D01*
X1410840Y941150D01*
X1412080Y941567D01*
X1413165Y942816D01*
X1413940Y944692D01*
X1414250Y946567D01*
Y948858D01*
X1413940Y950733D01*
X1413165Y952400D01*
X1412235Y953233D01*
X1411150Y953650D01*
X1409910Y953233D01*
X1408980Y952400D01*
X1408360Y951150D01*
X1408050Y949483D01*
X1408360Y948025D01*
X1409135Y946567D01*
X1410065Y945733D01*
X1411150Y945525D01*
X1412390Y945941D01*
X1413320Y946983D01*
X1414250Y948858D01*
G01X1423550Y940733D02*
X1423240Y940942D01*
Y941358D01*
X1423550Y941567D01*
X1423860Y941358D01*
Y940942D01*
X1423550Y940733D01*
G01X1435950Y953650D02*
X1434710Y953233D01*
X1433780Y952192D01*
X1433160Y950942D01*
X1432695Y949275D01*
X1432540Y947400D01*
X1432695Y945525D01*
X1433160Y943858D01*
X1433780Y942608D01*
X1434710Y941567D01*
X1435950Y941150D01*
X1437190Y941567D01*
X1438120Y942608D01*
X1438740Y943858D01*
X1439205Y945525D01*
X1439360Y947400D01*
X1439205Y949275D01*
X1438740Y950942D01*
X1438120Y952192D01*
X1437190Y953233D01*
X1435950Y953650D01*
G01X1389605Y984158D02*
X1390690Y985617D01*
X1391620Y986450D01*
X1392860Y986867D01*
X1393945Y986450D01*
X1394720Y985617D01*
X1395340Y984367D01*
X1395495Y982908D01*
X1395340Y981658D01*
X1394720Y980408D01*
X1393790Y979367D01*
X1392705Y978950D01*
X1391465Y979367D01*
X1390380Y980616D01*
X1389760Y982492D01*
X1389605Y984575D01*
X1389915Y987283D01*
X1390380Y988742D01*
X1391155Y990200D01*
X1392240Y991242D01*
X1393325Y991450D01*
X1394410Y991033D01*
X1395185Y989992D01*
G01X1404640Y978950D02*
X1404950Y981658D01*
X1405415Y983950D01*
X1406035Y986033D01*
X1406810Y988325D01*
X1408050Y991450D01*
X1401850D01*
G01X1417350Y978533D02*
X1417040Y978742D01*
Y979158D01*
X1417350Y979367D01*
X1417660Y979158D01*
Y978742D01*
X1417350Y978533D01*
G01X1429750Y991450D02*
X1428510Y991033D01*
X1427580Y989992D01*
X1426960Y988742D01*
X1426495Y987075D01*
X1426340Y985200D01*
X1426495Y983325D01*
X1426960Y981658D01*
X1427580Y980408D01*
X1428510Y979367D01*
X1429750Y978950D01*
X1430990Y979367D01*
X1431920Y980408D01*
X1432540Y981658D01*
X1433005Y983325D01*
X1433160Y985200D01*
X1433005Y987075D01*
X1432540Y988742D01*
X1431920Y989992D01*
X1430990Y991033D01*
X1429750Y991450D01*
G01X1389140Y1019250D02*
X1390070Y1017791D01*
X1391310Y1016958D01*
X1392705Y1016750D01*
X1393945Y1016958D01*
X1395185Y1018000D01*
X1395960Y1019250D01*
X1396115Y1020500D01*
X1395805Y1021958D01*
X1394720Y1023000D01*
X1393635Y1023417D01*
X1392240D01*
G01X1393635D02*
X1394565Y1024042D01*
X1395340Y1025083D01*
X1395650Y1026333D01*
X1395340Y1027583D01*
X1394565Y1028625D01*
X1393170Y1029250D01*
X1391775Y1029042D01*
X1390380Y1028208D01*
G01X1404950Y1016750D02*
X1406035Y1016958D01*
X1407275Y1017583D01*
X1408050Y1018625D01*
X1408360Y1020083D01*
X1408050Y1021541D01*
X1407120Y1022792D01*
X1405725Y1023417D01*
X1404175D01*
X1403245Y1023833D01*
X1402470Y1024875D01*
X1402160Y1026333D01*
X1402625Y1027792D01*
X1403710Y1028833D01*
X1404950Y1029250D01*
X1406190Y1028833D01*
X1407275Y1027792D01*
X1407740Y1026333D01*
X1407430Y1024875D01*
X1406655Y1023833D01*
X1405725Y1023417D01*
X1404175D01*
X1402780Y1022792D01*
X1401850Y1021541D01*
X1401540Y1020083D01*
X1401850Y1018625D01*
X1402625Y1017583D01*
X1403865Y1016958D01*
X1404950Y1016750D01*
G01X1417350Y1016333D02*
X1417040Y1016542D01*
Y1016958D01*
X1417350Y1017167D01*
X1417660Y1016958D01*
Y1016542D01*
X1417350Y1016333D01*
G01X1429750Y1029250D02*
X1428510Y1028833D01*
X1427580Y1027792D01*
X1426960Y1026542D01*
X1426495Y1024875D01*
X1426340Y1023000D01*
X1426495Y1021125D01*
X1426960Y1019458D01*
X1427580Y1018208D01*
X1428510Y1017167D01*
X1429750Y1016750D01*
X1430990Y1017167D01*
X1431920Y1018208D01*
X1432540Y1019458D01*
X1433005Y1021125D01*
X1433160Y1023000D01*
X1433005Y1024875D01*
X1432540Y1026542D01*
X1431920Y1027792D01*
X1430990Y1028833D01*
X1429750Y1029250D01*
G01X1392550Y1054550D02*
Y1067050D01*
X1390690Y1064550D01*
G01Y1054550D02*
X1394410D01*
G01X1404950Y1067050D02*
X1403710Y1066633D01*
X1402780Y1065592D01*
X1402160Y1064342D01*
X1401695Y1062675D01*
X1401540Y1060800D01*
X1401695Y1058925D01*
X1402160Y1057258D01*
X1402780Y1056008D01*
X1403710Y1054967D01*
X1404950Y1054550D01*
X1406190Y1054967D01*
X1407120Y1056008D01*
X1407740Y1057258D01*
X1408205Y1058925D01*
X1408360Y1060800D01*
X1408205Y1062675D01*
X1407740Y1064342D01*
X1407120Y1065592D01*
X1406190Y1066633D01*
X1404950Y1067050D01*
G01X1417350Y1054133D02*
X1417040Y1054342D01*
Y1054758D01*
X1417350Y1054967D01*
X1417660Y1054758D01*
Y1054342D01*
X1417350Y1054133D01*
G01X1429750Y1067050D02*
X1428510Y1066633D01*
X1427580Y1065592D01*
X1426960Y1064342D01*
X1426495Y1062675D01*
X1426340Y1060800D01*
X1426495Y1058925D01*
X1426960Y1057258D01*
X1427580Y1056008D01*
X1428510Y1054967D01*
X1429750Y1054550D01*
X1430990Y1054967D01*
X1431920Y1056008D01*
X1432540Y1057258D01*
X1433005Y1058925D01*
X1433160Y1060800D01*
X1433005Y1062675D01*
X1432540Y1064342D01*
X1431920Y1065592D01*
X1430990Y1066633D01*
X1429750Y1067050D01*
G01X1392550Y1092350D02*
Y1104850D01*
X1390690Y1102350D01*
G01Y1092350D02*
X1394410D01*
G01X1404950Y1104850D02*
X1403710Y1104433D01*
X1402780Y1103392D01*
X1402160Y1102142D01*
X1401695Y1100475D01*
X1401540Y1098600D01*
X1401695Y1096725D01*
X1402160Y1095058D01*
X1402780Y1093808D01*
X1403710Y1092767D01*
X1404950Y1092350D01*
X1406190Y1092767D01*
X1407120Y1093808D01*
X1407740Y1095058D01*
X1408205Y1096725D01*
X1408360Y1098600D01*
X1408205Y1100475D01*
X1407740Y1102142D01*
X1407120Y1103392D01*
X1406190Y1104433D01*
X1404950Y1104850D01*
G01X1417350Y1091933D02*
X1417040Y1092142D01*
Y1092558D01*
X1417350Y1092767D01*
X1417660Y1092558D01*
Y1092142D01*
X1417350Y1091933D01*
G01X1429750Y1104850D02*
X1428510Y1104433D01*
X1427580Y1103392D01*
X1426960Y1102142D01*
X1426495Y1100475D01*
X1426340Y1098600D01*
X1426495Y1096725D01*
X1426960Y1095058D01*
X1427580Y1093808D01*
X1428510Y1092767D01*
X1429750Y1092350D01*
X1430990Y1092767D01*
X1431920Y1093808D01*
X1432540Y1095058D01*
X1433005Y1096725D01*
X1433160Y1098600D01*
X1433005Y1100475D01*
X1432540Y1102142D01*
X1431920Y1103392D01*
X1430990Y1104433D01*
X1429750Y1104850D01*
G01X1387500Y1420000D02*
Y1372000D01*
G01Y1377000D02*
X1392500Y1378500D01*
Y1375500D01*
X1387500Y1377000D01*
G01X1402500D02*
X1387500D01*
G01X1384500Y1406000D02*
X1431500D01*
G01X1389500Y1426000D02*
X1431500D01*
G01X1430147Y1596588D02*
X1388576Y1430304D01*
G01X1390557Y1568360D02*
X1395557Y1566860D01*
Y1569860D01*
X1390557Y1568360D01*
G01X1438054Y1549319D02*
G03X1390754Y1568480I-47300J-48801D01*
G01X1390483Y1595431D02*
Y1623431D01*
G01Y1618431D02*
X1395483Y1616931D01*
Y1619931D01*
X1390483Y1618431D01*
G01D02*
X1405483D01*
G01X1410840Y1173750D02*
Y1186250D01*
X1413940D01*
X1415180Y1185625D01*
X1416110Y1184792D01*
X1416885Y1183542D01*
X1417505Y1182083D01*
X1417660Y1180000D01*
X1417505Y1177917D01*
X1416885Y1176458D01*
X1416110Y1175208D01*
X1415180Y1174375D01*
X1413940Y1173750D01*
X1410840D01*
G01X1423550D02*
Y1186250D01*
X1427425D01*
X1428665Y1185625D01*
X1429440Y1184792D01*
X1429750Y1183125D01*
X1429440Y1181458D01*
X1428510Y1180417D01*
X1427425Y1179792D01*
X1423550D01*
G01X1427425D02*
X1429750Y1173750D01*
G01X1437190Y1186250D02*
X1440910D01*
G01X1439050D02*
Y1173750D01*
G01X1437190D02*
X1440910D01*
G01X1448350Y1186250D02*
Y1173750D01*
X1454550D01*
G01X1460750Y1186250D02*
Y1173750D01*
X1466950D01*
G01X1492060Y1185208D02*
X1491130Y1185833D01*
X1490045Y1186250D01*
X1488805D01*
X1487410Y1185625D01*
X1486325Y1184583D01*
X1485550Y1183333D01*
X1484930Y1181250D01*
X1484775Y1179375D01*
X1485085Y1177500D01*
X1485550Y1176250D01*
X1486480Y1175000D01*
X1487565Y1174167D01*
X1488650Y1173750D01*
X1489735D01*
X1490820Y1174167D01*
X1491750Y1174791D01*
X1492525Y1175625D01*
G01X1497795Y1173750D02*
Y1186250D01*
G01X1504305D02*
Y1173750D01*
G01Y1180000D02*
X1497795D01*
G01X1509575Y1173750D02*
X1513450Y1186250D01*
X1517325Y1173750D01*
G01X1515930Y1178125D02*
X1510970D01*
G01X1522750Y1173750D02*
Y1186250D01*
X1526625D01*
X1527865Y1185625D01*
X1528640Y1184792D01*
X1528950Y1183125D01*
X1528640Y1181458D01*
X1527710Y1180417D01*
X1526625Y1179792D01*
X1522750D01*
G01X1526625D02*
X1528950Y1173750D01*
G01X1538250Y1186250D02*
Y1173750D01*
G01X1534685Y1186250D02*
X1541815D01*
G01X1550650Y1173333D02*
X1550340Y1173542D01*
Y1173958D01*
X1550650Y1174167D01*
X1550960Y1173958D01*
Y1173542D01*
X1550650Y1173333D01*
G01Y1178958D02*
X1550340Y1179167D01*
Y1179583D01*
X1550650Y1179792D01*
X1550960Y1179583D01*
Y1179167D01*
X1550650Y1178958D01*
G01X1575450Y1186250D02*
Y1173750D01*
G01X1571885Y1186250D02*
X1579015D01*
G01X1587850Y1173750D02*
X1586610Y1173958D01*
X1585525Y1174791D01*
X1584595Y1176042D01*
X1583975Y1177500D01*
X1583665Y1179167D01*
Y1180833D01*
X1583975Y1182500D01*
X1584595Y1183958D01*
X1585525Y1185208D01*
X1586610Y1186042D01*
X1587850Y1186250D01*
X1589090Y1186042D01*
X1590175Y1185208D01*
X1591105Y1183958D01*
X1591725Y1182500D01*
X1592035Y1180833D01*
Y1179167D01*
X1591725Y1177500D01*
X1591105Y1176042D01*
X1590175Y1174791D01*
X1589090Y1173958D01*
X1587850Y1173750D01*
G01X1597150D02*
Y1186250D01*
X1600870D01*
X1602110Y1185625D01*
X1603040Y1184167D01*
X1603350Y1182500D01*
X1603040Y1180833D01*
X1602265Y1179583D01*
X1600870Y1178958D01*
X1597150D01*
G01X1625050Y1186250D02*
Y1173750D01*
G01X1622880Y1182083D02*
X1627220D01*
G01X1637450Y1173750D02*
X1636520Y1173958D01*
X1635590Y1174791D01*
X1634970Y1176250D01*
X1634660Y1177917D01*
X1634970Y1179583D01*
X1635590Y1181042D01*
X1636520Y1181875D01*
X1637450Y1182083D01*
X1638380Y1181875D01*
X1639310Y1181042D01*
X1639930Y1179583D01*
X1640085Y1177917D01*
X1639930Y1176250D01*
X1639310Y1174791D01*
X1638380Y1173958D01*
X1637450Y1173750D01*
G01X1663490Y1180417D02*
X1664110Y1181042D01*
X1664575Y1182083D01*
X1664885Y1183542D01*
X1664575Y1184792D01*
X1663955Y1185625D01*
X1662870Y1186250D01*
X1658685D01*
Y1173750D01*
X1663800D01*
X1664885Y1174583D01*
X1665505Y1175833D01*
X1665815Y1177292D01*
X1665505Y1178750D01*
X1664575Y1180000D01*
X1663490Y1180417D01*
X1658685D01*
G01X1674650Y1173750D02*
X1673410Y1173958D01*
X1672325Y1174791D01*
X1671395Y1176042D01*
X1670775Y1177500D01*
X1670465Y1179167D01*
Y1180833D01*
X1670775Y1182500D01*
X1671395Y1183958D01*
X1672325Y1185208D01*
X1673410Y1186042D01*
X1674650Y1186250D01*
X1675890Y1186042D01*
X1676975Y1185208D01*
X1677905Y1183958D01*
X1678525Y1182500D01*
X1678835Y1180833D01*
Y1179167D01*
X1678525Y1177500D01*
X1677905Y1176042D01*
X1676975Y1174791D01*
X1675890Y1173958D01*
X1674650Y1173750D01*
G01X1687050Y1186250D02*
Y1173750D01*
G01X1683485Y1186250D02*
X1690615D01*
G01X1699450D02*
Y1173750D01*
G01X1695885Y1186250D02*
X1703015D01*
G01X1711850Y1173750D02*
X1710610Y1173958D01*
X1709525Y1174791D01*
X1708595Y1176042D01*
X1707975Y1177500D01*
X1707665Y1179167D01*
Y1180833D01*
X1707975Y1182500D01*
X1708595Y1183958D01*
X1709525Y1185208D01*
X1710610Y1186042D01*
X1711850Y1186250D01*
X1713090Y1186042D01*
X1714175Y1185208D01*
X1715105Y1183958D01*
X1715725Y1182500D01*
X1716035Y1180833D01*
Y1179167D01*
X1715725Y1177500D01*
X1715105Y1176042D01*
X1714175Y1174791D01*
X1713090Y1173958D01*
X1711850Y1173750D01*
G01X1720220D02*
Y1186250D01*
X1724250Y1175833D01*
X1728280Y1186250D01*
Y1173750D01*
G01X1411650Y1456800D02*
X1411023Y1456590D01*
X1410553Y1456065D01*
X1410240Y1455435D01*
X1410005Y1454595D01*
X1409927Y1453650D01*
X1410005Y1452705D01*
X1410240Y1451865D01*
X1410553Y1451235D01*
X1411023Y1450710D01*
X1411650Y1450500D01*
X1412277Y1450710D01*
X1412747Y1451235D01*
X1413060Y1451865D01*
X1413295Y1452705D01*
X1413373Y1453650D01*
X1413295Y1454595D01*
X1413060Y1455435D01*
X1412747Y1456065D01*
X1412277Y1456590D01*
X1411650Y1456800D01*
G01X1417950Y1450290D02*
X1417793Y1450395D01*
Y1450605D01*
X1417950Y1450710D01*
X1418107Y1450605D01*
Y1450395D01*
X1417950Y1450290D01*
G01X1422527Y1451445D02*
X1422997Y1450920D01*
X1423545Y1450605D01*
X1424250Y1450500D01*
X1424955Y1450710D01*
X1425503Y1451130D01*
X1425895Y1451865D01*
X1425973Y1452705D01*
X1425817Y1453545D01*
X1425425Y1454070D01*
X1424877Y1454490D01*
X1424328Y1454595D01*
X1423780Y1454490D01*
X1423075Y1454070D01*
X1423310Y1456800D01*
X1425425D01*
G01X1428200Y1450500D02*
Y1454700D01*
G01Y1453545D02*
X1428435Y1454070D01*
X1428827Y1454490D01*
X1429375Y1454700D01*
X1429923Y1454490D01*
X1430315Y1454070D01*
X1430550Y1453545D01*
Y1450500D01*
G01Y1453545D02*
X1430785Y1454070D01*
X1431177Y1454490D01*
X1431725Y1454700D01*
X1432273Y1454490D01*
X1432665Y1454070D01*
X1432900Y1453440D01*
Y1450500D01*
G01X1434500D02*
Y1454700D01*
G01Y1453545D02*
X1434735Y1454070D01*
X1435127Y1454490D01*
X1435675Y1454700D01*
X1436223Y1454490D01*
X1436615Y1454070D01*
X1436850Y1453545D01*
Y1450500D01*
G01Y1453545D02*
X1437085Y1454070D01*
X1437477Y1454490D01*
X1438025Y1454700D01*
X1438573Y1454490D01*
X1438965Y1454070D01*
X1439200Y1453440D01*
Y1450500D01*
G01X1455750Y1456800D02*
X1455123Y1456590D01*
X1454653Y1456065D01*
X1454340Y1455435D01*
X1454105Y1454595D01*
X1454027Y1453650D01*
X1454105Y1452705D01*
X1454340Y1451865D01*
X1454653Y1451235D01*
X1455123Y1450710D01*
X1455750Y1450500D01*
X1456377Y1450710D01*
X1456847Y1451235D01*
X1457160Y1451865D01*
X1457395Y1452705D01*
X1457473Y1453650D01*
X1457395Y1454595D01*
X1457160Y1455435D01*
X1456847Y1456065D01*
X1456377Y1456590D01*
X1455750Y1456800D01*
G01X1462050Y1450290D02*
X1461893Y1450395D01*
Y1450605D01*
X1462050Y1450710D01*
X1462207Y1450605D01*
Y1450395D01*
X1462050Y1450290D01*
G01X1466862Y1455750D02*
X1467332Y1456380D01*
X1467880Y1456695D01*
X1468507Y1456800D01*
X1469290Y1456590D01*
X1469838Y1456065D01*
X1469995Y1455435D01*
X1469917Y1454805D01*
X1469603Y1454280D01*
X1468037Y1453230D01*
X1467332Y1452495D01*
X1466862Y1451445D01*
X1466705Y1450500D01*
X1469995D01*
G01X1472927Y1451445D02*
X1473397Y1450920D01*
X1473945Y1450605D01*
X1474650Y1450500D01*
X1475355Y1450710D01*
X1475903Y1451130D01*
X1476295Y1451865D01*
X1476373Y1452705D01*
X1476217Y1453545D01*
X1475825Y1454070D01*
X1475277Y1454490D01*
X1474728Y1454595D01*
X1474180Y1454490D01*
X1473475Y1454070D01*
X1473710Y1456800D01*
X1475825D01*
G01X1421241Y1561247D02*
X1416241Y1562247D01*
X1417741Y1564747D01*
X1421241Y1561247D01*
G01X1441375Y1148750D02*
X1445250Y1161250D01*
X1449125Y1148750D01*
G01X1447730Y1153125D02*
X1442770D01*
G01X1454550Y1161250D02*
Y1148750D01*
X1460750D01*
G01X1466950Y1161250D02*
Y1148750D01*
X1473150D01*
G01X1491440Y1161250D02*
Y1152292D01*
X1492060Y1150416D01*
X1493300Y1149167D01*
X1494850Y1148750D01*
X1496400Y1149167D01*
X1497640Y1150416D01*
X1498260Y1152292D01*
Y1161250D01*
G01X1503685Y1148750D02*
Y1161250D01*
X1510815Y1148750D01*
Y1161250D01*
G01X1517790D02*
X1521510D01*
G01X1519650D02*
Y1148750D01*
G01X1517790D02*
X1521510D01*
G01X1532050Y1161250D02*
Y1148750D01*
G01X1528485Y1161250D02*
X1535615D01*
G01X1541195Y1150416D02*
X1542435Y1149375D01*
X1543830Y1148750D01*
X1545070D01*
X1546310Y1149375D01*
X1547240Y1150416D01*
X1547705Y1151875D01*
X1547395Y1153333D01*
X1546620Y1154583D01*
X1545225Y1155417D01*
X1543365Y1155833D01*
X1542280Y1156667D01*
X1541815Y1158125D01*
X1542125Y1159583D01*
X1542900Y1160625D01*
X1543985Y1161250D01*
X1545070D01*
X1546155Y1160833D01*
X1547085Y1159792D01*
G01X1565375Y1148750D02*
X1569250Y1161250D01*
X1573125Y1148750D01*
G01X1571730Y1153125D02*
X1566770D01*
G01X1578550Y1148750D02*
Y1161250D01*
X1582425D01*
X1583665Y1160625D01*
X1584440Y1159792D01*
X1584750Y1158125D01*
X1584440Y1156458D01*
X1583510Y1155417D01*
X1582425Y1154792D01*
X1578550D01*
G01X1582425D02*
X1584750Y1148750D01*
G01X1597150D02*
X1590950D01*
Y1161250D01*
X1597150D01*
G01X1594670Y1155208D02*
X1590950D01*
G01X1616990Y1161250D02*
X1620710D01*
G01X1618850D02*
Y1148750D01*
G01X1616990D02*
X1620710D01*
G01X1627685D02*
Y1161250D01*
X1634815Y1148750D01*
Y1161250D01*
G01X1652020Y1148750D02*
Y1161250D01*
X1656050Y1150833D01*
X1660080Y1161250D01*
Y1148750D01*
G01X1666590Y1161250D02*
X1670310D01*
G01X1668450D02*
Y1148750D01*
G01X1666590D02*
X1670310D01*
G01X1677750Y1161250D02*
Y1148750D01*
X1683950D01*
G01X1689995Y1150416D02*
X1691235Y1149375D01*
X1692630Y1148750D01*
X1693870D01*
X1695110Y1149375D01*
X1696040Y1150416D01*
X1696505Y1151875D01*
X1696195Y1153333D01*
X1695420Y1154583D01*
X1694025Y1155417D01*
X1692165Y1155833D01*
X1691080Y1156667D01*
X1690615Y1158125D01*
X1690925Y1159583D01*
X1691700Y1160625D01*
X1692785Y1161250D01*
X1693870D01*
X1694955Y1160833D01*
X1695885Y1159792D01*
G01X1421500Y1406000D02*
X1420000Y1411000D01*
X1423000D01*
X1421500Y1406000D01*
G01Y1426000D02*
X1420000Y1421000D01*
X1423000D01*
X1421500Y1426000D01*
G01Y1446000D02*
Y1406000D01*
G01X1425790Y1537000D02*
Y1543300D01*
X1422892Y1538785D01*
X1426808D01*
G01X1429427Y1537945D02*
X1429897Y1537420D01*
X1430445Y1537105D01*
X1431150Y1537000D01*
X1431855Y1537210D01*
X1432403Y1537630D01*
X1432795Y1538365D01*
X1432873Y1539205D01*
X1432717Y1540045D01*
X1432325Y1540570D01*
X1431777Y1540990D01*
X1431228Y1541095D01*
X1430680Y1540990D01*
X1429975Y1540570D01*
X1430210Y1543300D01*
X1432325D01*
G01X1448327Y1537945D02*
X1448797Y1537420D01*
X1449345Y1537105D01*
X1450050Y1537000D01*
X1450755Y1537210D01*
X1451303Y1537630D01*
X1451695Y1538365D01*
X1451773Y1539205D01*
X1451617Y1540045D01*
X1451225Y1540570D01*
X1450677Y1540990D01*
X1450128Y1541095D01*
X1449580Y1540990D01*
X1448875Y1540570D01*
X1449110Y1543300D01*
X1451225D01*
G01X1440000Y1537000D02*
X1445000D01*
G01X1440000Y1541000D02*
X1445000D01*
G01X1435618Y1545000D02*
G03I-1118J0D01*
G01X1448000Y1457000D02*
Y1452000D01*
G01X1445500Y1450500D02*
X1450500D01*
G01X1445500Y1454500D02*
X1450500D01*
G01X1442500Y1543500D02*
Y1538500D01*
G01X1454618Y1545000D02*
G03I-1118J0D01*
G01X1525850Y1136250D02*
Y1123750D01*
G01X1522285Y1136250D02*
X1529415D01*
G01X1538250Y1123750D02*
X1537010Y1123958D01*
X1535925Y1124791D01*
X1534995Y1126042D01*
X1534375Y1127500D01*
X1534065Y1129167D01*
Y1130833D01*
X1534375Y1132500D01*
X1534995Y1133958D01*
X1535925Y1135208D01*
X1537010Y1136042D01*
X1538250Y1136250D01*
X1539490Y1136042D01*
X1540575Y1135208D01*
X1541505Y1133958D01*
X1542125Y1132500D01*
X1542435Y1130833D01*
Y1129167D01*
X1542125Y1127500D01*
X1541505Y1126042D01*
X1540575Y1124791D01*
X1539490Y1123958D01*
X1538250Y1123750D01*
G01X1547550Y1136250D02*
Y1123750D01*
X1553750D01*
G01X1566150D02*
X1559950D01*
Y1136250D01*
X1566150D01*
G01X1563670Y1130208D02*
X1559950D01*
G01X1572350Y1123750D02*
Y1136250D01*
X1576225D01*
X1577465Y1135625D01*
X1578240Y1134792D01*
X1578550Y1133125D01*
X1578240Y1131458D01*
X1577310Y1130417D01*
X1576225Y1129792D01*
X1572350D01*
G01X1576225D02*
X1578550Y1123750D01*
G01X1583975D02*
X1587850Y1136250D01*
X1591725Y1123750D01*
G01X1590330Y1128125D02*
X1585370D01*
G01X1596685Y1123750D02*
Y1136250D01*
X1603815Y1123750D01*
Y1136250D01*
G01X1616060Y1135208D02*
X1615130Y1135833D01*
X1614045Y1136250D01*
X1612805D01*
X1611410Y1135625D01*
X1610325Y1134583D01*
X1609550Y1133333D01*
X1608930Y1131250D01*
X1608775Y1129375D01*
X1609085Y1127500D01*
X1609550Y1126250D01*
X1610480Y1125000D01*
X1611565Y1124167D01*
X1612650Y1123750D01*
X1613735D01*
X1614820Y1124167D01*
X1615750Y1124791D01*
X1616525Y1125625D01*
G01X1628150Y1123750D02*
X1621950D01*
Y1136250D01*
X1628150D01*
G01X1625670Y1130208D02*
X1621950D01*
G01X1632800Y1119583D02*
X1642100D01*
G01X1646440Y1123750D02*
Y1136250D01*
X1649540D01*
X1650780Y1135625D01*
X1651710Y1134792D01*
X1652485Y1133542D01*
X1653105Y1132083D01*
X1653260Y1130000D01*
X1653105Y1127917D01*
X1652485Y1126458D01*
X1651710Y1125208D01*
X1650780Y1124375D01*
X1649540Y1123750D01*
X1646440D01*
G01X1659150D02*
Y1136250D01*
X1663025D01*
X1664265Y1135625D01*
X1665040Y1134792D01*
X1665350Y1133125D01*
X1665040Y1131458D01*
X1664110Y1130417D01*
X1663025Y1129792D01*
X1659150D01*
G01X1663025D02*
X1665350Y1123750D01*
G01X1672790Y1136250D02*
X1676510D01*
G01X1674650D02*
Y1123750D01*
G01X1672790D02*
X1676510D01*
G01X1683950Y1136250D02*
Y1123750D01*
X1690150D01*
G01X1696350Y1136250D02*
Y1123750D01*
X1702550D01*
G01X1555145Y1058717D02*
X1558865D01*
G01X1556850Y1061425D02*
Y1056008D01*
G01X1569250Y1067050D02*
X1568010Y1066633D01*
X1567080Y1065592D01*
X1566460Y1064342D01*
X1565995Y1062675D01*
X1565840Y1060800D01*
X1565995Y1058925D01*
X1566460Y1057258D01*
X1567080Y1056008D01*
X1568010Y1054967D01*
X1569250Y1054550D01*
X1570490Y1054967D01*
X1571420Y1056008D01*
X1572040Y1057258D01*
X1572505Y1058925D01*
X1572660Y1060800D01*
X1572505Y1062675D01*
X1572040Y1064342D01*
X1571420Y1065592D01*
X1570490Y1066633D01*
X1569250Y1067050D01*
G01X1581650Y1054133D02*
X1581340Y1054342D01*
Y1054758D01*
X1581650Y1054967D01*
X1581960Y1054758D01*
Y1054342D01*
X1581650Y1054133D01*
G01X1594050Y1067050D02*
X1592810Y1066633D01*
X1591880Y1065592D01*
X1591260Y1064342D01*
X1590795Y1062675D01*
X1590640Y1060800D01*
X1590795Y1058925D01*
X1591260Y1057258D01*
X1591880Y1056008D01*
X1592810Y1054967D01*
X1594050Y1054550D01*
X1595290Y1054967D01*
X1596220Y1056008D01*
X1596840Y1057258D01*
X1597305Y1058925D01*
X1597460Y1060800D01*
X1597305Y1062675D01*
X1596840Y1064342D01*
X1596220Y1065592D01*
X1595290Y1066633D01*
X1594050Y1067050D01*
G01X1603660Y1054133D02*
X1609240Y1067050D01*
G01X1616835Y1058717D02*
X1620865D01*
G01X1631250Y1054550D02*
Y1067050D01*
X1629390Y1064550D01*
G01Y1054550D02*
X1633110D01*
G01X1643650Y1067050D02*
X1642410Y1066633D01*
X1641480Y1065592D01*
X1640860Y1064342D01*
X1640395Y1062675D01*
X1640240Y1060800D01*
X1640395Y1058925D01*
X1640860Y1057258D01*
X1641480Y1056008D01*
X1642410Y1054967D01*
X1643650Y1054550D01*
X1644890Y1054967D01*
X1645820Y1056008D01*
X1646440Y1057258D01*
X1646905Y1058925D01*
X1647060Y1060800D01*
X1646905Y1062675D01*
X1646440Y1064342D01*
X1645820Y1065592D01*
X1644890Y1066633D01*
X1643650Y1067050D01*
G01X1656050Y1054133D02*
X1655740Y1054342D01*
Y1054758D01*
X1656050Y1054967D01*
X1656360Y1054758D01*
Y1054342D01*
X1656050Y1054133D01*
G01X1668450Y1067050D02*
X1667210Y1066633D01*
X1666280Y1065592D01*
X1665660Y1064342D01*
X1665195Y1062675D01*
X1665040Y1060800D01*
X1665195Y1058925D01*
X1665660Y1057258D01*
X1666280Y1056008D01*
X1667210Y1054967D01*
X1668450Y1054550D01*
X1669690Y1054967D01*
X1670620Y1056008D01*
X1671240Y1057258D01*
X1671705Y1058925D01*
X1671860Y1060800D01*
X1671705Y1062675D01*
X1671240Y1064342D01*
X1670620Y1065592D01*
X1669690Y1066633D01*
X1668450Y1067050D01*
G01X1555145Y1096517D02*
X1558865D01*
G01X1556850Y1099225D02*
Y1093808D01*
G01X1569250Y1104850D02*
X1568010Y1104433D01*
X1567080Y1103392D01*
X1566460Y1102142D01*
X1565995Y1100475D01*
X1565840Y1098600D01*
X1565995Y1096725D01*
X1566460Y1095058D01*
X1567080Y1093808D01*
X1568010Y1092767D01*
X1569250Y1092350D01*
X1570490Y1092767D01*
X1571420Y1093808D01*
X1572040Y1095058D01*
X1572505Y1096725D01*
X1572660Y1098600D01*
X1572505Y1100475D01*
X1572040Y1102142D01*
X1571420Y1103392D01*
X1570490Y1104433D01*
X1569250Y1104850D01*
G01X1581650Y1091933D02*
X1581340Y1092142D01*
Y1092558D01*
X1581650Y1092767D01*
X1581960Y1092558D01*
Y1092142D01*
X1581650Y1091933D01*
G01X1594050Y1104850D02*
X1592810Y1104433D01*
X1591880Y1103392D01*
X1591260Y1102142D01*
X1590795Y1100475D01*
X1590640Y1098600D01*
X1590795Y1096725D01*
X1591260Y1095058D01*
X1591880Y1093808D01*
X1592810Y1092767D01*
X1594050Y1092350D01*
X1595290Y1092767D01*
X1596220Y1093808D01*
X1596840Y1095058D01*
X1597305Y1096725D01*
X1597460Y1098600D01*
X1597305Y1100475D01*
X1596840Y1102142D01*
X1596220Y1103392D01*
X1595290Y1104433D01*
X1594050Y1104850D01*
G01X1603660Y1091933D02*
X1609240Y1104850D01*
G01X1616835Y1096517D02*
X1620865D01*
G01X1631250Y1092350D02*
Y1104850D01*
X1629390Y1102350D01*
G01Y1092350D02*
X1633110D01*
G01X1643650Y1104850D02*
X1642410Y1104433D01*
X1641480Y1103392D01*
X1640860Y1102142D01*
X1640395Y1100475D01*
X1640240Y1098600D01*
X1640395Y1096725D01*
X1640860Y1095058D01*
X1641480Y1093808D01*
X1642410Y1092767D01*
X1643650Y1092350D01*
X1644890Y1092767D01*
X1645820Y1093808D01*
X1646440Y1095058D01*
X1646905Y1096725D01*
X1647060Y1098600D01*
X1646905Y1100475D01*
X1646440Y1102142D01*
X1645820Y1103392D01*
X1644890Y1104433D01*
X1643650Y1104850D01*
G01X1656050Y1091933D02*
X1655740Y1092142D01*
Y1092558D01*
X1656050Y1092767D01*
X1656360Y1092558D01*
Y1092142D01*
X1656050Y1091933D01*
G01X1668450Y1104850D02*
X1667210Y1104433D01*
X1666280Y1103392D01*
X1665660Y1102142D01*
X1665195Y1100475D01*
X1665040Y1098600D01*
X1665195Y1096725D01*
X1665660Y1095058D01*
X1666280Y1093808D01*
X1667210Y1092767D01*
X1668450Y1092350D01*
X1669690Y1092767D01*
X1670620Y1093808D01*
X1671240Y1095058D01*
X1671705Y1096725D01*
X1671860Y1098600D01*
X1671705Y1100475D01*
X1671240Y1102142D01*
X1670620Y1103392D01*
X1669690Y1104433D01*
X1668450Y1104850D01*
G01X1561345Y831917D02*
X1565065D01*
G01X1563050Y834625D02*
Y829208D01*
G01X1572505Y838167D02*
X1573435Y839416D01*
X1574520Y840042D01*
X1575760Y840250D01*
X1577310Y839833D01*
X1578395Y838792D01*
X1578705Y837542D01*
X1578550Y836291D01*
X1577930Y835250D01*
X1574830Y833167D01*
X1573435Y831708D01*
X1572505Y829625D01*
X1572195Y827750D01*
X1578705D01*
G01X1587850Y827333D02*
X1587540Y827542D01*
Y827958D01*
X1587850Y828167D01*
X1588160Y827958D01*
Y827542D01*
X1587850Y827333D01*
G01X1600250Y840250D02*
X1599010Y839833D01*
X1598080Y838792D01*
X1597460Y837542D01*
X1596995Y835875D01*
X1596840Y834000D01*
X1596995Y832125D01*
X1597460Y830458D01*
X1598080Y829208D01*
X1599010Y828167D01*
X1600250Y827750D01*
X1601490Y828167D01*
X1602420Y829208D01*
X1603040Y830458D01*
X1603505Y832125D01*
X1603660Y834000D01*
X1603505Y835875D01*
X1603040Y837542D01*
X1602420Y838792D01*
X1601490Y839833D01*
X1600250Y840250D01*
G01X1609860Y827333D02*
X1615440Y840250D01*
G01X1623035Y831917D02*
X1627065D01*
G01X1637450Y840250D02*
X1636210Y839833D01*
X1635280Y838792D01*
X1634660Y837542D01*
X1634195Y835875D01*
X1634040Y834000D01*
X1634195Y832125D01*
X1634660Y830458D01*
X1635280Y829208D01*
X1636210Y828167D01*
X1637450Y827750D01*
X1638690Y828167D01*
X1639620Y829208D01*
X1640240Y830458D01*
X1640705Y832125D01*
X1640860Y834000D01*
X1640705Y835875D01*
X1640240Y837542D01*
X1639620Y838792D01*
X1638690Y839833D01*
X1637450Y840250D01*
G01X1649850Y827333D02*
X1649540Y827542D01*
Y827958D01*
X1649850Y828167D01*
X1650160Y827958D01*
Y827542D01*
X1649850Y827333D01*
G01X1662250Y840250D02*
X1661010Y839833D01*
X1660080Y838792D01*
X1659460Y837542D01*
X1658995Y835875D01*
X1658840Y834000D01*
X1658995Y832125D01*
X1659460Y830458D01*
X1660080Y829208D01*
X1661010Y828167D01*
X1662250Y827750D01*
X1663490Y828167D01*
X1664420Y829208D01*
X1665040Y830458D01*
X1665505Y832125D01*
X1665660Y834000D01*
X1665505Y835875D01*
X1665040Y837542D01*
X1664420Y838792D01*
X1663490Y839833D01*
X1662250Y840250D01*
G01X1561345Y869717D02*
X1565065D01*
G01X1563050Y872425D02*
Y867008D01*
G01X1572505Y875967D02*
X1573435Y877216D01*
X1574520Y877842D01*
X1575760Y878050D01*
X1577310Y877633D01*
X1578395Y876592D01*
X1578705Y875342D01*
X1578550Y874091D01*
X1577930Y873050D01*
X1574830Y870967D01*
X1573435Y869508D01*
X1572505Y867425D01*
X1572195Y865550D01*
X1578705D01*
G01X1587850Y865133D02*
X1587540Y865342D01*
Y865758D01*
X1587850Y865967D01*
X1588160Y865758D01*
Y865342D01*
X1587850Y865133D01*
G01X1600250Y878050D02*
X1599010Y877633D01*
X1598080Y876592D01*
X1597460Y875342D01*
X1596995Y873675D01*
X1596840Y871800D01*
X1596995Y869925D01*
X1597460Y868258D01*
X1598080Y867008D01*
X1599010Y865967D01*
X1600250Y865550D01*
X1601490Y865967D01*
X1602420Y867008D01*
X1603040Y868258D01*
X1603505Y869925D01*
X1603660Y871800D01*
X1603505Y873675D01*
X1603040Y875342D01*
X1602420Y876592D01*
X1601490Y877633D01*
X1600250Y878050D01*
G01X1609860Y865133D02*
X1615440Y878050D01*
G01X1623035Y869717D02*
X1627065D01*
G01X1634505Y875967D02*
X1635435Y877216D01*
X1636520Y877842D01*
X1637760Y878050D01*
X1639310Y877633D01*
X1640395Y876592D01*
X1640705Y875342D01*
X1640550Y874091D01*
X1639930Y873050D01*
X1636830Y870967D01*
X1635435Y869508D01*
X1634505Y867425D01*
X1634195Y865550D01*
X1640705D01*
G01X1649850Y865133D02*
X1649540Y865342D01*
Y865758D01*
X1649850Y865967D01*
X1650160Y865758D01*
Y865342D01*
X1649850Y865133D01*
G01X1662250Y878050D02*
X1661010Y877633D01*
X1660080Y876592D01*
X1659460Y875342D01*
X1658995Y873675D01*
X1658840Y871800D01*
X1658995Y869925D01*
X1659460Y868258D01*
X1660080Y867008D01*
X1661010Y865967D01*
X1662250Y865550D01*
X1663490Y865967D01*
X1664420Y867008D01*
X1665040Y868258D01*
X1665505Y869925D01*
X1665660Y871800D01*
X1665505Y873675D01*
X1665040Y875342D01*
X1664420Y876592D01*
X1663490Y877633D01*
X1662250Y878050D01*
G01X1561345Y907517D02*
X1565065D01*
G01X1563050Y910225D02*
Y904808D01*
G01X1577310Y903350D02*
Y915850D01*
X1571575Y906892D01*
X1579325D01*
G01X1587850Y902933D02*
X1587540Y903142D01*
Y903558D01*
X1587850Y903767D01*
X1588160Y903558D01*
Y903142D01*
X1587850Y902933D01*
G01X1600250Y915850D02*
X1599010Y915433D01*
X1598080Y914392D01*
X1597460Y913142D01*
X1596995Y911475D01*
X1596840Y909600D01*
X1596995Y907725D01*
X1597460Y906058D01*
X1598080Y904808D01*
X1599010Y903767D01*
X1600250Y903350D01*
X1601490Y903767D01*
X1602420Y904808D01*
X1603040Y906058D01*
X1603505Y907725D01*
X1603660Y909600D01*
X1603505Y911475D01*
X1603040Y913142D01*
X1602420Y914392D01*
X1601490Y915433D01*
X1600250Y915850D01*
G01X1609860Y902933D02*
X1615440Y915850D01*
G01X1623035Y907517D02*
X1627065D01*
G01X1639310Y903350D02*
Y915850D01*
X1633575Y906892D01*
X1641325D01*
G01X1649850Y902933D02*
X1649540Y903142D01*
Y903558D01*
X1649850Y903767D01*
X1650160Y903558D01*
Y903142D01*
X1649850Y902933D01*
G01X1662250Y915850D02*
X1661010Y915433D01*
X1660080Y914392D01*
X1659460Y913142D01*
X1658995Y911475D01*
X1658840Y909600D01*
X1658995Y907725D01*
X1659460Y906058D01*
X1660080Y904808D01*
X1661010Y903767D01*
X1662250Y903350D01*
X1663490Y903767D01*
X1664420Y904808D01*
X1665040Y906058D01*
X1665505Y907725D01*
X1665660Y909600D01*
X1665505Y911475D01*
X1665040Y913142D01*
X1664420Y914392D01*
X1663490Y915433D01*
X1662250Y915850D01*
G01X1561345Y945317D02*
X1565065D01*
G01X1563050Y948025D02*
Y942608D01*
G01X1572040Y943650D02*
X1572970Y942191D01*
X1574210Y941358D01*
X1575605Y941150D01*
X1576845Y941358D01*
X1578085Y942400D01*
X1578860Y943650D01*
X1579015Y944900D01*
X1578705Y946358D01*
X1577620Y947400D01*
X1576535Y947817D01*
X1575140D01*
G01X1576535D02*
X1577465Y948442D01*
X1578240Y949483D01*
X1578550Y950733D01*
X1578240Y951983D01*
X1577465Y953025D01*
X1576070Y953650D01*
X1574675Y953442D01*
X1573280Y952608D01*
G01X1587850Y940733D02*
X1587540Y940942D01*
Y941358D01*
X1587850Y941567D01*
X1588160Y941358D01*
Y940942D01*
X1587850Y940733D01*
G01X1600250Y953650D02*
X1599010Y953233D01*
X1598080Y952192D01*
X1597460Y950942D01*
X1596995Y949275D01*
X1596840Y947400D01*
X1596995Y945525D01*
X1597460Y943858D01*
X1598080Y942608D01*
X1599010Y941567D01*
X1600250Y941150D01*
X1601490Y941567D01*
X1602420Y942608D01*
X1603040Y943858D01*
X1603505Y945525D01*
X1603660Y947400D01*
X1603505Y949275D01*
X1603040Y950942D01*
X1602420Y952192D01*
X1601490Y953233D01*
X1600250Y953650D01*
G01X1609860Y940733D02*
X1615440Y953650D01*
G01X1623035Y945317D02*
X1627065D01*
G01X1634040Y943650D02*
X1634970Y942191D01*
X1636210Y941358D01*
X1637605Y941150D01*
X1638845Y941358D01*
X1640085Y942400D01*
X1640860Y943650D01*
X1641015Y944900D01*
X1640705Y946358D01*
X1639620Y947400D01*
X1638535Y947817D01*
X1637140D01*
G01X1638535D02*
X1639465Y948442D01*
X1640240Y949483D01*
X1640550Y950733D01*
X1640240Y951983D01*
X1639465Y953025D01*
X1638070Y953650D01*
X1636675Y953442D01*
X1635280Y952608D01*
G01X1649850Y940733D02*
X1649540Y940942D01*
Y941358D01*
X1649850Y941567D01*
X1650160Y941358D01*
Y940942D01*
X1649850Y940733D01*
G01X1662250Y953650D02*
X1661010Y953233D01*
X1660080Y952192D01*
X1659460Y950942D01*
X1658995Y949275D01*
X1658840Y947400D01*
X1658995Y945525D01*
X1659460Y943858D01*
X1660080Y942608D01*
X1661010Y941567D01*
X1662250Y941150D01*
X1663490Y941567D01*
X1664420Y942608D01*
X1665040Y943858D01*
X1665505Y945525D01*
X1665660Y947400D01*
X1665505Y949275D01*
X1665040Y950942D01*
X1664420Y952192D01*
X1663490Y953233D01*
X1662250Y953650D01*
G01X1561345Y983117D02*
X1565065D01*
G01X1563050Y985825D02*
Y980408D01*
G01X1572040Y981450D02*
X1572970Y979991D01*
X1574210Y979158D01*
X1575605Y978950D01*
X1576845Y979158D01*
X1578085Y980200D01*
X1578860Y981450D01*
X1579015Y982700D01*
X1578705Y984158D01*
X1577620Y985200D01*
X1576535Y985617D01*
X1575140D01*
G01X1576535D02*
X1577465Y986242D01*
X1578240Y987283D01*
X1578550Y988533D01*
X1578240Y989783D01*
X1577465Y990825D01*
X1576070Y991450D01*
X1574675Y991242D01*
X1573280Y990408D01*
G01X1587850Y978533D02*
X1587540Y978742D01*
Y979158D01*
X1587850Y979367D01*
X1588160Y979158D01*
Y978742D01*
X1587850Y978533D01*
G01X1600250Y991450D02*
X1599010Y991033D01*
X1598080Y989992D01*
X1597460Y988742D01*
X1596995Y987075D01*
X1596840Y985200D01*
X1596995Y983325D01*
X1597460Y981658D01*
X1598080Y980408D01*
X1599010Y979367D01*
X1600250Y978950D01*
X1601490Y979367D01*
X1602420Y980408D01*
X1603040Y981658D01*
X1603505Y983325D01*
X1603660Y985200D01*
X1603505Y987075D01*
X1603040Y988742D01*
X1602420Y989992D01*
X1601490Y991033D01*
X1600250Y991450D01*
G01X1609860Y978533D02*
X1615440Y991450D01*
G01X1623035Y983117D02*
X1627065D01*
G01X1634040Y981450D02*
X1634970Y979991D01*
X1636210Y979158D01*
X1637605Y978950D01*
X1638845Y979158D01*
X1640085Y980200D01*
X1640860Y981450D01*
X1641015Y982700D01*
X1640705Y984158D01*
X1639620Y985200D01*
X1638535Y985617D01*
X1637140D01*
G01X1638535D02*
X1639465Y986242D01*
X1640240Y987283D01*
X1640550Y988533D01*
X1640240Y989783D01*
X1639465Y990825D01*
X1638070Y991450D01*
X1636675Y991242D01*
X1635280Y990408D01*
G01X1649850Y978533D02*
X1649540Y978742D01*
Y979158D01*
X1649850Y979367D01*
X1650160Y979158D01*
Y978742D01*
X1649850Y978533D01*
G01X1662250Y991450D02*
X1661010Y991033D01*
X1660080Y989992D01*
X1659460Y988742D01*
X1658995Y987075D01*
X1658840Y985200D01*
X1658995Y983325D01*
X1659460Y981658D01*
X1660080Y980408D01*
X1661010Y979367D01*
X1662250Y978950D01*
X1663490Y979367D01*
X1664420Y980408D01*
X1665040Y981658D01*
X1665505Y983325D01*
X1665660Y985200D01*
X1665505Y987075D01*
X1665040Y988742D01*
X1664420Y989992D01*
X1663490Y991033D01*
X1662250Y991450D01*
G01X1561345Y1020917D02*
X1565065D01*
G01X1563050Y1023625D02*
Y1018208D01*
G01X1572505Y1027167D02*
X1573435Y1028416D01*
X1574520Y1029042D01*
X1575760Y1029250D01*
X1577310Y1028833D01*
X1578395Y1027792D01*
X1578705Y1026542D01*
X1578550Y1025291D01*
X1577930Y1024250D01*
X1574830Y1022167D01*
X1573435Y1020708D01*
X1572505Y1018625D01*
X1572195Y1016750D01*
X1578705D01*
G01X1587850Y1016333D02*
X1587540Y1016542D01*
Y1016958D01*
X1587850Y1017167D01*
X1588160Y1016958D01*
Y1016542D01*
X1587850Y1016333D01*
G01X1600250Y1029250D02*
X1599010Y1028833D01*
X1598080Y1027792D01*
X1597460Y1026542D01*
X1596995Y1024875D01*
X1596840Y1023000D01*
X1596995Y1021125D01*
X1597460Y1019458D01*
X1598080Y1018208D01*
X1599010Y1017167D01*
X1600250Y1016750D01*
X1601490Y1017167D01*
X1602420Y1018208D01*
X1603040Y1019458D01*
X1603505Y1021125D01*
X1603660Y1023000D01*
X1603505Y1024875D01*
X1603040Y1026542D01*
X1602420Y1027792D01*
X1601490Y1028833D01*
X1600250Y1029250D01*
G01X1609860Y1016333D02*
X1615440Y1029250D01*
G01X1623035Y1020917D02*
X1627065D01*
G01X1634505Y1027167D02*
X1635435Y1028416D01*
X1636520Y1029042D01*
X1637760Y1029250D01*
X1639310Y1028833D01*
X1640395Y1027792D01*
X1640705Y1026542D01*
X1640550Y1025291D01*
X1639930Y1024250D01*
X1636830Y1022167D01*
X1635435Y1020708D01*
X1634505Y1018625D01*
X1634195Y1016750D01*
X1640705D01*
G01X1649850Y1016333D02*
X1649540Y1016542D01*
Y1016958D01*
X1649850Y1017167D01*
X1650160Y1016958D01*
Y1016542D01*
X1649850Y1016333D01*
G01X1662250Y1029250D02*
X1661010Y1028833D01*
X1660080Y1027792D01*
X1659460Y1026542D01*
X1658995Y1024875D01*
X1658840Y1023000D01*
X1658995Y1021125D01*
X1659460Y1019458D01*
X1660080Y1018208D01*
X1661010Y1017167D01*
X1662250Y1016750D01*
X1663490Y1017167D01*
X1664420Y1018208D01*
X1665040Y1019458D01*
X1665505Y1021125D01*
X1665660Y1023000D01*
X1665505Y1024875D01*
X1665040Y1026542D01*
X1664420Y1027792D01*
X1663490Y1028833D01*
X1662250Y1029250D01*
G01X1717585Y827750D02*
Y840250D01*
X1724715Y827750D01*
Y840250D01*
G01X1733550Y827750D02*
X1732310Y827958D01*
X1731225Y828791D01*
X1730295Y830042D01*
X1729675Y831500D01*
X1729365Y833167D01*
Y834833D01*
X1729675Y836500D01*
X1730295Y837958D01*
X1731225Y839208D01*
X1732310Y840042D01*
X1733550Y840250D01*
X1734790Y840042D01*
X1735875Y839208D01*
X1736805Y837958D01*
X1737425Y836500D01*
X1737735Y834833D01*
Y833167D01*
X1737425Y831500D01*
X1736805Y830042D01*
X1735875Y828791D01*
X1734790Y827958D01*
X1733550Y827750D01*
G01X1742385D02*
Y840250D01*
X1749515Y827750D01*
Y840250D01*
G01X1756335Y831917D02*
X1760365D01*
G01X1767650Y827750D02*
Y840250D01*
X1771370D01*
X1772610Y839625D01*
X1773540Y838167D01*
X1773850Y836500D01*
X1773540Y834833D01*
X1772765Y833583D01*
X1771370Y832958D01*
X1767650D01*
G01X1780050Y840250D02*
Y827750D01*
X1786250D01*
G01X1791675D02*
X1795550Y840250D01*
X1799425Y827750D01*
G01X1798030Y832125D02*
X1793070D01*
G01X1807950Y840250D02*
Y827750D01*
G01X1804385Y840250D02*
X1811515D01*
G01X1823450Y827750D02*
X1817250D01*
Y840250D01*
X1823450D01*
G01X1820970Y834208D02*
X1817250D01*
G01X1829340Y827750D02*
Y840250D01*
X1832440D01*
X1833680Y839625D01*
X1834610Y838792D01*
X1835385Y837542D01*
X1836005Y836083D01*
X1836160Y834000D01*
X1836005Y831917D01*
X1835385Y830458D01*
X1834610Y829208D01*
X1833680Y828375D01*
X1832440Y827750D01*
X1829340D01*
G01X1717585Y865550D02*
Y878050D01*
X1724715Y865550D01*
Y878050D01*
G01X1733550Y865550D02*
X1732310Y865758D01*
X1731225Y866591D01*
X1730295Y867842D01*
X1729675Y869300D01*
X1729365Y870967D01*
Y872633D01*
X1729675Y874300D01*
X1730295Y875758D01*
X1731225Y877008D01*
X1732310Y877842D01*
X1733550Y878050D01*
X1734790Y877842D01*
X1735875Y877008D01*
X1736805Y875758D01*
X1737425Y874300D01*
X1737735Y872633D01*
Y870967D01*
X1737425Y869300D01*
X1736805Y867842D01*
X1735875Y866591D01*
X1734790Y865758D01*
X1733550Y865550D01*
G01X1742385D02*
Y878050D01*
X1749515Y865550D01*
Y878050D01*
G01X1756335Y869717D02*
X1760365D01*
G01X1767650Y865550D02*
Y878050D01*
X1771370D01*
X1772610Y877425D01*
X1773540Y875967D01*
X1773850Y874300D01*
X1773540Y872633D01*
X1772765Y871383D01*
X1771370Y870758D01*
X1767650D01*
G01X1780050Y878050D02*
Y865550D01*
X1786250D01*
G01X1791675D02*
X1795550Y878050D01*
X1799425Y865550D01*
G01X1798030Y869925D02*
X1793070D01*
G01X1807950Y878050D02*
Y865550D01*
G01X1804385Y878050D02*
X1811515D01*
G01X1823450Y865550D02*
X1817250D01*
Y878050D01*
X1823450D01*
G01X1820970Y872008D02*
X1817250D01*
G01X1829340Y865550D02*
Y878050D01*
X1832440D01*
X1833680Y877425D01*
X1834610Y876592D01*
X1835385Y875342D01*
X1836005Y873883D01*
X1836160Y871800D01*
X1836005Y869717D01*
X1835385Y868258D01*
X1834610Y867008D01*
X1833680Y866175D01*
X1832440Y865550D01*
X1829340D01*
G01X1742850Y903350D02*
Y915850D01*
X1746570D01*
X1747810Y915225D01*
X1748740Y913767D01*
X1749050Y912100D01*
X1748740Y910433D01*
X1747965Y909183D01*
X1746570Y908558D01*
X1742850D01*
G01X1755250Y915850D02*
Y903350D01*
X1761450D01*
G01X1766875D02*
X1770750Y915850D01*
X1774625Y903350D01*
G01X1773230Y907725D02*
X1768270D01*
G01X1783150Y915850D02*
Y903350D01*
G01X1779585Y915850D02*
X1786715D01*
G01X1798650Y903350D02*
X1792450D01*
Y915850D01*
X1798650D01*
G01X1796170Y909808D02*
X1792450D01*
G01X1804540Y903350D02*
Y915850D01*
X1807640D01*
X1808880Y915225D01*
X1809810Y914392D01*
X1810585Y913142D01*
X1811205Y911683D01*
X1811360Y909600D01*
X1811205Y907517D01*
X1810585Y906058D01*
X1809810Y904808D01*
X1808880Y903975D01*
X1807640Y903350D01*
X1804540D01*
G01X1742850Y941150D02*
Y953650D01*
X1746570D01*
X1747810Y953025D01*
X1748740Y951567D01*
X1749050Y949900D01*
X1748740Y948233D01*
X1747965Y946983D01*
X1746570Y946358D01*
X1742850D01*
G01X1755250Y953650D02*
Y941150D01*
X1761450D01*
G01X1766875D02*
X1770750Y953650D01*
X1774625Y941150D01*
G01X1773230Y945525D02*
X1768270D01*
G01X1783150Y953650D02*
Y941150D01*
G01X1779585Y953650D02*
X1786715D01*
G01X1798650Y941150D02*
X1792450D01*
Y953650D01*
X1798650D01*
G01X1796170Y947608D02*
X1792450D01*
G01X1804540Y941150D02*
Y953650D01*
X1807640D01*
X1808880Y953025D01*
X1809810Y952192D01*
X1810585Y950942D01*
X1811205Y949483D01*
X1811360Y947400D01*
X1811205Y945317D01*
X1810585Y943858D01*
X1809810Y942608D01*
X1808880Y941775D01*
X1807640Y941150D01*
X1804540D01*
G01X1742850Y978950D02*
Y991450D01*
X1746570D01*
X1747810Y990825D01*
X1748740Y989367D01*
X1749050Y987700D01*
X1748740Y986033D01*
X1747965Y984783D01*
X1746570Y984158D01*
X1742850D01*
G01X1755250Y991450D02*
Y978950D01*
X1761450D01*
G01X1766875D02*
X1770750Y991450D01*
X1774625Y978950D01*
G01X1773230Y983325D02*
X1768270D01*
G01X1783150Y991450D02*
Y978950D01*
G01X1779585Y991450D02*
X1786715D01*
G01X1798650Y978950D02*
X1792450D01*
Y991450D01*
X1798650D01*
G01X1796170Y985408D02*
X1792450D01*
G01X1804540Y978950D02*
Y991450D01*
X1807640D01*
X1808880Y990825D01*
X1809810Y989992D01*
X1810585Y988742D01*
X1811205Y987283D01*
X1811360Y985200D01*
X1811205Y983117D01*
X1810585Y981658D01*
X1809810Y980408D01*
X1808880Y979575D01*
X1807640Y978950D01*
X1804540D01*
G01X1742850Y1016750D02*
Y1029250D01*
X1746570D01*
X1747810Y1028625D01*
X1748740Y1027167D01*
X1749050Y1025500D01*
X1748740Y1023833D01*
X1747965Y1022583D01*
X1746570Y1021958D01*
X1742850D01*
G01X1755250Y1029250D02*
Y1016750D01*
X1761450D01*
G01X1766875D02*
X1770750Y1029250D01*
X1774625Y1016750D01*
G01X1773230Y1021125D02*
X1768270D01*
G01X1783150Y1029250D02*
Y1016750D01*
G01X1779585Y1029250D02*
X1786715D01*
G01X1798650Y1016750D02*
X1792450D01*
Y1029250D01*
X1798650D01*
G01X1796170Y1023208D02*
X1792450D01*
G01X1804540Y1016750D02*
Y1029250D01*
X1807640D01*
X1808880Y1028625D01*
X1809810Y1027792D01*
X1810585Y1026542D01*
X1811205Y1025083D01*
X1811360Y1023000D01*
X1811205Y1020917D01*
X1810585Y1019458D01*
X1809810Y1018208D01*
X1808880Y1017375D01*
X1807640Y1016750D01*
X1804540D01*
G01X1742850Y1054550D02*
Y1067050D01*
X1746570D01*
X1747810Y1066425D01*
X1748740Y1064967D01*
X1749050Y1063300D01*
X1748740Y1061633D01*
X1747965Y1060383D01*
X1746570Y1059758D01*
X1742850D01*
G01X1755250Y1067050D02*
Y1054550D01*
X1761450D01*
G01X1766875D02*
X1770750Y1067050D01*
X1774625Y1054550D01*
G01X1773230Y1058925D02*
X1768270D01*
G01X1783150Y1067050D02*
Y1054550D01*
G01X1779585Y1067050D02*
X1786715D01*
G01X1798650Y1054550D02*
X1792450D01*
Y1067050D01*
X1798650D01*
G01X1796170Y1061008D02*
X1792450D01*
G01X1804540Y1054550D02*
Y1067050D01*
X1807640D01*
X1808880Y1066425D01*
X1809810Y1065592D01*
X1810585Y1064342D01*
X1811205Y1062883D01*
X1811360Y1060800D01*
X1811205Y1058717D01*
X1810585Y1057258D01*
X1809810Y1056008D01*
X1808880Y1055175D01*
X1807640Y1054550D01*
X1804540D01*
G01X1742850Y1092350D02*
Y1104850D01*
X1746570D01*
X1747810Y1104225D01*
X1748740Y1102767D01*
X1749050Y1101100D01*
X1748740Y1099433D01*
X1747965Y1098183D01*
X1746570Y1097558D01*
X1742850D01*
G01X1755250Y1104850D02*
Y1092350D01*
X1761450D01*
G01X1766875D02*
X1770750Y1104850D01*
X1774625Y1092350D01*
G01X1773230Y1096725D02*
X1768270D01*
G01X1783150Y1104850D02*
Y1092350D01*
G01X1779585Y1104850D02*
X1786715D01*
G01X1798650Y1092350D02*
X1792450D01*
Y1104850D01*
X1798650D01*
G01X1796170Y1098808D02*
X1792450D01*
G01X1804540Y1092350D02*
Y1104850D01*
X1807640D01*
X1808880Y1104225D01*
X1809810Y1103392D01*
X1810585Y1102142D01*
X1811205Y1100683D01*
X1811360Y1098600D01*
X1811205Y1096517D01*
X1810585Y1095058D01*
X1809810Y1093808D01*
X1808880Y1092975D01*
X1807640Y1092350D01*
X1804540D01*
G01X1742850Y1123750D02*
Y1136250D01*
X1746570D01*
X1747810Y1135625D01*
X1748740Y1134167D01*
X1749050Y1132500D01*
X1748740Y1130833D01*
X1747965Y1129583D01*
X1746570Y1128958D01*
X1742850D01*
G01X1755250Y1136250D02*
Y1123750D01*
X1761450D01*
G01X1766875D02*
X1770750Y1136250D01*
X1774625Y1123750D01*
G01X1773230Y1128125D02*
X1768270D01*
G01X1783150Y1136250D02*
Y1123750D01*
G01X1779585Y1136250D02*
X1786715D01*
G01X1798650Y1123750D02*
X1792450D01*
Y1136250D01*
X1798650D01*
G01X1796170Y1130208D02*
X1792450D01*
G01X1804540Y1123750D02*
Y1136250D01*
X1807640D01*
X1808880Y1135625D01*
X1809810Y1134792D01*
X1810585Y1133542D01*
X1811205Y1132083D01*
X1811360Y1130000D01*
X1811205Y1127917D01*
X1810585Y1126458D01*
X1809810Y1125208D01*
X1808880Y1124375D01*
X1807640Y1123750D01*
X1804540D01*
G01X1860650Y1054550D02*
Y1067050D01*
X1858790Y1064550D01*
G01Y1054550D02*
X1862510D01*
G01X1873050D02*
Y1067050D01*
X1871190Y1064550D01*
G01Y1054550D02*
X1874910D01*
G01X1882040Y1057050D02*
X1882970Y1055591D01*
X1884210Y1054758D01*
X1885605Y1054550D01*
X1886845Y1054758D01*
X1888085Y1055800D01*
X1888860Y1057050D01*
X1889015Y1058300D01*
X1888705Y1059758D01*
X1887620Y1060800D01*
X1886535Y1061217D01*
X1885140D01*
G01X1886535D02*
X1887465Y1061842D01*
X1888240Y1062883D01*
X1888550Y1064133D01*
X1888240Y1065383D01*
X1887465Y1066425D01*
X1886070Y1067050D01*
X1884675Y1066842D01*
X1883280Y1066008D01*
G01X1895215Y1056008D02*
X1896300Y1054967D01*
X1897540Y1054550D01*
X1898780Y1054967D01*
X1899865Y1056216D01*
X1900640Y1058092D01*
X1900950Y1059967D01*
Y1062258D01*
X1900640Y1064133D01*
X1899865Y1065800D01*
X1898935Y1066633D01*
X1897850Y1067050D01*
X1896610Y1066633D01*
X1895680Y1065800D01*
X1895060Y1064550D01*
X1894750Y1062883D01*
X1895060Y1061425D01*
X1895835Y1059967D01*
X1896765Y1059133D01*
X1897850Y1058925D01*
X1899090Y1059341D01*
X1900020Y1060383D01*
X1900950Y1062258D01*
G01X1875840Y830250D02*
X1876770Y828791D01*
X1878010Y827958D01*
X1879405Y827750D01*
X1880645Y827958D01*
X1881885Y829000D01*
X1882660Y830250D01*
X1882815Y831500D01*
X1882505Y832958D01*
X1881420Y834000D01*
X1880335Y834417D01*
X1878940D01*
G01X1880335D02*
X1881265Y835042D01*
X1882040Y836083D01*
X1882350Y837333D01*
X1882040Y838583D01*
X1881265Y839625D01*
X1879870Y840250D01*
X1878475Y840042D01*
X1877080Y839208D01*
G01X1879250Y865550D02*
X1880335Y865758D01*
X1881575Y866383D01*
X1882350Y867425D01*
X1882660Y868883D01*
X1882350Y870341D01*
X1881420Y871592D01*
X1880025Y872217D01*
X1878475D01*
X1877545Y872633D01*
X1876770Y873675D01*
X1876460Y875133D01*
X1876925Y876592D01*
X1878010Y877633D01*
X1879250Y878050D01*
X1880490Y877633D01*
X1881575Y876592D01*
X1882040Y875133D01*
X1881730Y873675D01*
X1880955Y872633D01*
X1880025Y872217D01*
X1878475D01*
X1877080Y871592D01*
X1876150Y870341D01*
X1875840Y868883D01*
X1876150Y867425D01*
X1876925Y866383D01*
X1878165Y865758D01*
X1879250Y865550D01*
G01Y903350D02*
Y915850D01*
X1877390Y913350D01*
G01Y903350D02*
X1881110D01*
G01Y941150D02*
Y953650D01*
X1875375Y944692D01*
X1883125D01*
G01X1873050Y978950D02*
Y991450D01*
X1871190Y988950D01*
G01Y978950D02*
X1874910D01*
G01X1882505Y989367D02*
X1883435Y990616D01*
X1884520Y991242D01*
X1885760Y991450D01*
X1887310Y991033D01*
X1888395Y989992D01*
X1888705Y988742D01*
X1888550Y987491D01*
X1887930Y986450D01*
X1884830Y984367D01*
X1883435Y982908D01*
X1882505Y980825D01*
X1882195Y978950D01*
X1888705D01*
G01X1866850Y1016750D02*
Y1029250D01*
X1864990Y1026750D01*
G01Y1016750D02*
X1868710D01*
G01X1876305Y1027167D02*
X1877235Y1028416D01*
X1878320Y1029042D01*
X1879560Y1029250D01*
X1881110Y1028833D01*
X1882195Y1027792D01*
X1882505Y1026542D01*
X1882350Y1025291D01*
X1881730Y1024250D01*
X1878630Y1022167D01*
X1877235Y1020708D01*
X1876305Y1018625D01*
X1875995Y1016750D01*
X1882505D01*
G01X1891650D02*
X1892735Y1016958D01*
X1893975Y1017583D01*
X1894750Y1018625D01*
X1895060Y1020083D01*
X1894750Y1021541D01*
X1893820Y1022792D01*
X1892425Y1023417D01*
X1890875D01*
X1889945Y1023833D01*
X1889170Y1024875D01*
X1888860Y1026333D01*
X1889325Y1027792D01*
X1890410Y1028833D01*
X1891650Y1029250D01*
X1892890Y1028833D01*
X1893975Y1027792D01*
X1894440Y1026333D01*
X1894130Y1024875D01*
X1893355Y1023833D01*
X1892425Y1023417D01*
X1890875D01*
X1889480Y1022792D01*
X1888550Y1021541D01*
X1888240Y1020083D01*
X1888550Y1018625D01*
X1889325Y1017583D01*
X1890565Y1016958D01*
X1891650Y1016750D01*
G01X1863440Y1094850D02*
X1864370Y1093391D01*
X1865610Y1092558D01*
X1867005Y1092350D01*
X1868245Y1092558D01*
X1869485Y1093600D01*
X1870260Y1094850D01*
X1870415Y1096100D01*
X1870105Y1097558D01*
X1869020Y1098600D01*
X1867935Y1099017D01*
X1866540D01*
G01X1867935D02*
X1868865Y1099642D01*
X1869640Y1100683D01*
X1869950Y1101933D01*
X1869640Y1103183D01*
X1868865Y1104225D01*
X1867470Y1104850D01*
X1866075Y1104642D01*
X1864680Y1103808D01*
G01X1875840Y1094225D02*
X1876770Y1093183D01*
X1877855Y1092558D01*
X1879250Y1092350D01*
X1880645Y1092767D01*
X1881730Y1093600D01*
X1882505Y1095058D01*
X1882660Y1096725D01*
X1882350Y1098392D01*
X1881575Y1099433D01*
X1880490Y1100267D01*
X1879405Y1100475D01*
X1878320Y1100267D01*
X1876925Y1099433D01*
X1877390Y1104850D01*
X1881575D01*
G01X1891650D02*
X1890410Y1104433D01*
X1889480Y1103392D01*
X1888860Y1102142D01*
X1888395Y1100475D01*
X1888240Y1098600D01*
X1888395Y1096725D01*
X1888860Y1095058D01*
X1889480Y1093808D01*
X1890410Y1092767D01*
X1891650Y1092350D01*
X1892890Y1092767D01*
X1893820Y1093808D01*
X1894440Y1095058D01*
X1894905Y1096725D01*
X1895060Y1098600D01*
X1894905Y1100475D01*
X1894440Y1102142D01*
X1893820Y1103392D01*
X1892890Y1104433D01*
X1891650Y1104850D01*
G01X1866850Y1123750D02*
X1865610Y1123958D01*
X1864525Y1124791D01*
X1863595Y1126042D01*
X1862975Y1127500D01*
X1862665Y1129167D01*
Y1130833D01*
X1862975Y1132500D01*
X1863595Y1133958D01*
X1864525Y1135208D01*
X1865610Y1136042D01*
X1866850Y1136250D01*
X1868090Y1136042D01*
X1869175Y1135208D01*
X1870105Y1133958D01*
X1870725Y1132500D01*
X1871035Y1130833D01*
Y1129167D01*
X1870725Y1127500D01*
X1870105Y1126042D01*
X1869175Y1124791D01*
X1868090Y1123958D01*
X1866850Y1123750D01*
G01X1868090Y1127083D02*
X1869950Y1123750D01*
G01X1879250Y1136250D02*
Y1123750D01*
G01X1875685Y1136250D02*
X1882815D01*
G01X1891650Y1123750D02*
Y1129375D01*
X1888550Y1136250D01*
G01X1894750D02*
X1891650Y1129375D01*
G54D12*
X0Y0D03*
G54D13*
X3005Y30675D03*
X7500Y44000D03*
X3005Y50675D03*
Y70675D03*
Y90675D03*
Y110675D03*
Y130675D03*
Y150675D03*
Y170675D03*
X8908Y163243D03*
Y160243D03*
X3005Y190675D03*
Y210675D03*
Y230675D03*
Y250675D03*
Y270675D03*
Y290675D03*
Y310675D03*
Y330675D03*
Y350675D03*
Y370675D03*
Y390675D03*
Y410675D03*
Y430675D03*
Y450675D03*
Y470675D03*
Y490675D03*
Y510675D03*
Y530675D03*
Y550675D03*
Y570675D03*
Y590675D03*
Y610675D03*
Y630675D03*
Y650675D03*
Y670675D03*
Y690675D03*
Y710675D03*
Y730675D03*
X6025Y734000D03*
X6000Y727000D03*
X3005Y750675D03*
X6025Y748000D03*
Y741000D03*
X3005Y770675D03*
Y790675D03*
Y810675D03*
Y830675D03*
Y850675D03*
Y870675D03*
Y890675D03*
Y910675D03*
Y930675D03*
Y950675D03*
Y970675D03*
X9838Y994729D03*
X3005Y990675D03*
Y1010675D03*
Y1030675D03*
Y1050675D03*
Y1070675D03*
Y1090675D03*
Y1110675D03*
Y1130675D03*
Y1150675D03*
Y1170675D03*
Y1190675D03*
Y1210675D03*
Y1230675D03*
X8000Y1220000D03*
Y1222500D03*
X3005Y1250675D03*
Y1270675D03*
Y1290675D03*
Y1310675D03*
X15868Y3010D03*
X11874Y154893D03*
X13708Y173943D03*
Y170943D03*
X11208Y173943D03*
Y170943D03*
X13080Y179343D03*
Y182343D03*
Y192843D03*
Y189843D03*
X13580Y201643D03*
Y198643D03*
X14791Y210028D03*
Y207028D03*
X29191Y207428D03*
X17782Y248150D03*
X26040Y245190D03*
X29291Y235093D03*
X26791D03*
X31871D03*
X26791Y232593D03*
X29331D03*
X31871D03*
X25545Y248578D03*
X14587Y231944D03*
X17087D03*
X19667D03*
Y229444D03*
X17127D03*
X14587D03*
X12791Y261000D03*
X17953Y267500D03*
X27912Y270676D03*
X32000Y261000D03*
X10000Y267303D03*
X21185Y286228D03*
X24185D03*
X27185Y289228D03*
X21185D03*
X24185D03*
X18185D03*
X21185Y312228D03*
Y315228D03*
X18185D03*
X24185Y312228D03*
X27185Y315228D03*
X24185D03*
X14000Y335928D03*
X17000D03*
X20000D03*
X23000D03*
X26000D03*
X26500Y358728D03*
X23500D03*
X20500D03*
X17500D03*
X20500Y361728D03*
X23500D03*
X11000Y502000D03*
X18000Y491500D03*
X20500Y497500D03*
Y495000D03*
X11000Y511000D03*
X10987Y523418D03*
X29500Y520500D03*
Y512500D03*
X11000Y520000D03*
Y515500D03*
Y506500D03*
X29500Y534075D03*
X28900Y556900D03*
X32258Y646000D03*
X21000Y644000D03*
X32760Y657000D03*
X21525Y660000D03*
Y654000D03*
X12512Y647013D03*
X14925Y663000D03*
X21525Y666500D03*
X32760Y669500D03*
X21525Y672500D03*
X32760Y682000D03*
X13000Y709000D03*
X20453Y708047D03*
X15713Y710009D03*
X17500Y734000D03*
X26500Y732500D03*
X13425Y712500D03*
X17500Y741000D03*
Y748000D03*
X12819Y751500D03*
X12419Y765261D03*
X14830Y763614D03*
X23000Y760000D03*
X12800Y870600D03*
X15600D03*
X12864Y873315D03*
Y876315D03*
Y879315D03*
X15664D03*
Y876315D03*
Y873315D03*
X11700Y907753D03*
Y904753D03*
Y918753D03*
Y915753D03*
X32525Y904241D03*
Y907241D03*
X32825Y917841D03*
Y914841D03*
X12053Y937268D03*
Y934268D03*
X11700Y928753D03*
Y925753D03*
X32625Y925241D03*
Y928241D03*
X27587Y934815D03*
X31871Y961865D03*
X26791D03*
X29291D03*
X31871Y959365D03*
X29331D03*
X26791D03*
X14587Y958716D03*
X17087D03*
X19667D03*
Y956216D03*
X17127D03*
X14587D03*
X26990Y975034D03*
X25500Y977500D03*
X17500Y974500D03*
X28791Y976919D03*
X23702Y992261D03*
X20000Y989000D03*
X31791Y993000D03*
X26500Y997500D03*
X15275Y995500D03*
X15000Y1001300D03*
X16985Y1028800D03*
X19985D03*
Y1015800D03*
X16985D03*
X19985Y1012800D03*
X16985D03*
X22985Y1028800D03*
X25985D03*
Y1015800D03*
X22985D03*
X25985Y1012800D03*
X22985D03*
X24685Y1041800D03*
X18185Y1041900D03*
X21385D03*
X24685Y1038800D03*
X21385Y1038900D03*
X13492Y1049256D03*
Y1051756D03*
Y1046676D03*
X26000Y1062720D03*
X23000D03*
X20000D03*
X17000D03*
X14000D03*
X22000Y1104300D03*
X19000D03*
Y1107300D03*
X22000D03*
X25000D03*
X11000Y1215000D03*
X10241Y1234150D03*
X11000Y1239500D03*
X23500Y1237000D03*
X12150Y1227850D03*
X16017Y1323770D03*
X34927Y3006D03*
X54927D03*
X47399Y149664D03*
X44399D03*
Y152164D03*
X47399D03*
Y146864D03*
X44399D03*
X34380Y179643D03*
X47487Y171264D03*
X44487D03*
Y174264D03*
X34380Y182643D03*
X34544Y189540D03*
X34480Y199243D03*
X50967Y246228D03*
X53967D03*
X48477Y233457D03*
X51477D03*
X54477D03*
X39167Y230228D03*
X42167D03*
X51456Y230214D03*
X54456D03*
X39167Y244728D03*
X42167D03*
X38880Y263169D03*
X55167Y259228D03*
X52167D03*
X55167Y272228D03*
Y256328D03*
X52167D03*
X40472Y283287D03*
X55650Y280728D03*
X47561Y280228D03*
X53343Y301334D03*
X44500Y301500D03*
X50021Y313863D03*
X52561D03*
Y311363D03*
X50061D03*
X47481D03*
Y313863D03*
X37185Y316228D03*
X40185D03*
Y301728D03*
X37185D03*
X54926Y296651D03*
X53000Y345997D03*
Y348497D03*
Y350997D03*
X55700Y342500D03*
X53000Y364997D03*
Y367497D03*
Y369997D03*
X49689Y474203D03*
X49250Y516750D03*
X37500Y520500D03*
Y512500D03*
X35484Y534075D03*
X45500Y646000D03*
X45240Y669500D03*
X33500Y694425D03*
X34000Y757000D03*
X37000Y756900D03*
X38900Y800200D03*
X52800Y813500D03*
X47813Y833013D03*
X48308Y877415D03*
Y880415D03*
Y883415D03*
X50808Y877415D03*
Y880415D03*
Y883415D03*
X48631Y964607D03*
Y962107D03*
X48731Y959507D03*
Y957007D03*
X42167Y958400D03*
X39167D03*
X48731Y972307D03*
Y974807D03*
X48631Y969707D03*
Y967207D03*
X42367Y972800D03*
X39367D03*
X51164Y988115D03*
Y985115D03*
X48664D03*
Y988115D03*
X40972Y1010059D03*
X38880Y989941D03*
X48492Y1006856D03*
X51164Y994115D03*
Y991115D03*
X48664D03*
Y994115D03*
X53000Y1026000D03*
X48005Y1012038D03*
X37555Y1027168D03*
X40555D03*
X53000Y1021500D03*
X40585Y1041300D03*
X37585D03*
X50561Y1038135D03*
X53061D03*
Y1040635D03*
X50521D03*
X47981D03*
Y1038135D03*
X55700Y1079289D03*
Y1075878D03*
X55701Y1071860D03*
Y1068449D03*
X55635Y1090665D03*
Y1094076D03*
X40500Y1164000D03*
X56000Y1203273D03*
X35517Y1323770D03*
X56017D03*
X61802Y25927D03*
X78400Y40200D03*
Y36700D03*
Y33200D03*
X68508Y50969D03*
X78400Y47200D03*
Y43700D03*
X60475Y79692D03*
X61500Y97500D03*
X76000Y133500D03*
X58700Y110900D03*
X75500Y130000D03*
X76743Y116500D03*
X56967Y246228D03*
X58167Y259228D03*
X61167D03*
X58167Y272228D03*
X61167D03*
X64167D03*
X58167Y256328D03*
X61167D03*
X72500Y283771D03*
X64500Y287000D03*
X56730Y278169D03*
X66561Y273985D03*
X64765Y314512D03*
Y317012D03*
X62265Y314512D03*
X62225Y317012D03*
X59685D03*
Y314512D03*
X73300Y340600D03*
Y338100D03*
X74700Y346000D03*
Y351000D03*
Y348500D03*
X74428Y370500D03*
Y368000D03*
Y365500D03*
X78500Y410000D03*
X60475Y424728D03*
Y429228D03*
X62216Y412678D03*
X77773Y420228D03*
X58500Y454500D03*
X60773Y457228D03*
X58500Y441000D03*
X71300Y460000D03*
X57000Y483000D03*
X56925Y498000D03*
Y493000D03*
Y488000D03*
Y513500D03*
X78500Y512500D03*
Y504500D03*
X74626Y515080D03*
X56925Y533500D03*
X76500Y531476D03*
X68500Y537075D03*
X72500Y541500D03*
X75396Y544500D03*
X73747Y570715D03*
X74000Y608425D03*
X74857Y611575D03*
X56475Y641000D03*
X78457Y634010D03*
X78677Y637315D03*
X56475Y647000D03*
Y660000D03*
X66400Y655400D03*
X65552Y645503D03*
X56475Y666500D03*
Y679000D03*
Y685000D03*
X65475Y666500D03*
X65500Y671500D03*
X65475Y685000D03*
Y679000D03*
X76500Y704000D03*
Y709500D03*
X61500Y728500D03*
X70925Y732000D03*
X76475Y715000D03*
X74075Y721500D03*
Y726500D03*
X76475Y742500D03*
X70925Y749000D03*
X76500Y746500D03*
X76725Y749500D03*
X58673Y775800D03*
X68694Y764764D03*
X69000Y771500D03*
X77400Y775000D03*
X60000Y797925D03*
X71500Y805500D03*
X77000Y819000D03*
X61000Y810000D03*
X60773Y820614D03*
X71650Y821000D03*
X77000Y823500D03*
X68000Y804606D03*
X62216Y830875D03*
X77018Y836764D03*
X75500Y852500D03*
X73000Y1010500D03*
X56150Y1007500D03*
X65367Y996400D03*
X62367D03*
X56367D03*
X59367D03*
X64108Y1006500D03*
X56245Y1004000D03*
X69802Y1006198D03*
X60185Y1043784D03*
X62725D03*
X65265D03*
Y1041284D03*
X62765D03*
X60185D03*
X76526Y1075845D03*
X76464Y1079181D03*
Y1072947D03*
X76526Y1069611D03*
X75860Y1064323D03*
X75893Y1061138D03*
X61029Y1064153D03*
Y1060742D03*
X76431Y1094565D03*
X76493Y1091229D03*
X62216Y1139950D03*
X77518Y1142650D03*
X68543Y1128650D03*
X77816D03*
X69018Y1147650D03*
X77773Y1147500D03*
X77518Y1138500D03*
X76500Y1162975D03*
X60475Y1152000D03*
X61500Y1160000D03*
X61000Y1172500D03*
X71150Y1165500D03*
X79000Y1157425D03*
Y1173425D03*
X79106Y1176575D03*
X75000Y1196500D03*
X57500Y1181000D03*
X76400Y1188100D03*
X73505Y1200075D03*
X76017Y1323770D03*
X85500Y40000D03*
Y36500D03*
Y33000D03*
X82975Y53333D03*
X84400Y64200D03*
X85500Y47000D03*
Y43500D03*
X99883Y57500D03*
X79500Y86925D03*
X80500Y74000D03*
X88802Y100198D03*
X91059Y94630D03*
X79500Y104425D03*
X79463Y429962D03*
X91500Y434000D03*
X82000Y415000D03*
X84575Y487075D03*
X98925Y515000D03*
X86500Y512500D03*
Y504500D03*
X98925Y524000D03*
Y512500D03*
Y534000D03*
X82000Y531476D03*
X87500D03*
X93000D03*
X102075Y534000D03*
X84050Y555925D03*
X85000Y562148D03*
X91532Y663261D03*
X86000Y676000D03*
Y684000D03*
Y700000D03*
Y696000D03*
X93000Y731000D03*
Y745000D03*
X79975Y739975D03*
X99279Y781942D03*
X94000Y818500D03*
X101500Y824271D03*
X92950Y821707D03*
X84000Y844950D03*
X99000Y848000D03*
X80000Y828500D03*
X99000Y853000D03*
X79500Y1134000D03*
X91000Y1173425D03*
X81000Y1193425D03*
X86000Y1176575D03*
X94730Y1173910D03*
X96017Y1323770D03*
X111522Y39800D03*
X114522D03*
X122917D03*
Y37300D03*
X111522Y44800D03*
X114522D03*
X111522Y47300D03*
Y49800D03*
X114522D03*
Y52300D03*
X111522D03*
X114522Y47300D03*
X111522Y42300D03*
X114522D03*
X122917Y49800D03*
Y47300D03*
Y44800D03*
Y42300D03*
X123500Y59500D03*
X118475Y83500D03*
X112500Y76000D03*
X112000Y88700D03*
X122500Y102000D03*
X114500Y127000D03*
X103000Y136500D03*
X107000Y400425D03*
X113000Y394500D03*
X124378Y409308D03*
X117500Y398500D03*
X110500Y445000D03*
X104500Y478500D03*
X122000Y463000D03*
X124500Y485000D03*
X119000D03*
X113500D03*
X109000Y500000D03*
X105760Y493500D03*
X105815Y488500D03*
X105732Y496844D03*
X104500Y483425D03*
X113500Y523000D03*
X120000Y512500D03*
Y504500D03*
X108500Y512000D03*
X116000Y529500D03*
X108000Y539500D03*
X109000Y543500D03*
X111000Y555925D03*
X125000Y562500D03*
X106000Y634500D03*
X119500Y707500D03*
X118000Y696000D03*
X119500Y715500D03*
X115525Y731000D03*
Y745000D03*
Y738000D03*
X112294Y754294D03*
X121536Y749253D03*
X121841Y775967D03*
X115563Y759063D03*
X125227Y815000D03*
X120500Y845000D03*
X123000Y829114D03*
X119500Y992000D03*
X121072Y1077500D03*
Y1075000D03*
Y1072500D03*
Y1094500D03*
Y1092000D03*
Y1097000D03*
X110000Y1128425D03*
X121000Y1131575D03*
Y1128425D03*
X112941Y1146240D03*
X124500Y1148575D03*
X123500Y1137500D03*
X118000Y1151575D03*
X123000Y1181000D03*
X125000Y1198000D03*
X116017Y1323770D03*
X146740Y3016D03*
X141748Y26922D03*
X125917Y39800D03*
Y37300D03*
X135014Y50977D03*
X125917Y49800D03*
Y47300D03*
Y44800D03*
Y42300D03*
X142727Y79842D03*
X127000Y77500D03*
X142727Y94000D03*
X134525Y107842D03*
X132350Y94273D03*
X142000Y98842D03*
X141327Y115542D03*
X125500Y118000D03*
X127500Y129500D03*
X141890Y246451D03*
X138198Y231944D03*
X140778D03*
X143358D03*
Y229444D03*
X140818D03*
X138238D03*
X133529Y265385D03*
X147393Y265728D03*
X136500Y261000D03*
X139435Y266728D03*
X145982Y268287D03*
X136482Y272471D03*
X127482Y289228D03*
X133482D03*
X130482D03*
X136482D03*
X133482Y286228D03*
X130482D03*
X133482Y315228D03*
Y312228D03*
X130482Y315228D03*
Y312228D03*
X146482Y316228D03*
X127482Y315228D03*
X146482Y301728D03*
X130200Y339900D03*
Y337400D03*
X144600Y337100D03*
Y339828D03*
X128000Y348300D03*
X127900Y345100D03*
Y364300D03*
Y351800D03*
X127800Y370900D03*
X127900Y367900D03*
X141327Y398000D03*
X136000Y429941D03*
X129314Y414545D03*
X145327Y416500D03*
X142727Y428000D03*
X132850Y421837D03*
X125500Y469600D03*
X135500Y485024D03*
X130000Y485025D03*
X148000Y483000D03*
X134000Y501000D03*
X141500Y516500D03*
X128000Y512500D03*
Y504500D03*
X128500Y554925D03*
X135500Y562500D03*
X133491Y560490D03*
X135000Y637500D03*
X139150Y712500D03*
X136500Y742000D03*
X144827Y763510D03*
X129705Y777796D03*
X129285Y781799D03*
X128500Y791500D03*
X142727D03*
X141993Y800295D03*
X132370Y788872D03*
X128500Y786500D03*
X138428Y806903D03*
X141088Y804709D03*
X133246Y811300D03*
X142999Y842350D03*
X148281Y838882D03*
X145600Y838100D03*
X146000Y854500D03*
X138278Y961865D03*
X140778D03*
X143358D03*
Y959365D03*
X140818D03*
X138278D03*
X142000Y977500D03*
X133529Y995306D03*
X136482Y1002392D03*
X147393Y995649D03*
X139435Y989500D03*
Y996649D03*
X145982Y998208D03*
X131882Y1012900D03*
X134882D03*
X131882Y1015900D03*
X134882D03*
X125882Y1012900D03*
X128882D03*
X125882Y1015900D03*
X128882D03*
X146482Y1028500D03*
X127182Y1055000D03*
Y1042000D03*
X133382Y1055000D03*
Y1042000D03*
Y1039000D03*
X130382Y1055000D03*
Y1042000D03*
Y1039000D03*
X146482Y1043000D03*
X126760Y1071023D03*
X126793Y1067838D03*
X143072Y1073000D03*
Y1075500D03*
Y1078000D03*
X141572Y1067900D03*
Y1070400D03*
X143072Y1092500D03*
Y1095000D03*
Y1097500D03*
X127000Y1143000D03*
X141649Y1141500D03*
X135500Y1143441D03*
X142088Y1131281D03*
X127000Y1157025D03*
X132350Y1156741D03*
X142727Y1151000D03*
X127000Y1166000D03*
X126360Y1185947D03*
X142500Y1183500D03*
X125440Y1175970D03*
X142500Y1176000D03*
X135000Y1197500D03*
X136017Y1323770D03*
X165799Y3002D03*
X148576Y146649D03*
X151576D03*
Y149149D03*
X148576D03*
X154576Y146649D03*
Y149149D03*
X149664Y174443D03*
Y171443D03*
Y168443D03*
Y165443D03*
X165164Y186143D03*
X164964Y196543D03*
X164864Y205443D03*
X168564Y217543D03*
Y214543D03*
X150500Y247000D03*
X153022Y232593D03*
X150482D03*
X155562D03*
X165562Y230593D03*
X163022D03*
X150482Y235093D03*
X152982D03*
X155562D03*
X165858Y244728D03*
X162858D03*
X161105Y266081D03*
X155482Y266228D03*
X149000Y250000D03*
X149769Y283287D03*
X164947Y280728D03*
X156858Y280228D03*
X166499Y276483D03*
X169358Y286228D03*
X149500Y295500D03*
X156778Y311363D03*
Y313863D03*
X159318D03*
X161858D03*
Y311363D03*
X159358D03*
X149482Y316228D03*
Y301728D03*
X164296Y297723D03*
X162783Y301463D03*
X168982Y314512D03*
X171562D03*
X171522Y317012D03*
X168982D03*
X158858Y329228D03*
X149900Y346300D03*
Y349028D03*
Y351800D03*
Y364300D03*
Y370300D03*
Y367528D03*
X151635Y476202D03*
X154000Y471000D03*
X150575Y494500D03*
Y499500D03*
X150500Y489500D03*
X150575Y524500D03*
X170000Y504500D03*
X169000Y522000D03*
Y514000D03*
X150575Y519500D03*
Y509500D03*
X169000Y535075D03*
X150500Y544500D03*
X150575Y539500D03*
Y529500D03*
X169000Y542075D03*
X169475Y706000D03*
Y733000D03*
Y713000D03*
Y720000D03*
X163925Y756500D03*
X169475Y747000D03*
Y740000D03*
X167075Y756500D03*
X151300Y756400D03*
X149000Y854500D03*
X149500Y850500D03*
X152364Y890115D03*
Y893115D03*
Y896115D03*
X149864Y890115D03*
Y893115D03*
Y896115D03*
X162877Y910500D03*
Y913500D03*
Y931500D03*
Y934500D03*
Y921500D03*
Y924500D03*
X168177Y940100D03*
X153622Y962514D03*
X151082D03*
Y965014D03*
X153582D03*
X156162D03*
Y962514D03*
X167858Y961800D03*
X164858D03*
X168177Y943100D03*
X149658Y974968D03*
X164758Y976500D03*
X167758D03*
X151000Y981000D03*
X159000Y972500D03*
X161581Y995673D03*
X149769Y1010059D03*
X164947Y1007500D03*
X156858Y1007000D03*
X166358Y1004941D03*
X155482Y996149D03*
X169358Y1013000D03*
X161884Y1026048D03*
X170929Y1024429D03*
X149482Y1028500D03*
X162500Y1023000D03*
X149482Y1043000D03*
X156778Y1038135D03*
Y1040635D03*
X159318D03*
X161858D03*
Y1038135D03*
X159358D03*
X168982Y1043784D03*
X171522D03*
X171562Y1041284D03*
X168982D03*
X164000Y1171500D03*
X156017Y1323770D03*
X185799Y3002D03*
X193719Y157489D03*
X191219D03*
X192164Y164843D03*
X189664D03*
X192164Y167843D03*
X189664D03*
X192164Y170843D03*
X189664D03*
X192164Y173843D03*
X189664D03*
X186964Y189043D03*
Y186043D03*
Y199543D03*
Y196543D03*
X183582Y217228D03*
Y214228D03*
X186764Y208743D03*
Y205743D03*
X179358Y230328D03*
Y227328D03*
X182358Y230328D03*
Y227328D03*
X185358D03*
X185658Y243528D03*
X182658D03*
X179658D03*
X181258Y269528D03*
X184258D03*
X187258D03*
X178258D03*
X181067Y256528D03*
X184067D03*
X187067D03*
X178067D03*
X180967Y253728D03*
X177967D03*
X183967D03*
X186967D03*
X178811Y281071D03*
X175858Y273985D03*
X172905Y279728D03*
X174062Y314512D03*
Y317012D03*
X177458Y335828D03*
X180458D03*
X186458D03*
X183458D03*
X176858Y359790D03*
Y362290D03*
X185858Y359790D03*
X182858D03*
Y362290D03*
X185858D03*
X179858Y359790D03*
Y362290D03*
X189500Y512000D03*
X177000Y522000D03*
Y514000D03*
X191575Y518500D03*
Y524000D03*
X179000Y531925D03*
X189250Y541750D03*
X179000Y535075D03*
X191500Y529500D03*
X176000Y659500D03*
X175500Y651500D03*
X187050Y659500D03*
X182500Y688000D03*
X175500Y672500D03*
X187041Y730000D03*
X181475Y720000D03*
X193000Y754500D03*
X191000Y756500D03*
X181475Y740000D03*
X189000Y758500D03*
X173200Y770800D03*
X193964Y887015D03*
Y890015D03*
Y893015D03*
Y896015D03*
X180264Y895915D03*
Y892915D03*
Y889915D03*
X193964Y899015D03*
X184377Y910500D03*
Y913500D03*
X180264Y898915D03*
X183177Y940100D03*
X184377Y931500D03*
Y934500D03*
Y921500D03*
Y924500D03*
X180658Y956100D03*
X186658D03*
Y952900D03*
X180658D03*
X183758Y956200D03*
Y953000D03*
X183177Y943100D03*
X180658Y969000D03*
X186658D03*
X183758Y969100D03*
X182285Y982200D03*
X179285D03*
X188285D03*
X185285D03*
X178811Y1007843D03*
X175858Y1000757D03*
X172905Y1006500D03*
X187658Y995000D03*
Y998000D03*
X184658Y995000D03*
Y998000D03*
X181658Y995000D03*
Y998000D03*
X190158Y995000D03*
Y998000D03*
X174062Y1043784D03*
Y1041284D03*
X190358Y1062764D03*
X187358D03*
X184358D03*
X181358D03*
Y1060064D03*
X184358D03*
X187358D03*
X190358D03*
X186458Y1103662D03*
X183458D03*
X180458D03*
Y1106662D03*
X183458D03*
X192500Y1215000D03*
X182741Y1235150D03*
X183500Y1240500D03*
X176017Y1323770D03*
X194471Y1321882D03*
X199120Y9903D03*
X200536Y29059D03*
Y49059D03*
Y69059D03*
Y109059D03*
Y89059D03*
Y129059D03*
Y149059D03*
Y169059D03*
Y189059D03*
Y209059D03*
Y249059D03*
Y229059D03*
Y269059D03*
Y289059D03*
Y309059D03*
Y329059D03*
Y349059D03*
Y369059D03*
Y409059D03*
Y389059D03*
Y429059D03*
Y449059D03*
Y469059D03*
Y489059D03*
X195000Y490500D03*
X195500Y495000D03*
Y497500D03*
X200536Y509059D03*
Y549059D03*
Y529059D03*
Y569059D03*
Y589059D03*
Y609059D03*
Y629059D03*
Y649059D03*
Y669059D03*
Y709059D03*
Y689059D03*
Y729059D03*
X195000Y752500D03*
X200536Y749059D03*
Y769059D03*
Y789059D03*
Y809059D03*
Y849059D03*
Y829059D03*
Y869059D03*
Y889059D03*
Y909059D03*
Y929059D03*
Y947059D03*
Y969059D03*
Y1009059D03*
Y989059D03*
Y1029059D03*
Y1049059D03*
Y1069059D03*
Y1089059D03*
Y1109059D03*
Y1149059D03*
Y1129059D03*
Y1169059D03*
Y1189059D03*
Y1209059D03*
Y1229059D03*
X195500Y1220000D03*
Y1222500D03*
X200536Y1249059D03*
Y1289059D03*
Y1269059D03*
Y1309059D03*
X1265450Y1060800D03*
G54D14*
X9400Y241516D03*
X10500Y274500D03*
X11800Y284000D03*
X12000Y641000D03*
X34544Y192540D03*
X34480Y202243D03*
X29191Y210428D03*
X22170Y246150D03*
X14791Y247715D03*
X29390Y246960D03*
X21500Y267500D03*
X32716Y273500D03*
X24000Y276000D03*
X27185Y286228D03*
X18185D03*
Y312228D03*
X27185D03*
X17500Y361728D03*
X26500D03*
X20452Y513547D03*
X27580Y528341D03*
X30380Y648320D03*
X32720Y660000D03*
X12389Y653509D03*
X25023Y663850D03*
Y669850D03*
X32728Y679000D03*
X12500D03*
X14925Y669000D03*
Y690000D03*
X20327Y711174D03*
X13375Y730274D03*
X15012Y745563D03*
X17458Y737184D03*
X13500Y862500D03*
X27587Y937815D03*
X14791Y976000D03*
X27886Y972134D03*
X23009Y995491D03*
X30522Y1000288D03*
X18185Y1038900D03*
X25000Y1104300D03*
X19500Y1239500D03*
X47487Y174264D03*
X36880Y249217D03*
X42309Y251270D03*
X48456Y230214D03*
X41864Y265636D03*
X44500Y272767D03*
X38383Y280119D03*
X40500Y295500D03*
X52000Y298528D03*
X57430Y298520D03*
X56925Y503000D03*
Y528500D03*
Y508500D03*
Y523500D03*
Y518500D03*
X57000Y538500D03*
X47499Y649000D03*
X52977Y662650D03*
X56475Y654000D03*
X46950Y666500D03*
X45240Y657000D03*
X56475Y672500D03*
X46950D03*
X52977Y681650D03*
X45240Y682000D03*
X35259Y968798D03*
X38500Y977199D03*
X40500Y995000D03*
X39061Y1005000D03*
X51852Y1012249D03*
X42000Y1023000D03*
X44100Y1027850D03*
X50000Y1023000D03*
X68416Y63842D03*
X61000Y84192D03*
X61300Y66900D03*
X69100Y76100D03*
X75173Y78000D03*
X68500Y70000D03*
X71650Y94259D03*
Y111259D03*
X64025Y92575D03*
X65350Y102000D03*
X71500Y130000D03*
X62716Y129542D03*
X58561Y280728D03*
X71689Y302000D03*
X64561Y298446D03*
X61420Y299310D03*
X68700Y400000D03*
X78500Y406000D03*
X65900Y413000D03*
X69018Y420378D03*
X67000Y430500D03*
X71000Y427000D03*
X60773Y443728D03*
X74979Y437559D03*
X79500Y449925D03*
X65350Y447500D03*
X70500Y443500D03*
X65250Y470378D03*
X74500Y475000D03*
X68000Y463878D03*
X79293Y523513D03*
X75650Y517770D03*
X68345Y533265D03*
X73500Y562200D03*
X63070Y652400D03*
X68000Y664000D03*
X69000Y669745D03*
X68000Y676500D03*
X59475Y688975D03*
X60000Y696984D03*
X69350Y711940D03*
X68100Y721000D03*
X74075Y732000D03*
X65570Y734500D03*
X58612Y740500D03*
X66000Y776000D03*
X61576Y762200D03*
X77816Y764764D03*
X78000Y782500D03*
X68481Y800951D03*
X69018Y783764D03*
X62058Y801075D03*
X67993Y827764D03*
X65350Y818654D03*
X71410Y846500D03*
X72000Y1013500D03*
X59268Y1007793D03*
X74000Y1026000D03*
X66000Y1025000D03*
X62500Y1025500D03*
X64231Y1115268D03*
X68686Y1139993D03*
X64425Y1165500D03*
X64843Y1194000D03*
X74313Y1178559D03*
X64850Y1179000D03*
X99000Y61000D03*
X87500Y83300D03*
X86000Y92000D03*
X94430Y103830D03*
X88900Y119300D03*
X82500Y389500D03*
X84500Y404000D03*
X82500Y398000D03*
X100835Y446500D03*
X91059Y452760D03*
X91593Y439000D03*
X95000Y462740D03*
X85500Y472975D03*
X86500Y481500D03*
X96502Y501930D03*
X95184Y493787D03*
X98040Y506730D03*
X87500Y522800D03*
X96275Y519750D03*
X84723Y532202D03*
X100505Y561919D03*
X97000Y569153D03*
X90680Y561766D03*
X98780Y617000D03*
X99051Y635051D03*
X87500Y634700D03*
X88300Y639800D03*
X83300Y624100D03*
X103037Y624462D03*
X95032Y660000D03*
X86000Y680000D03*
Y688000D03*
X101284Y671500D03*
X101309Y675500D03*
X93025Y738000D03*
X99500Y787000D03*
X83000Y804000D03*
X94000Y825740D03*
X83000Y810000D03*
X82000Y833575D03*
X104500Y834500D03*
X102500Y979500D03*
X115918Y75650D03*
X123500Y115500D03*
X127482Y286228D03*
Y312228D03*
X107000Y389500D03*
X118500Y403500D03*
X107966Y408260D03*
X110000Y392500D03*
X112441Y418434D03*
X106850Y441596D03*
X125200Y453800D03*
X113500Y476000D03*
X118490Y495330D03*
X126070Y493931D03*
X112070Y499790D03*
X109000Y485000D03*
X111000Y506000D03*
X115788Y573787D03*
X106977Y561919D03*
X121500Y557500D03*
X114000Y591000D03*
X120000Y581500D03*
X108601Y627084D03*
X118079Y639954D03*
X124499Y660000D03*
X126185Y688915D03*
X123401Y669102D03*
X117500Y689900D03*
X126500Y706500D03*
X119000Y734000D03*
X125075Y715000D03*
X125352Y749277D03*
X114857Y741500D03*
X119836Y761664D03*
X107500Y782530D03*
X125654Y772281D03*
X107365Y776004D03*
X118711Y797500D03*
X125500Y820114D03*
X126000Y834500D03*
X117500Y857575D03*
X127182Y1039000D03*
X126500Y1129000D03*
X109500Y1139500D03*
X135500Y70441D03*
X142000Y74575D03*
X142500Y103342D03*
X138650Y94000D03*
X132500Y99000D03*
X135000Y120500D03*
X137449Y113340D03*
X135750Y132750D03*
X128000Y251000D03*
X137495Y248875D03*
X144482Y265728D03*
X142400Y269800D03*
X147500Y278228D03*
X136482Y286228D03*
X135245Y407228D03*
X130500Y432500D03*
X139150Y420193D03*
Y429650D03*
X135349Y468652D03*
X135000Y463000D03*
X129000Y468000D03*
X150575Y504500D03*
X144324Y498325D03*
X145193Y504232D03*
X144335Y509166D03*
X138532Y507500D03*
X150575Y534500D03*
X131500Y634500D03*
X150300Y645900D03*
X141900Y645410D03*
X134575Y659000D03*
X128000Y694500D03*
X133575Y692000D03*
X136500Y728500D03*
X128065Y725566D03*
X146000Y729000D03*
X127983Y736234D03*
X133900Y776000D03*
X132350Y793241D03*
X139650Y785905D03*
X139075Y801984D03*
X141327Y822814D03*
X134525Y815114D03*
X134800Y826614D03*
X129112Y978769D03*
X138605Y977649D03*
X146644Y1007363D03*
X147229Y1004299D03*
X144482Y995649D03*
X149500Y1023000D03*
X132175Y1117325D03*
X135800Y1138000D03*
X138650Y1149500D03*
X142500Y1161500D03*
X138650Y1165500D03*
X136800Y1194800D03*
X165164Y189143D03*
X164964Y199543D03*
X164864Y208443D03*
X152500Y249501D03*
X161200Y251200D03*
X159430Y244830D03*
X165014Y268287D03*
X152420Y296500D03*
X167000Y296310D03*
X167858Y279310D03*
X160777Y275688D03*
X160000Y298500D03*
X170358Y298858D03*
X158858Y332228D03*
X153725Y524500D03*
Y514500D03*
X167190Y529510D03*
X171977Y656850D03*
X166547Y663500D03*
X159051Y671661D03*
X167679Y674254D03*
X167642Y682217D03*
X167060Y692500D03*
X171440Y708767D03*
X156962Y692037D03*
X171586Y735683D03*
X171580Y716500D03*
X171500Y743500D03*
X172000Y751500D03*
X152823Y978573D03*
X160732Y977966D03*
X164600Y998649D03*
X167858Y1007500D03*
X164337Y1002475D03*
X159500Y1023000D03*
X153150Y1028430D03*
X165500Y1229900D03*
X185358Y230328D03*
X173858Y298500D03*
X183500Y299500D03*
X188516Y518310D03*
X191991Y536336D03*
X194000Y550000D03*
X191259Y547500D03*
X182500Y641600D03*
X187500Y643500D03*
X187050Y652000D03*
Y663500D03*
X180500Y684500D03*
X177500Y679500D03*
X175475Y668500D03*
X179000Y676500D03*
X187925Y701000D03*
X181475Y713000D03*
X193475Y706000D03*
X181000Y696500D03*
X179000Y694000D03*
X190300Y725200D03*
X192582Y733000D03*
X184425Y738000D03*
X181475Y747000D03*
X182058Y1022519D03*
X173858Y1025500D03*
X186458Y1106662D03*
X192000Y1240500D03*
X182600Y1228850D03*
X1265450Y1098600D03*
G54D15*
X30315Y41378D03*
Y404764D03*
Y768150D03*
Y1131536D03*
X173228Y111456D03*
Y474842D03*
Y838228D03*
Y1201614D03*
X1265450Y871800D03*
G54D16*
X34252Y64606D03*
Y56732D03*
Y48858D03*
X26378Y64606D03*
Y56732D03*
Y48858D03*
X34252Y88228D03*
Y80354D03*
Y72480D03*
X26378Y88228D03*
Y80354D03*
Y72480D03*
X34252Y103976D03*
Y96102D03*
X26378Y103976D03*
Y96102D03*
X34252Y412244D03*
X26378D03*
X34252Y435866D03*
Y427992D03*
Y420118D03*
X26378Y435866D03*
Y427992D03*
Y420118D03*
X34252Y451614D03*
Y443740D03*
X26378Y451614D03*
Y443740D03*
X34252Y467362D03*
Y459488D03*
X26378Y467362D03*
Y459488D03*
X34252Y775630D03*
X26378D03*
X34252Y799252D03*
Y791378D03*
Y783504D03*
X26378Y799252D03*
Y791378D03*
Y783504D03*
X34252Y822874D03*
Y815000D03*
Y807126D03*
X26378Y822874D03*
Y815000D03*
Y807126D03*
X34252Y830748D03*
X26378D03*
X34252Y1146890D03*
Y1139016D03*
X26378Y1146890D03*
Y1139016D03*
X34252Y1170512D03*
Y1162638D03*
Y1154764D03*
X26378Y1170512D03*
Y1162638D03*
Y1154764D03*
X34252Y1194134D03*
Y1186260D03*
Y1178386D03*
X26378Y1194134D03*
Y1186260D03*
Y1178386D03*
X169291Y48858D03*
Y56732D03*
Y64606D03*
Y72480D03*
Y80354D03*
Y88228D03*
Y96102D03*
Y103976D03*
Y412244D03*
Y420118D03*
Y427992D03*
Y435866D03*
Y443740D03*
Y451614D03*
Y459488D03*
Y467362D03*
Y775630D03*
Y783504D03*
Y791378D03*
Y799252D03*
Y807126D03*
Y815000D03*
Y822874D03*
Y830748D03*
Y1139016D03*
Y1146890D03*
Y1154764D03*
Y1162638D03*
Y1170512D03*
Y1178386D03*
Y1186260D03*
Y1194134D03*
X177165Y48858D03*
Y56732D03*
Y64606D03*
Y72480D03*
Y80354D03*
Y88228D03*
Y96102D03*
Y103976D03*
Y412244D03*
Y420118D03*
Y427992D03*
Y435866D03*
Y443740D03*
Y451614D03*
Y459488D03*
Y467362D03*
Y775630D03*
Y783504D03*
Y791378D03*
Y799252D03*
Y807126D03*
Y815000D03*
Y822874D03*
Y830748D03*
Y1139016D03*
Y1146890D03*
Y1154764D03*
Y1162638D03*
Y1170512D03*
Y1178386D03*
Y1186260D03*
Y1194134D03*
X1265450Y1023000D03*
G54D17*
X42717Y595122D03*
X101772Y178779D03*
Y926810D03*
X160827Y595122D03*
G54D18*
X42717Y620713D03*
X101772Y204370D03*
Y952401D03*
X160827Y620713D03*
X1265450Y947400D03*
G54D19*
X20000Y1307000D03*
X44000Y17500D03*
X178500D03*
X1265450Y834000D03*
M02*
